G04 ================== begin FILE IDENTIFICATION RECORD ==================*
G04 Layout Name:  15126-1b.brd*
G04 Film Name:    BSILK*
G04 File Format:  Gerber RS274X*
G04 File Origin:  Cadence Allegro 16.6-2015-S079*
G04 Origin Date:  Fri Feb 10 17:21:49 2017*
G04 *
G04 Layer:  REF DES/ASSEMBLY_BOTTOM*
G04 Layer:  PACKAGE GEOMETRY/SILKSCREEN_BOTTOM*
G04 Layer:  DRAWING FORMAT/LAYER_SILK_B*
G04 Layer:  BOARD GEOMETRY/SILKSCREEN_BOTTOM*
G04 Layer:  VIA CLASS/FILMMASKBOTTOM*
G04 Layer:  DRAWING FORMAT/LAYER_PCB_STORY*
G04 *
G04 Offset:    (0.00 0.00)*
G04 Mirror:    No*
G04 Mode:      Positive*
G04 Rotation:  0*
G04 FullContactRelief:  No*
G04 UndefLineWidth:     6.00*
G04 ================== end FILE IDENTIFICATION RECORD ====================*
%FSLAX35Y35*MOIN*%
%IR0*IPPOS*OFA0.00000B0.00000*MIA0B0*SFA1.00000B1.00000*%
%ADD10C,.024*%
%ADD11C,.01*%
%ADD12C,.02*%
%ADD13C,.012*%
%ADD14C,.013*%
%ADD15C,.015*%
%ADD16C,.025*%
%ADD17C,.006*%
%ADD18C,.008*%
G75*
%LPD*%
G75*
G36*
G01X44066Y155526D02*
X46066Y160526D01*
X48066Y155526D01*
X44066D01*
G37*
G36*
G01X44842Y491479D02*
Y492121D01*
X35858D01*
Y491479D01*
X44842D01*
G37*
G36*
G01X70637Y92633D02*
X74637D01*
X72637Y97633D01*
X70637Y92633D01*
G37*
G36*
G01X61052Y476894D02*
X65052D01*
X63052Y471894D01*
X61052Y476894D01*
G37*
G36*
G01X100034Y573365D02*
X104034D01*
X102034Y568365D01*
X100034Y573365D01*
G37*
G36*
G01X100752Y534914D02*
X104752D01*
X102752Y529914D01*
X100752Y534914D01*
G37*
G36*
G01X114594Y33462D02*
X118594D01*
X116594Y28462D01*
X114594Y33462D01*
G37*
G36*
G01X114626Y68905D02*
X118626D01*
X116626Y63905D01*
X114626Y68905D01*
G37*
G36*
G01X115111Y109482D02*
X119111D01*
X117111Y104482D01*
X115111Y109482D01*
G37*
G36*
G01X115057Y607447D02*
X119057D01*
X117057Y602447D01*
X115057Y607447D01*
G37*
G36*
G01X243551Y131102D02*
G03X272031I14240J-6724D01*
G01X243551D01*
G37*
G36*
G01X272031Y471654D02*
G03X243551I-14240J6724D01*
G01X272031D01*
G37*
G36*
G01X503551Y131102D02*
G03X532031I14240J-6724D01*
G01X503551D01*
G37*
G36*
G01X531931Y471654D02*
G03X503451I-14240J6724D01*
G01X531931D01*
G37*
G36*
G01X763817Y33010D02*
X767817D01*
X765817Y28010D01*
X763817Y33010D01*
G37*
G36*
G01X764172Y71069D02*
X768172D01*
X766172Y66069D01*
X764172Y71069D01*
G37*
G36*
G01X764721Y109482D02*
X768721D01*
X766721Y104482D01*
X764721Y109482D01*
G37*
G36*
G01X749674Y573335D02*
X753674D01*
X751674Y568335D01*
X749674Y573335D01*
G37*
G36*
G01X750296Y535476D02*
X754296D01*
X752296Y530476D01*
X750296Y535476D01*
G37*
G36*
G01X749852Y613090D02*
X753852D01*
X751852Y608090D01*
X749852Y613090D01*
G37*
G36*
G01X893161Y131102D02*
G03X921641I14240J-6724D01*
G01X893161D01*
G37*
G36*
G01X921641Y471654D02*
G03X893161I-14240J6724D01*
G01X921641D01*
G37*
G36*
G01X1153161Y131102D02*
G03X1181641I14240J-6724D01*
G01X1153161D01*
G37*
G36*
G01X1181641Y471654D02*
G03X1153161I-14240J6724D01*
G01X1181641D01*
G37*
G36*
G01X1376350Y332250D02*
X1372250D01*
X1376350Y336350D01*
Y332250D01*
G37*
G36*
G01X1441978Y-21750D02*
X1443978Y-26750D01*
X1439978D01*
X1441978Y-21750D01*
G37*
G36*
G01X1505100Y-9200D02*
X1503100Y-4200D01*
X1507100D01*
X1505100Y-9200D01*
G37*
G36*
G01X1535623Y53108D02*
Y45108D01*
X1526523D01*
Y53108D01*
X1535623D01*
G37*
G36*
G01X1507300Y327100D02*
X1508700Y328500D01*
Y325700D01*
X1507300Y327100D01*
G37*
G36*
G01X1551817Y61626D02*
Y53626D01*
X1542717D01*
Y61626D01*
X1551817D01*
G37*
G36*
G01X1566160Y117100D02*
X1564760Y118500D01*
X1563900Y119360D01*
X1563800Y119460D01*
Y119500D01*
X1563900D01*
X1568500D01*
Y119440D01*
X1567560Y118500D01*
X1566160Y117100D01*
G37*
G36*
G01X1536024Y222179D02*
Y184670D01*
X1561424D01*
Y222179D01*
X1536024D01*
G37*
G36*
G01X1552360Y156400D02*
X1550960Y157800D01*
X1553760D01*
X1552360Y156400D01*
G37*
G36*
G01X1584910Y297290D02*
X1576910D01*
Y306390D01*
X1584910D01*
Y297290D01*
G37*
G36*
G01X1622400Y58100D02*
X1623800Y59500D01*
Y56700D01*
X1622400Y58100D01*
G37*
G36*
G01X1703481Y-21750D02*
X1705481Y-26750D01*
X1701481D01*
X1703481Y-21750D01*
G37*
G36*
G01X1696378Y628128D02*
X1692378D01*
X1694378Y623128D01*
X1696378Y628128D01*
G37*
G36*
G01X1769482Y-21750D02*
X1771482Y-26750D01*
X1767482D01*
X1769482Y-21750D01*
G37*
G36*
G01X1724994Y572814D02*
X1736934D01*
Y568414D01*
X1724994D01*
Y572814D01*
G37*
G36*
G01X1892498Y501384D02*
X1896498D01*
X1894498Y506384D01*
X1892498Y501384D01*
G37*
G36*
G01X1843569Y563016D02*
Y559016D01*
X1848569Y561016D01*
X1843569Y563016D01*
G37*
G36*
G01X1868604Y569368D02*
Y538608D01*
X1883204D01*
Y569368D01*
X1868604D01*
G37*
G36*
G01X1882629Y590050D02*
Y594050D01*
X1887629Y592050D01*
X1882629Y590050D01*
G37*
G36*
G01X1954741Y159309D02*
X1948221D01*
Y160164D01*
X1954741D01*
Y159309D01*
G37*
G36*
G01X1902570Y505490D02*
X1906570D01*
X1904570Y500490D01*
X1902570Y505490D01*
G37*
G36*
G01X1969571Y159509D02*
X1963051D01*
Y160364D01*
X1969571D01*
Y159509D01*
G37*
G36*
G01X1970133Y556303D02*
Y560319D01*
X1965133Y558311D01*
X1970133Y556303D01*
G37*
G54D10*
X39530Y5205D03*
X45670Y5185D03*
X33370D03*
X45429Y-4669D03*
X33628Y131D03*
X40994Y-7148D03*
X45700Y40D03*
X11539Y31427D03*
X27200Y30600D03*
X27239Y28027D03*
X25600Y32500D03*
X11600Y33944D03*
X11925Y74867D03*
X11864Y71294D03*
X11539Y39927D03*
X11500Y43400D03*
X11539Y47127D03*
X25886Y71467D03*
X25925Y75867D03*
X26185Y67017D03*
X27488Y64671D03*
X11925Y65311D03*
X27625Y73967D03*
X27525Y69367D03*
X11925Y67811D03*
X11864Y62794D03*
X24064Y61894D03*
X15111Y62553D03*
X27564Y61894D03*
X11600Y36444D03*
X25900Y40300D03*
X27564Y59394D03*
X24064D03*
X25700Y36200D03*
X27300Y34300D03*
Y38300D03*
X27208Y42313D03*
X27239Y47027D03*
X25700Y44400D03*
X27525Y77867D03*
X11864Y78494D03*
X13300Y509600D03*
X13600Y504300D03*
X4000Y509500D03*
X2485Y498185D03*
X13700Y498500D03*
X1439Y546583D03*
Y553783D03*
X1539Y550183D03*
X1500Y540600D03*
X15787Y551700D03*
X17100Y545400D03*
X13639Y534683D03*
Y537183D03*
X15800Y543300D03*
X15600Y539100D03*
X17139Y534683D03*
Y537183D03*
X17100Y541200D03*
X17035Y549558D03*
X15800Y547500D03*
X17139Y553683D03*
X1500Y543100D03*
X1439Y538083D03*
X15800Y579500D03*
Y575300D03*
X17108Y585513D03*
X17156Y581481D03*
X17100Y577400D03*
X17139Y573183D03*
X1500Y576600D03*
X17139Y570683D03*
X1500Y579100D03*
X1539Y586183D03*
X1439Y582583D03*
Y574083D03*
X15770Y587700D03*
X15800Y583500D03*
X1439Y589783D03*
X17139Y589683D03*
X71500Y298000D03*
X66000Y292700D03*
X76800Y298000D03*
X76900Y292600D03*
X66500Y303400D03*
X76800D03*
X76500Y368300D03*
X76300Y358400D03*
X82037Y358542D03*
X70600Y368400D03*
X82100Y368300D03*
X70900Y358300D03*
X141263Y215216D03*
X125563Y218616D03*
X137763Y217716D03*
X128500Y218700D03*
X141263Y217716D03*
X137763Y215216D03*
X125624Y223633D03*
Y221133D03*
X141263Y234216D03*
X141200Y229600D03*
X141211Y225615D03*
X141300Y221700D03*
X139763Y231700D03*
Y227600D03*
Y223700D03*
X139582Y219800D03*
X125563Y234316D03*
X125663Y230716D03*
X125563Y227116D03*
X128200Y250700D03*
X125563Y250616D03*
X141263Y249716D03*
Y247216D03*
X137763D03*
Y249716D03*
X125624Y255633D03*
X125563Y259116D03*
X125663Y262716D03*
X125563Y266316D03*
X141300Y253700D03*
X139631Y251900D03*
X125624Y253133D03*
X137763Y279216D03*
X141263Y266216D03*
X139763Y255700D03*
Y259600D03*
X139800Y263700D03*
X141313Y257533D03*
X141263Y279216D03*
X141200Y261600D03*
X125624Y287633D03*
X125663Y294716D03*
X125563Y298316D03*
Y291116D03*
X128200Y282600D03*
X141263Y311216D03*
X137763D03*
X141263Y281716D03*
X139730Y284200D03*
X139763Y288200D03*
Y292000D03*
Y296000D03*
X125624Y285133D03*
X141200Y286100D03*
X141261Y290076D03*
X141300Y294000D03*
X141263Y298216D03*
X137763Y281716D03*
X125563Y282616D03*
X141211Y325515D03*
X128200Y314800D03*
X141263Y330216D03*
X139763Y327800D03*
X141300Y317500D03*
Y321500D03*
X139582Y315800D03*
X139763Y319400D03*
X125563Y323116D03*
X125663Y326716D03*
X125563Y330316D03*
Y314616D03*
X141263Y313716D03*
X137763D03*
X139763Y323600D03*
X125624Y317133D03*
Y319633D03*
X141289Y349488D03*
X128100Y346700D03*
X141300Y353300D03*
X141200Y357200D03*
X137763Y345716D03*
X141263D03*
Y343216D03*
X125624Y349133D03*
X137763Y343216D03*
X125563Y362316D03*
Y355116D03*
X125663Y358716D03*
X141263Y362216D03*
X139582Y347800D03*
X139763Y351400D03*
Y355200D03*
Y359500D03*
X125624Y351633D03*
X125563Y346616D03*
X141300Y381800D03*
X139763Y384000D03*
X125624Y381133D03*
X141263Y394216D03*
Y390416D03*
X141261Y385876D03*
X139736Y392300D03*
X125563Y378616D03*
X125663Y390716D03*
X125563Y387116D03*
Y394316D03*
X137763Y375216D03*
X141263D03*
Y377716D03*
X137763D03*
X139631Y379900D03*
X128500Y378700D03*
X139900Y388000D03*
X125624Y383633D03*
X659900Y256900D03*
Y269200D03*
X655900Y307700D03*
X656300Y312300D03*
X660700Y307700D03*
X655900Y316500D03*
X656000Y329800D03*
X655900Y320500D03*
X656000Y325100D03*
X660900Y329800D03*
X692000Y45000D03*
Y48500D03*
X697500D03*
Y45000D03*
X692513Y213800D03*
X692673Y206200D03*
X692500Y210100D03*
X690861Y211917D03*
Y215717D03*
X692400Y218100D03*
X690861Y204317D03*
Y208117D03*
X706500Y217400D03*
Y214900D03*
Y207800D03*
X706561Y211417D03*
Y204217D03*
X694361Y223317D03*
Y220817D03*
X690861D03*
Y223317D03*
X672300Y269200D03*
X672200Y256800D03*
X706561Y219917D03*
X719900Y269300D03*
X725500Y279300D03*
X725300Y269400D03*
X719600Y279400D03*
X678200Y307800D03*
X672700Y307700D03*
X667100D03*
X678100Y324800D03*
X672200Y329800D03*
X678100Y329600D03*
X666900Y329700D03*
X678200Y313700D03*
Y319300D03*
X691900Y531350D03*
Y534850D03*
X697500Y534750D03*
Y531250D03*
X775171Y218616D03*
X787371Y215216D03*
Y217716D03*
X777700Y218600D03*
X731100Y269300D03*
Y279300D03*
X775200Y230500D03*
X775171Y227116D03*
Y234316D03*
X787371Y247216D03*
Y249716D03*
X775232Y221133D03*
X777700Y250600D03*
X775232Y223633D03*
X775171Y250616D03*
X775271Y262716D03*
X775171Y259116D03*
Y266316D03*
X775232Y253133D03*
Y255633D03*
X787371Y279216D03*
X775271Y294716D03*
X775171Y291116D03*
Y298316D03*
X777700Y282600D03*
X775232Y287633D03*
Y285133D03*
X775171Y282616D03*
X787371Y281716D03*
Y311216D03*
X775271Y326716D03*
X775171Y323116D03*
Y330316D03*
X777800Y314700D03*
X775171Y314616D03*
X787371Y313716D03*
X775232Y317133D03*
Y319633D03*
X775171Y346616D03*
Y362316D03*
X775271Y358716D03*
X775171Y355116D03*
X787371Y343216D03*
Y345716D03*
X775232Y349133D03*
X777600Y346600D03*
X775232Y351633D03*
X787321Y374916D03*
Y377316D03*
X775182Y383633D03*
Y381133D03*
X778000Y378700D03*
X775121Y378616D03*
Y394316D03*
X775221Y390716D03*
X775121Y387116D03*
X790871Y215216D03*
Y217716D03*
X789500Y231800D03*
X790900Y234000D03*
Y229700D03*
X790846Y225774D03*
X790882Y221723D03*
X790871Y247216D03*
Y249716D03*
X789471Y227742D03*
X789576Y223737D03*
X789554Y219723D03*
X790900Y253900D03*
X789432Y252000D03*
X790871Y266216D03*
X789432Y255800D03*
X790867Y257724D03*
X789432Y259800D03*
X789500Y263900D03*
X790885Y261711D03*
X790871Y279216D03*
Y311216D03*
X789432Y284200D03*
Y288300D03*
Y292400D03*
X789400Y296200D03*
X790871Y298216D03*
X790937Y294270D03*
X790900Y290300D03*
Y286200D03*
X790871Y281716D03*
Y313716D03*
X789432Y319900D03*
Y323900D03*
X790900Y322000D03*
Y326000D03*
X790871Y330216D03*
X789500Y328000D03*
X789478Y315671D03*
X790800Y317700D03*
X789432Y348100D03*
Y352100D03*
X789597Y356105D03*
X789500Y360200D03*
X790900Y358200D03*
X790835Y354048D03*
X790867Y350024D03*
X790871Y345716D03*
Y343216D03*
Y362216D03*
X790821Y374916D03*
X790900Y389300D03*
X789500Y391300D03*
X790900Y393400D03*
Y381100D03*
X789582Y383200D03*
X790900Y385300D03*
X789500Y387300D03*
X790821Y377316D03*
X789282Y379200D03*
X1355950Y-16507D03*
X1359450Y-7D03*
X1355950D03*
X1357489Y-1924D03*
X1359450Y2493D03*
X1355950D03*
X1357489Y-14424D03*
Y-10524D03*
Y-6124D03*
X1355889Y-8524D03*
X1355847Y-12275D03*
X1355989Y-3924D03*
X1356261Y32017D03*
X1356300Y20100D03*
X1356376Y24167D03*
X1356200Y28200D03*
X1357900Y30200D03*
X1357800Y26100D03*
X1357803Y22200D03*
X1356261Y15517D03*
X1357700Y17800D03*
X1359761Y32317D03*
X1371650Y-907D03*
X1371589Y-3424D03*
Y-5924D03*
X1371900Y28600D03*
X1371598Y-11633D03*
X1371632Y-9191D03*
X1371653Y-16654D03*
X1371605Y-14069D03*
X1371941Y22617D03*
X1371950Y20200D03*
X1371900Y17800D03*
Y15400D03*
Y26100D03*
Y31100D03*
X1350830Y60730D03*
X1356261Y34517D03*
X1356950Y54370D03*
X1356760Y66660D03*
X1357000Y60500D03*
X1359761Y34817D03*
X1350800Y66600D03*
X1351190Y54710D03*
X1363170Y54280D03*
X1362900Y60500D03*
X1363040Y66660D03*
X1352200Y104950D03*
Y108400D03*
X1357700D03*
Y104950D03*
X1358500Y374500D03*
X1360200Y377400D03*
X1358655Y379352D03*
X1362068Y393385D03*
X1360300Y381100D03*
X1360200Y384700D03*
Y389000D03*
X1358700Y386700D03*
X1358568Y390885D03*
Y393385D03*
X1358600Y382800D03*
X1362068Y390885D03*
X1374300Y377885D03*
Y381485D03*
X1374268Y374285D03*
Y389985D03*
X1374207Y384968D03*
Y387468D03*
X1352490Y515470D03*
X1346870Y515450D03*
X1352590Y519170D03*
X1346970Y519150D03*
X1360500Y570900D03*
Y574700D03*
X1360261Y578873D03*
X1360247Y567390D03*
X1360261Y562373D03*
Y581373D03*
X1362000Y576700D03*
Y572800D03*
X1362100Y569100D03*
X1362000Y565600D03*
X1375961Y569473D03*
X1376000Y565700D03*
X1375961Y562273D03*
X1363761Y581373D03*
X1375961Y577973D03*
X1376000Y575456D03*
Y572956D03*
X1363761Y612573D03*
X1360261D03*
X1360200Y597800D03*
X1361600Y599900D03*
X1361500Y595700D03*
X1360100Y610100D03*
X1360200Y606300D03*
Y602000D03*
X1361900Y608200D03*
X1361500Y604200D03*
X1360261Y593573D03*
X1375961Y600673D03*
X1375861Y597073D03*
X1375961Y593473D03*
X1363761Y610073D03*
X1375961Y609173D03*
X1375900Y604156D03*
Y606656D03*
X1409500Y538000D03*
X1420500Y549800D03*
X1420400Y538000D03*
X1472412Y596032D03*
Y599532D03*
X1479029Y596132D03*
X1477129Y597656D03*
X1474912Y596032D03*
X1480760Y611602D03*
X1485429Y597571D03*
X1491412Y596032D03*
X1489229Y597571D03*
X1487329Y596032D03*
X1512500Y598639D03*
X1510450Y597300D03*
X1507950D03*
X1510450Y600800D03*
X1508031Y599922D03*
X1524800Y598778D03*
X1522900Y597300D03*
X1526950D03*
X1518800Y597200D03*
X1520813Y598508D03*
X1516800Y598639D03*
X1514500Y597300D03*
X1527050Y613000D03*
X1523450Y612900D03*
X1519850Y613000D03*
X1487912Y611632D03*
X1491512Y611732D03*
X1484312D03*
X1511350Y613000D03*
X1513867Y612939D03*
X1516367D03*
X1475812Y611732D03*
X1474912Y599532D03*
X1478329Y611671D03*
X1483104Y596072D03*
X1481229Y597571D03*
X1589500Y-600D03*
X1547000Y263500D03*
Y269400D03*
X1541000Y263500D03*
Y269500D03*
X1544000Y266500D03*
X1589604Y585896D03*
X1581704D03*
Y590196D03*
X1589604D03*
X1558800Y599300D03*
X1560400Y611600D03*
X1564300Y599400D03*
X1564400Y605500D03*
X1561700Y602200D03*
X1552400Y607600D03*
X1554900Y607100D03*
X1556200Y602400D03*
X1554400Y599300D03*
X1564300Y611500D03*
X1635503Y340146D03*
X1629503D03*
Y346146D03*
X1635503Y346046D03*
X1632503Y343146D03*
X1709400Y513000D03*
X1713600D03*
X1727843Y597142D03*
X1732443Y592342D03*
Y597142D03*
X1727743Y592342D03*
X1788200Y93000D03*
Y89000D03*
Y85000D03*
X1820648Y155537D03*
X1816348D03*
Y163437D03*
X1818500Y159500D03*
X1820648Y163437D03*
X1860995Y84509D03*
X1856873Y91200D03*
X1856778Y87397D03*
X1864208Y87724D03*
X1864195Y84509D03*
X1864153Y91241D03*
X1860815Y91184D03*
X1842250Y90750D03*
X1887300Y121500D03*
X1850700Y156000D03*
X1875700Y115700D03*
Y121500D03*
X1881500Y115700D03*
Y121500D03*
Y127300D03*
X1887300D03*
X1875700D03*
X1887300Y115700D03*
X1846663Y153748D03*
X1854663Y158248D03*
X1846663D03*
X1900740Y178720D03*
X1900700Y172990D03*
Y167290D03*
X1906440Y178720D03*
X1906500Y173100D03*
X1906400Y167290D03*
X1912190Y178870D03*
X1912230Y167330D03*
Y173030D03*
G54D11*
G01X20470Y247537D02*
G03I-500J0D01*
G01X19245Y462182D02*
G03I-500J0D01*
G01X31964Y486344D02*
G03I-500J0D01*
G01X78450Y128450D02*
G03I-500J0D01*
G01X88239Y242573D02*
G03I-500J0D01*
G01X87463Y323750D02*
G03I-500J0D01*
G01X102114Y309750D02*
G03I-501J0D01*
G01X61250Y335841D02*
G03I-500J0D01*
G01X61122Y321700D02*
G03I-500J0D01*
G01X84400Y351000D02*
G03I-500J0D01*
G01X663467Y511167D02*
G03I-500J0D01*
G01X678954Y266626D02*
G03I-500J0D01*
G01X1237003Y105821D02*
G03I-500J0D01*
G01X1237334Y118565D02*
G03I-500J0D01*
G01X1298600Y37900D02*
G03I-500J0D01*
G01X1299029Y231317D02*
G03I-500J0D01*
G01X1287826Y485731D02*
G03I-500J0D01*
G01X1373684Y331553D02*
G03I-500J0D01*
G01X1459004Y142710D02*
G03I-500J0D01*
G01X1463551Y186095D02*
G03I-500J0D01*
G01X1465097Y242376D02*
G03I-500J0D01*
G01X1461097Y219876D02*
G03I-500J0D01*
G01X1494372Y27144D02*
G03I-500J0D01*
G01X1521041Y14750D02*
G03I-500J0D01*
G01X1470766Y144342D02*
G03I-500J0D01*
G01X1497500Y178350D02*
G03I-500J0D01*
G01X1480876Y182467D02*
G03I-500J0D01*
G01X1501850Y175900D02*
G03I-500J0D01*
G01X1523048Y177728D02*
G03I-500J0D01*
G01X1516250Y260950D02*
G03I-500J0D01*
G01X1484431Y326445D02*
G03I-500J0D01*
G01X1533550Y15518D02*
G03I-500J0D01*
G01X1537565Y179772D02*
G03I-500J0D01*
G01X1540128Y168552D02*
G03I-500J0D01*
G01X1539300Y250172D02*
G03I-500J0D01*
G01X1535950Y239900D02*
G03I-500J0D01*
G01X1605760Y-8962D02*
G03I-500J0D01*
G01X1624560Y-910D02*
G03I-500J0D01*
G01X1647049Y23538D02*
G03I-500J0D01*
G01X1616680Y19550D02*
G03I-499J0D01*
G01X1625250Y20750D02*
G03I-500J0D01*
G01X1645150Y56571D02*
G03I-500J0D01*
G01X1645650Y41971D02*
G03I-500J0D01*
G01X1604250Y208659D02*
G03I-500J0D01*
G01X1612217Y341491D02*
G03I-500J0D01*
G01X1639946Y293141D02*
G03I-500J0D01*
G01X1612217Y362491D02*
G03I-500J0D01*
G01Y351991D02*
G03I-500J0D01*
G01X1654642Y292915D02*
G03I-500J0D01*
G01X1656500Y286900D02*
G03I-500J0D01*
G01X1657305Y317902D02*
G03I-500J0D01*
G01X1732353Y65330D02*
G03I-500J0D01*
G01X1747900Y85850D02*
G03I-500J0D01*
G01X1727650Y75750D02*
G03I-500J0D01*
G01X1750059Y504250D02*
G03I-500J0D01*
G01X1749442Y573053D02*
G03I-500J0D01*
G01X1747208Y568480D02*
G03I-500J0D01*
G01X1751149Y595593D02*
G03I-500J0D01*
G01X1752950Y610300D02*
G03I-500J0D01*
G01X1744350Y622000D02*
G03I-500J0D01*
G01X1763150Y592350D02*
G03I-500J0D01*
G01X1779424Y33908D02*
G03I-500J0D01*
G01X1785900Y71750D02*
G03I-500J0D01*
G01X1787518Y140331D02*
G03I-500J0D01*
G01X1808241Y107300D02*
G03I-500J0D01*
G01X1793100Y504750D02*
G03I-500J0D01*
G01X1813266Y513978D02*
G03I-500J0D01*
G01X1830688Y519293D02*
G03I-500J0D01*
G01X1807592Y500221D02*
G03I-500J0D01*
G01X1817750Y566400D02*
G03I-500J0D01*
G01X1800843Y540641D02*
G03I-500J0D01*
G01X1815692Y603710D02*
G03I-500J0D01*
G01X1870144Y58114D02*
G03I-500J0D01*
G01X1843215Y65387D02*
G03I-500J0D01*
G01X1892168Y222677D02*
G03I-500J0D01*
G01X1878456Y491179D02*
G03I-500J0D01*
G01X1871600Y467000D02*
G03I-500J0D01*
G01X1866392Y535323D02*
G03I-500J0D01*
G01X1897338Y586082D02*
G03I-500J0D01*
G01X1881615Y594339D02*
G03I-500J0D01*
G01X1953065Y137099D02*
G03I-500J0D01*
G01X1939316Y217684D02*
G03I-500J0D01*
G01X1944537Y179863D02*
G03I-500J0D01*
G01X1935600Y526350D02*
G03I-500J0D01*
G01X1950240Y494898D02*
G03I-500J0D01*
G01X1902928Y586256D02*
G03I-500J0D01*
G01Y560156D02*
G03I-500J0D01*
G01Y577556D02*
G03I-500J0D01*
G01Y568856D02*
G03I-500J0D01*
G01X1923891Y556841D02*
G03I-500J0D01*
G01X1946799Y528596D02*
G03I-500J0D01*
G01X1901000Y545600D02*
G03I-500J0D01*
G01X1951245Y530560D02*
G03I-500J0D01*
G01X1923141Y607850D02*
G03I-500J0D01*
G01X1965370Y190178D02*
G03I-500J0D01*
G01X1970840Y504160D02*
G03I-500J0D01*
G01X1973300Y581450D02*
G03I-500J0D01*
G01X1973800Y561150D02*
G03I-500J0D01*
G54D12*
G01X-11900Y38000D02*
Y33000D01*
G01X-12300Y27700D02*
Y22700D01*
G01X-12216Y47978D02*
Y42978D01*
G01X-12150Y57960D02*
Y52960D01*
G01X-960Y67030D02*
Y75630D01*
G01X46900Y490600D02*
Y484400D01*
G01X430749Y-124922D02*
G02I-12000J0D01*
G01X425599D02*
G02I-6850J0D01*
G01X434749D02*
X402749D01*
G01X434749Y-140922D02*
Y-220922D01*
G01D02*
X1729349D01*
G01X434749Y-176422D02*
X1729349D01*
G01X418749Y-140922D02*
Y-108922D01*
G01X434749Y-140922D02*
X1729349D01*
G01X708770Y240145D02*
X703770D01*
G01X717400Y240290D02*
X712400D01*
G01X726104Y233224D02*
X721104D01*
G01X724600Y520500D02*
Y525500D01*
G01X726068Y33402D02*
Y38402D01*
G01X734000Y212500D02*
X739000D01*
G01X748000Y211000D02*
Y216000D01*
G01X734844Y233243D02*
X729844D01*
G01X743555Y238036D02*
X738555D01*
G01X941849Y-140922D02*
Y-220922D01*
G01X1079349Y-140922D02*
Y-220922D01*
G01X1194349Y-140922D02*
Y-220922D01*
G01X1361849Y-140922D02*
Y-220922D01*
G01X1387031Y94854D02*
Y99854D01*
G01X1401920Y375698D02*
Y380698D01*
G01Y367863D02*
Y372863D01*
G01X1382500Y410500D02*
X1377500D01*
G01X1374500D02*
X1369500D01*
G01X1366500D02*
X1361500D01*
G01X1390500D02*
X1385500D01*
G01X1359155Y527255D02*
X1354155D01*
G01X1370284Y557953D02*
Y552953D01*
G01X1392315Y555332D02*
Y560332D01*
G01Y562972D02*
Y567972D01*
G01X1396450Y578060D02*
X1401450D01*
G01X1426761Y572723D02*
X1431761D01*
G01X1434513D02*
X1439513D01*
G01X1406904Y577863D02*
X1411904D01*
G01X1460500Y596000D02*
Y601000D01*
G01X1446026Y597222D02*
X1451026D01*
G01X1459194Y614770D02*
X1454194D01*
G01X1451194D02*
X1446194D01*
G01X1443194D02*
X1438194D01*
G01X1531849Y-140922D02*
Y-220922D01*
G01X1554267Y53326D02*
Y45626D01*
G01X1538073Y44808D02*
Y37108D01*
G01X1561424Y224720D02*
X1571524D01*
G01X1576610Y294840D02*
X1568910D01*
G01X1729349Y-140922D02*
Y-220922D01*
G01X1757349Y-124922D02*
G02I-12000J0D01*
G01X1752199D02*
G02I-6850J0D01*
G01X1745349Y-140922D02*
Y-108922D01*
G01X1761349Y-124922D02*
X1729349D01*
G01X1722834Y572814D02*
Y578914D01*
G01X1875900Y164600D02*
Y159600D01*
G01X1875940Y172249D02*
Y167249D01*
G01X1874700Y182200D02*
Y177200D01*
G01X1874800Y193600D02*
Y188600D01*
G01X1890904Y570628D02*
X1881404Y570638D01*
G01X1956631Y157809D02*
Y152689D01*
G01X1903500Y211050D02*
X1909500D01*
G01X1919724Y219907D02*
X1924724D01*
G01X1912069Y219896D02*
X1917069D01*
G01X1971461Y158009D02*
Y152889D01*
G01X1965987Y217993D02*
X1970987D01*
G54D13*
G01X1709705Y539095D02*
G03X1704705I-2500J-2304D01*
G01D02*
G03X1699705I-2500J-2304D01*
G01D02*
G03X1694705I-2500J-2304D01*
G01D02*
G03X1689705I-2500J-2304D01*
G01D02*
G03Y534487I-2500J-2304D01*
G01D02*
G03X1694705I2500J2304D01*
G01D02*
G03X1699705I2500J2304D01*
G01D02*
G03X1704705I2500J2304D01*
G01D02*
G03X1709705I2500J2304D01*
G01X1714705Y539095D02*
G03X1709705I-2500J-2304D01*
G01Y534487D02*
G03X1714705I2500J2304D01*
G01D02*
G03Y539095I2500J2304D01*
G01X1738654Y536991D02*
Y536591D01*
G01X1759370Y534327D02*
G03X1764339Y536591I1969J2264D01*
G01D02*
Y536991D01*
G01D02*
G03X1759370Y539255I-3000J0D01*
G01D02*
G03X1755434I-1968J-2264D01*
G01D02*
G03X1751496I-1969J-2264D01*
G01D02*
G03X1747560I-1968J-2264D01*
G01D02*
G03X1743622I-1969J-2264D01*
G01D02*
G03X1738654Y536991I-1968J-2264D01*
G01Y536591D02*
G03X1743622Y534327I3000J0D01*
G01D02*
G03X1747560I1969J2264D01*
G01D02*
G03X1751496I1968J2264D01*
G01D02*
G03X1755434I1969J2264D01*
G01D02*
G03X1759370I1968J2264D01*
G01X1940787Y-11811D02*
X1921102D01*
G01Y55118D02*
X1940787D01*
G54D14*
G01X1507550Y326750D02*
Y330600D01*
X1503750D01*
G01X1552710Y156650D02*
X1548860D01*
Y152850D01*
G01X1622650Y57750D02*
Y61600D01*
X1618850D01*
G01X1767100Y81100D02*
Y83950D01*
X1764400D01*
G54D15*
G01X22835Y-23622D02*
X-7874D01*
G01Y626378D02*
X22835D01*
G01X137797Y-23620D02*
X168506D01*
G01X137797Y626380D02*
X168506D01*
G01X341734Y-23620D02*
X372443D01*
G01X341734Y626380D02*
X372443D01*
G01X560632Y-23620D02*
X529923D01*
G01Y626380D02*
X560632D01*
G01X819687Y-23620D02*
X788979D01*
G01Y626380D02*
X819687D01*
G01X1006301Y-23620D02*
X975593D01*
G01Y626380D02*
X1006301D01*
G01X1162207Y-23620D02*
X1192916D01*
G01Y626380D02*
X1162207D01*
G01X1429134Y-23622D02*
X1398425D01*
G01X1425199Y626380D02*
X1394490D01*
G01X1513100Y218350D02*
G03I-750J0D01*
G01X1511300Y246350D02*
G03I-750J0D01*
G01X1881890Y-23622D02*
X1851181D01*
G01X1881892Y626380D02*
X1851183D01*
G01X1939129Y74770D02*
G03I-750J0D01*
G54D16*
G01X249660Y27514D02*
Y35514D01*
X247326D01*
X246393Y35114D01*
X245693Y34581D01*
X245110Y33781D01*
X244643Y32847D01*
X244526Y31514D01*
X244643Y30181D01*
X245110Y29247D01*
X245693Y28447D01*
X246393Y27914D01*
X247326Y27514D01*
X249660D01*
G01X238993Y35514D02*
X236193D01*
G01X237593D02*
Y27514D01*
G01X238993D02*
X236193D01*
G01X231126D02*
Y35514D01*
X228093Y28847D01*
X225060Y35514D01*
Y27514D01*
G01X221626D02*
Y35514D01*
X218593Y28847D01*
X215560Y35514D01*
Y27514D01*
G01X197026Y34847D02*
X197726Y35247D01*
X198543Y35514D01*
X199476D01*
X200526Y35114D01*
X201343Y34447D01*
X201926Y33647D01*
X202393Y32314D01*
X202510Y31114D01*
X202276Y29914D01*
X201926Y29114D01*
X201226Y28314D01*
X200410Y27781D01*
X199593Y27514D01*
X198776D01*
X197960Y27781D01*
X197260Y28181D01*
X196676Y28714D01*
G01X192660D02*
X191960Y28047D01*
X191143Y27647D01*
X190093Y27514D01*
X189043Y27781D01*
X188226Y28314D01*
X187643Y29247D01*
X187526Y30314D01*
X187760Y31381D01*
X188343Y32047D01*
X189160Y32581D01*
X189976Y32714D01*
X190793Y32581D01*
X191843Y32047D01*
X191493Y35514D01*
X188343D01*
G01X249391Y65418D02*
Y73418D01*
X247057D01*
X246124Y73018D01*
X245424Y72485D01*
X244841Y71685D01*
X244374Y70751D01*
X244257Y69418D01*
X244374Y68085D01*
X244841Y67151D01*
X245424Y66351D01*
X246124Y65818D01*
X247057Y65418D01*
X249391D01*
G01X238724Y73418D02*
X235924D01*
G01X237324D02*
Y65418D01*
G01X238724D02*
X235924D01*
G01X230857D02*
Y73418D01*
X227824Y66751D01*
X224791Y73418D01*
Y65418D01*
G01X221357D02*
Y73418D01*
X218324Y66751D01*
X215291Y73418D01*
Y65418D01*
G01X196757Y72751D02*
X197457Y73151D01*
X198274Y73418D01*
X199207D01*
X200257Y73018D01*
X201074Y72351D01*
X201657Y71551D01*
X202124Y70218D01*
X202241Y69018D01*
X202007Y67818D01*
X201657Y67018D01*
X200957Y66218D01*
X200141Y65685D01*
X199324Y65418D01*
X198507D01*
X197691Y65685D01*
X196991Y66085D01*
X196407Y66618D01*
G01X188424Y65418D02*
Y73418D01*
X192741Y67685D01*
X186907D01*
G01X242437Y106350D02*
Y114350D01*
X240103D01*
X239170Y113950D01*
X238470Y113417D01*
X237887Y112617D01*
X237420Y111683D01*
X237303Y110350D01*
X237420Y109017D01*
X237887Y108083D01*
X238470Y107283D01*
X239170Y106750D01*
X240103Y106350D01*
X242437D01*
G01X231770Y114350D02*
X228970D01*
G01X230370D02*
Y106350D01*
G01X231770D02*
X228970D01*
G01X223903D02*
Y114350D01*
X220870Y107683D01*
X217837Y114350D01*
Y106350D01*
G01X214403D02*
Y114350D01*
X211370Y107683D01*
X208337Y114350D01*
Y106350D01*
G01X189803Y113683D02*
X190503Y114083D01*
X191320Y114350D01*
X192253D01*
X193303Y113950D01*
X194120Y113283D01*
X194703Y112483D01*
X195170Y111150D01*
X195287Y109950D01*
X195053Y108750D01*
X194703Y107950D01*
X194003Y107150D01*
X193187Y106617D01*
X192370Y106350D01*
X191553D01*
X190737Y106617D01*
X190037Y107017D01*
X189453Y107550D01*
G01X185437Y107950D02*
X184737Y107017D01*
X183803Y106483D01*
X182753Y106350D01*
X181820Y106483D01*
X180887Y107150D01*
X180303Y107950D01*
X180187Y108750D01*
X180420Y109683D01*
X181237Y110350D01*
X182053Y110617D01*
X183103D01*
G01X182053D02*
X181353Y111017D01*
X180770Y111683D01*
X180537Y112483D01*
X180770Y113283D01*
X181353Y113950D01*
X182403Y114350D01*
X183453Y114217D01*
X184503Y113683D01*
G01X249391Y528473D02*
Y536473D01*
X247057D01*
X246124Y536073D01*
X245424Y535540D01*
X244841Y534740D01*
X244374Y533806D01*
X244257Y532473D01*
X244374Y531140D01*
X244841Y530206D01*
X245424Y529406D01*
X246124Y528873D01*
X247057Y528473D01*
X249391D01*
G01X238724Y536473D02*
X235924D01*
G01X237324D02*
Y528473D01*
G01X238724D02*
X235924D01*
G01X230857D02*
Y536473D01*
X227824Y529806D01*
X224791Y536473D01*
Y528473D01*
G01X221357D02*
Y536473D01*
X218324Y529806D01*
X215291Y536473D01*
Y528473D01*
G01X201891D02*
Y536473D01*
X199557D01*
X198624Y536073D01*
X197924Y535540D01*
X197341Y534740D01*
X196874Y533806D01*
X196757Y532473D01*
X196874Y531140D01*
X197341Y530206D01*
X197924Y529406D01*
X198624Y528873D01*
X199557Y528473D01*
X201891D01*
G01X192391Y530073D02*
X191691Y529140D01*
X190757Y528606D01*
X189707Y528473D01*
X188774Y528606D01*
X187841Y529273D01*
X187257Y530073D01*
X187141Y530873D01*
X187374Y531806D01*
X188191Y532473D01*
X189007Y532740D01*
X190057D01*
G01X189007D02*
X188307Y533140D01*
X187724Y533806D01*
X187491Y534606D01*
X187724Y535406D01*
X188307Y536073D01*
X189357Y536473D01*
X190407Y536340D01*
X191457Y535806D01*
G01X249659Y566512D02*
Y574512D01*
X247325D01*
X246392Y574112D01*
X245692Y573579D01*
X245109Y572779D01*
X244642Y571845D01*
X244525Y570512D01*
X244642Y569179D01*
X245109Y568245D01*
X245692Y567445D01*
X246392Y566912D01*
X247325Y566512D01*
X249659D01*
G01X238992Y574512D02*
X236192D01*
G01X237592D02*
Y566512D01*
G01X238992D02*
X236192D01*
G01X231125D02*
Y574512D01*
X228092Y567845D01*
X225059Y574512D01*
Y566512D01*
G01X221625D02*
Y574512D01*
X218592Y567845D01*
X215559Y574512D01*
Y566512D01*
G01X202159D02*
Y574512D01*
X199825D01*
X198892Y574112D01*
X198192Y573579D01*
X197609Y572779D01*
X197142Y571845D01*
X197025Y570512D01*
X197142Y569179D01*
X197609Y568245D01*
X198192Y567445D01*
X198892Y566912D01*
X199825Y566512D01*
X202159D01*
G01X188692D02*
Y574512D01*
X193009Y568779D01*
X187175D01*
G01X249659Y605223D02*
Y613223D01*
X247325D01*
X246392Y612823D01*
X245692Y612290D01*
X245109Y611490D01*
X244642Y610556D01*
X244525Y609223D01*
X244642Y607890D01*
X245109Y606956D01*
X245692Y606156D01*
X246392Y605623D01*
X247325Y605223D01*
X249659D01*
G01X238992Y613223D02*
X236192D01*
G01X237592D02*
Y605223D01*
G01X238992D02*
X236192D01*
G01X231125D02*
Y613223D01*
X228092Y606556D01*
X225059Y613223D01*
Y605223D01*
G01X221625D02*
Y613223D01*
X218592Y606556D01*
X215559Y613223D01*
Y605223D01*
G01X202159D02*
Y613223D01*
X199825D01*
X198892Y612823D01*
X198192Y612290D01*
X197609Y611490D01*
X197142Y610556D01*
X197025Y609223D01*
X197142Y607890D01*
X197609Y606956D01*
X198192Y606156D01*
X198892Y605623D01*
X199825Y605223D01*
X202159D01*
G01X192659Y606423D02*
X191959Y605756D01*
X191142Y605356D01*
X190092Y605223D01*
X189042Y605490D01*
X188225Y606023D01*
X187642Y606956D01*
X187525Y608023D01*
X187759Y609090D01*
X188342Y609756D01*
X189159Y610290D01*
X189975Y610423D01*
X190792Y610290D01*
X191842Y609756D01*
X191492Y613223D01*
X188342D01*
G01X869844Y27648D02*
Y35648D01*
X867510D01*
X866577Y35248D01*
X865877Y34715D01*
X865294Y33915D01*
X864827Y32981D01*
X864710Y31648D01*
X864827Y30315D01*
X865294Y29381D01*
X865877Y28581D01*
X866577Y28048D01*
X867510Y27648D01*
X869844D01*
G01X859177Y35648D02*
X856377D01*
G01X857777D02*
Y27648D01*
G01X859177D02*
X856377D01*
G01X851310D02*
Y35648D01*
X848277Y28981D01*
X845244Y35648D01*
Y27648D01*
G01X841810D02*
Y35648D01*
X838777Y28981D01*
X835744Y35648D01*
Y27648D01*
G01X822694D02*
X819777Y35648D01*
X816860Y27648D01*
G01X817910Y30448D02*
X821644D01*
G01X812844Y28848D02*
X812144Y28181D01*
X811327Y27781D01*
X810277Y27648D01*
X809227Y27915D01*
X808410Y28448D01*
X807827Y29381D01*
X807710Y30448D01*
X807944Y31515D01*
X808527Y32181D01*
X809344Y32715D01*
X810160Y32848D01*
X810977Y32715D01*
X812027Y32181D01*
X811677Y35648D01*
X808527D01*
G01X869306Y65553D02*
Y73553D01*
X866972D01*
X866039Y73153D01*
X865339Y72620D01*
X864756Y71820D01*
X864289Y70886D01*
X864172Y69553D01*
X864289Y68220D01*
X864756Y67286D01*
X865339Y66486D01*
X866039Y65953D01*
X866972Y65553D01*
X869306D01*
G01X858639Y73553D02*
X855839D01*
G01X857239D02*
Y65553D01*
G01X858639D02*
X855839D01*
G01X850772D02*
Y73553D01*
X847739Y66886D01*
X844706Y73553D01*
Y65553D01*
G01X841272D02*
Y73553D01*
X838239Y66886D01*
X835206Y73553D01*
Y65553D01*
G01X822156D02*
X819239Y73553D01*
X816322Y65553D01*
G01X817372Y68353D02*
X821106D01*
G01X808339Y65553D02*
Y73553D01*
X812656Y67820D01*
X806822D01*
G01X861511Y105608D02*
Y113608D01*
X859177D01*
X858244Y113208D01*
X857544Y112675D01*
X856961Y111875D01*
X856494Y110941D01*
X856377Y109608D01*
X856494Y108275D01*
X856961Y107341D01*
X857544Y106541D01*
X858244Y106008D01*
X859177Y105608D01*
X861511D01*
G01X850844Y113608D02*
X848044D01*
G01X849444D02*
Y105608D01*
G01X850844D02*
X848044D01*
G01X842977D02*
Y113608D01*
X839944Y106941D01*
X836911Y113608D01*
Y105608D01*
G01X833477D02*
Y113608D01*
X830444Y106941D01*
X827411Y113608D01*
Y105608D01*
G01X814361D02*
X811444Y113608D01*
X808527Y105608D01*
G01X809577Y108408D02*
X813311D01*
G01X804511Y107208D02*
X803811Y106275D01*
X802877Y105741D01*
X801827Y105608D01*
X800894Y105741D01*
X799961Y106408D01*
X799377Y107208D01*
X799261Y108008D01*
X799494Y108941D01*
X800311Y109608D01*
X801127Y109875D01*
X802177D01*
G01X801127D02*
X800427Y110275D01*
X799844Y110941D01*
X799611Y111741D01*
X799844Y112541D01*
X800427Y113208D01*
X801477Y113608D01*
X802527Y113475D01*
X803577Y112941D01*
G01X891349Y528876D02*
Y536876D01*
X889015D01*
X888082Y536476D01*
X887382Y535943D01*
X886799Y535143D01*
X886332Y534209D01*
X886215Y532876D01*
X886332Y531543D01*
X886799Y530609D01*
X887382Y529809D01*
X888082Y529276D01*
X889015Y528876D01*
X891349D01*
G01X880682Y536876D02*
X877882D01*
G01X879282D02*
Y528876D01*
G01X880682D02*
X877882D01*
G01X872815D02*
Y536876D01*
X869782Y530209D01*
X866749Y536876D01*
Y528876D01*
G01X863315D02*
Y536876D01*
X860282Y530209D01*
X857249Y536876D01*
Y528876D01*
G01X840349Y533143D02*
X839882Y533543D01*
X839532Y534209D01*
X839299Y535143D01*
X839532Y535943D01*
X839999Y536476D01*
X840815Y536876D01*
X843965D01*
Y528876D01*
X840115D01*
X839299Y529409D01*
X838832Y530209D01*
X838599Y531143D01*
X838832Y532076D01*
X839532Y532876D01*
X840349Y533143D01*
X843965D01*
G01X834349Y530476D02*
X833649Y529543D01*
X832715Y529009D01*
X831665Y528876D01*
X830732Y529009D01*
X829799Y529676D01*
X829215Y530476D01*
X829099Y531276D01*
X829332Y532209D01*
X830149Y532876D01*
X830965Y533143D01*
X832015D01*
G01X830965D02*
X830265Y533543D01*
X829682Y534209D01*
X829449Y535009D01*
X829682Y535809D01*
X830265Y536476D01*
X831315Y536876D01*
X832365Y536743D01*
X833415Y536209D01*
G01X891081Y566646D02*
Y574646D01*
X888747D01*
X887814Y574246D01*
X887114Y573713D01*
X886531Y572913D01*
X886064Y571979D01*
X885947Y570646D01*
X886064Y569313D01*
X886531Y568379D01*
X887114Y567579D01*
X887814Y567046D01*
X888747Y566646D01*
X891081D01*
G01X880414Y574646D02*
X877614D01*
G01X879014D02*
Y566646D01*
G01X880414D02*
X877614D01*
G01X872547D02*
Y574646D01*
X869514Y567979D01*
X866481Y574646D01*
Y566646D01*
G01X863047D02*
Y574646D01*
X860014Y567979D01*
X856981Y574646D01*
Y566646D01*
G01X840081Y570913D02*
X839614Y571313D01*
X839264Y571979D01*
X839031Y572913D01*
X839264Y573713D01*
X839731Y574246D01*
X840547Y574646D01*
X843697D01*
Y566646D01*
X839847D01*
X839031Y567179D01*
X838564Y567979D01*
X838331Y568913D01*
X838564Y569846D01*
X839264Y570646D01*
X840081Y570913D01*
X843697D01*
G01X830114Y566646D02*
Y574646D01*
X834431Y568913D01*
X828597D01*
G01X891215Y604820D02*
Y612820D01*
X888881D01*
X887948Y612420D01*
X887248Y611887D01*
X886665Y611087D01*
X886198Y610153D01*
X886081Y608820D01*
X886198Y607487D01*
X886665Y606553D01*
X887248Y605753D01*
X887948Y605220D01*
X888881Y604820D01*
X891215D01*
G01X880548Y612820D02*
X877748D01*
G01X879148D02*
Y604820D01*
G01X880548D02*
X877748D01*
G01X872681D02*
Y612820D01*
X869648Y606153D01*
X866615Y612820D01*
Y604820D01*
G01X863181D02*
Y612820D01*
X860148Y606153D01*
X857115Y612820D01*
Y604820D01*
G01X840215Y609087D02*
X839748Y609487D01*
X839398Y610153D01*
X839165Y611087D01*
X839398Y611887D01*
X839865Y612420D01*
X840681Y612820D01*
X843831D01*
Y604820D01*
X839981D01*
X839165Y605353D01*
X838698Y606153D01*
X838465Y607087D01*
X838698Y608020D01*
X839398Y608820D01*
X840215Y609087D01*
X843831D01*
G01X834215Y606020D02*
X833515Y605353D01*
X832698Y604953D01*
X831648Y604820D01*
X830598Y605087D01*
X829781Y605620D01*
X829198Y606553D01*
X829081Y607620D01*
X829315Y608687D01*
X829898Y609353D01*
X830715Y609887D01*
X831531Y610020D01*
X832348Y609887D01*
X833398Y609353D01*
X833048Y612820D01*
X829898D01*
G01X1565250Y112190D02*
Y116040D01*
X1561450D01*
G01X1931026Y136648D02*
G03I-500J0D01*
G54D17*
G01X548049Y-193422D02*
Y-210922D01*
G01X543027Y-193422D02*
X553071D01*
G01X565549Y-199256D02*
Y-210922D01*
G01Y-194589D02*
X565112Y-194297D01*
Y-193714D01*
X565549Y-193422D01*
X565986Y-193714D01*
Y-194297D01*
X565549Y-194589D01*
G01X583049Y-210922D02*
X581739Y-210630D01*
X580429Y-209464D01*
X579555Y-207422D01*
X579119Y-205089D01*
X579555Y-202755D01*
X580429Y-200714D01*
X581739Y-199547D01*
X583049Y-199256D01*
X584359Y-199547D01*
X585669Y-200714D01*
X586542Y-202755D01*
X586761Y-205089D01*
X586542Y-207422D01*
X585669Y-209464D01*
X584359Y-210630D01*
X583049Y-210922D01*
G01X597492Y-215297D02*
X599021Y-216464D01*
X600767Y-216755D01*
X602295Y-216464D01*
X603606Y-215006D01*
X604479Y-212964D01*
Y-199256D01*
G01Y-201589D02*
X603606Y-200422D01*
X602295Y-199547D01*
X600767Y-199256D01*
X599021Y-199839D01*
X597929Y-201005D01*
X597055Y-203047D01*
X596619Y-205089D01*
X596837Y-206839D01*
X597711Y-208881D01*
X599021Y-210339D01*
X600767Y-210922D01*
X602077Y-210630D01*
X603606Y-209464D01*
X604479Y-208298D01*
G01X621979Y-210922D02*
Y-199256D01*
G01Y-201297D02*
X621106Y-200131D01*
X619795Y-199547D01*
X618267Y-199256D01*
X616739Y-199839D01*
X615429Y-201005D01*
X614555Y-202755D01*
X614119Y-205089D01*
X614555Y-207422D01*
X615429Y-209172D01*
X616739Y-210339D01*
X618267Y-210922D01*
X619795Y-210630D01*
X621106Y-209756D01*
X621979Y-208589D01*
G01X648682Y-210922D02*
Y-193422D01*
X653922D01*
X655669Y-194297D01*
X656979Y-196339D01*
X657416Y-198672D01*
X656979Y-201005D01*
X655887Y-202755D01*
X653922Y-203631D01*
X648682D01*
G01X674479Y-210922D02*
Y-199256D01*
G01Y-201297D02*
X673606Y-200131D01*
X672295Y-199547D01*
X670767Y-199256D01*
X669239Y-199839D01*
X667929Y-201005D01*
X667055Y-202755D01*
X666619Y-205089D01*
X667055Y-207422D01*
X667929Y-209172D01*
X669239Y-210339D01*
X670767Y-210922D01*
X672295Y-210630D01*
X673606Y-209756D01*
X674479Y-208589D01*
G01X684774Y-208881D02*
X685866Y-210047D01*
X687394Y-210922D01*
X688704D01*
X690014Y-210339D01*
X690887Y-209464D01*
X691324Y-208298D01*
X691106Y-206547D01*
X690232Y-205672D01*
X686302Y-203922D01*
X685429Y-201880D01*
X685866Y-200422D01*
X686739Y-199547D01*
X688049Y-199256D01*
X689359Y-199547D01*
X690669Y-200422D01*
G01X702274Y-208881D02*
X703366Y-210047D01*
X704894Y-210922D01*
X706204D01*
X707514Y-210339D01*
X708387Y-209464D01*
X708824Y-208298D01*
X708606Y-206547D01*
X707732Y-205672D01*
X703802Y-203922D01*
X702929Y-201880D01*
X703366Y-200422D01*
X704239Y-199547D01*
X705549Y-199256D01*
X706859Y-199547D01*
X708169Y-200422D01*
G01X735746Y-210922D02*
Y-193422D01*
X740112D01*
X741859Y-194297D01*
X743169Y-195464D01*
X744261Y-197213D01*
X745134Y-199256D01*
X745352Y-202172D01*
X745134Y-205089D01*
X744261Y-207131D01*
X743169Y-208881D01*
X741859Y-210047D01*
X740112Y-210922D01*
X735746D01*
G01X752590Y-193422D02*
X758049Y-210922D01*
X763508Y-193422D01*
G01X775549D02*
Y-210922D01*
G01X770527Y-193422D02*
X780571D01*
G01X804872Y-210922D02*
Y-193422D01*
X810549Y-208005D01*
X816226Y-193422D01*
Y-210922D01*
G01X829795Y-201589D02*
X830669Y-200714D01*
X831324Y-199256D01*
X831761Y-197213D01*
X831324Y-195464D01*
X830451Y-194297D01*
X828922Y-193422D01*
X823027D01*
Y-210922D01*
X830232D01*
X831761Y-209756D01*
X832634Y-208005D01*
X833071Y-205964D01*
X832634Y-203922D01*
X831324Y-202172D01*
X829795Y-201589D01*
X823027D01*
G01X647372Y-165922D02*
Y-148422D01*
X653049Y-163005D01*
X658726Y-148422D01*
Y-165922D01*
G01X670549D02*
X669239Y-165630D01*
X667929Y-164464D01*
X667055Y-162422D01*
X666619Y-160089D01*
X667055Y-157755D01*
X667929Y-155714D01*
X669239Y-154547D01*
X670549Y-154256D01*
X671859Y-154547D01*
X673169Y-155714D01*
X674042Y-157755D01*
X674261Y-160089D01*
X674042Y-162422D01*
X673169Y-164464D01*
X671859Y-165630D01*
X670549Y-165922D01*
G01X691979Y-148422D02*
Y-165922D01*
G01Y-163298D02*
X691106Y-164756D01*
X689795Y-165630D01*
X688267Y-165922D01*
X686521Y-165339D01*
X685211Y-163881D01*
X684337Y-162131D01*
X684119Y-160089D01*
X684337Y-158047D01*
X685211Y-156297D01*
X686521Y-154839D01*
X688267Y-154256D01*
X689795Y-154547D01*
X690887Y-155131D01*
X691979Y-156297D01*
G01X702274Y-158047D02*
X709261D01*
X708606Y-156005D01*
X707514Y-154839D01*
X705986Y-154256D01*
X704457Y-154547D01*
X703147Y-155422D01*
X702274Y-157464D01*
X701837Y-159214D01*
Y-160964D01*
X702274Y-162714D01*
X703366Y-164464D01*
X704676Y-165630D01*
X706204Y-165922D01*
X707732Y-165339D01*
X709261Y-163589D01*
G01X723049Y-165922D02*
Y-148422D01*
G01X975549Y-210922D02*
Y-193422D01*
X972929Y-196922D01*
G01Y-210922D02*
X978169D01*
G01X988246Y-208298D02*
X989555Y-209756D01*
X991084Y-210630D01*
X993049Y-210922D01*
X995014Y-210339D01*
X996542Y-209172D01*
X997634Y-207131D01*
X997852Y-204797D01*
X997416Y-202464D01*
X996324Y-201005D01*
X994795Y-199839D01*
X993267Y-199547D01*
X991739Y-199839D01*
X989774Y-201005D01*
X990429Y-193422D01*
X996324D01*
G01X1010549Y-210922D02*
Y-193422D01*
X1007929Y-196922D01*
G01Y-210922D02*
X1013169D01*
G01X1023901Y-196339D02*
X1025211Y-194589D01*
X1026739Y-193714D01*
X1028486Y-193422D01*
X1030669Y-194005D01*
X1032197Y-195464D01*
X1032634Y-197213D01*
X1032416Y-198964D01*
X1031542Y-200422D01*
X1027176Y-203339D01*
X1025211Y-205380D01*
X1023901Y-208298D01*
X1023464Y-210922D01*
X1032634D01*
G01X1041401Y-203631D02*
X1042929Y-201589D01*
X1044239Y-200422D01*
X1045986Y-199839D01*
X1047514Y-200422D01*
X1048606Y-201589D01*
X1049479Y-203339D01*
X1049697Y-205380D01*
X1049479Y-207131D01*
X1048606Y-208881D01*
X1047295Y-210339D01*
X1045767Y-210922D01*
X1044021Y-210339D01*
X1042492Y-208589D01*
X1041619Y-205964D01*
X1041401Y-203047D01*
X1041837Y-199256D01*
X1042492Y-197213D01*
X1043584Y-195172D01*
X1045112Y-193714D01*
X1046641Y-193422D01*
X1048169Y-194005D01*
X1049261Y-195464D01*
G01X962432Y-165922D02*
Y-148422D01*
X967672D01*
X969419Y-149297D01*
X970729Y-151339D01*
X971166Y-153672D01*
X970729Y-156005D01*
X969637Y-157755D01*
X967672Y-158631D01*
X962432D01*
G01X989102Y-149881D02*
X987792Y-149005D01*
X986264Y-148422D01*
X984517D01*
X982552Y-149297D01*
X981024Y-150755D01*
X979932Y-152506D01*
X979059Y-155422D01*
X978840Y-158047D01*
X979277Y-160672D01*
X979932Y-162422D01*
X981242Y-164172D01*
X982771Y-165339D01*
X984299Y-165922D01*
X985827D01*
X987356Y-165339D01*
X988666Y-164464D01*
X989758Y-163298D01*
G01X1003545Y-156589D02*
X1004419Y-155714D01*
X1005074Y-154256D01*
X1005511Y-152213D01*
X1005074Y-150464D01*
X1004201Y-149297D01*
X1002672Y-148422D01*
X996777D01*
Y-165922D01*
X1003982D01*
X1005511Y-164756D01*
X1006384Y-163005D01*
X1006821Y-160964D01*
X1006384Y-158922D01*
X1005074Y-157172D01*
X1003545Y-156589D01*
X996777D01*
G01X1012749Y-171755D02*
X1025849D01*
G01X1031777Y-165922D02*
Y-148422D01*
X1041821Y-165922D01*
Y-148422D01*
G01X1054299Y-165922D02*
X1052552Y-165630D01*
X1051024Y-164464D01*
X1049714Y-162714D01*
X1048840Y-160672D01*
X1048404Y-158339D01*
Y-156005D01*
X1048840Y-153672D01*
X1049714Y-151630D01*
X1051024Y-149881D01*
X1052552Y-148714D01*
X1054299Y-148422D01*
X1056045Y-148714D01*
X1057574Y-149881D01*
X1058884Y-151630D01*
X1059758Y-153672D01*
X1060194Y-156005D01*
Y-158339D01*
X1059758Y-160672D01*
X1058884Y-162714D01*
X1057574Y-164464D01*
X1056045Y-165630D01*
X1054299Y-165922D01*
G01X1128099Y-210922D02*
Y-193422D01*
X1125479Y-196922D01*
G01Y-210922D02*
X1130719D01*
G01X1147345Y-201589D02*
X1148219Y-200714D01*
X1148874Y-199256D01*
X1149311Y-197213D01*
X1148874Y-195464D01*
X1148001Y-194297D01*
X1146472Y-193422D01*
X1140577D01*
Y-210922D01*
X1147782D01*
X1149311Y-209756D01*
X1150184Y-208005D01*
X1150621Y-205964D01*
X1150184Y-203922D01*
X1148874Y-202172D01*
X1147345Y-201589D01*
X1140577D01*
G01X1105140Y-148422D02*
X1110599Y-165922D01*
X1116058Y-148422D01*
G01X1132466Y-165922D02*
X1123732D01*
Y-148422D01*
X1132466D01*
G01X1128972Y-156880D02*
X1123732D01*
G01X1141232Y-165922D02*
Y-148422D01*
X1146691D01*
X1148437Y-149297D01*
X1149529Y-150464D01*
X1149966Y-152797D01*
X1149529Y-155131D01*
X1148219Y-156589D01*
X1146691Y-157464D01*
X1141232D01*
G01X1146691D02*
X1149966Y-165922D01*
G01X1163099Y-166505D02*
X1162662Y-166214D01*
Y-165630D01*
X1163099Y-165339D01*
X1163536Y-165630D01*
Y-166214D01*
X1163099Y-166505D01*
G01X1311303Y-201589D02*
X1310429Y-200714D01*
X1309774Y-199256D01*
X1309337Y-197213D01*
X1309774Y-195464D01*
X1310647Y-194297D01*
X1312176Y-193422D01*
X1318071D01*
Y-210922D01*
X1310866D01*
X1309337Y-209756D01*
X1308464Y-208005D01*
X1308027Y-205964D01*
X1308464Y-203922D01*
X1309774Y-202172D01*
X1311303Y-201589D01*
X1318071D01*
G01X1300134Y-208589D02*
X1298387Y-210047D01*
X1296422Y-210922D01*
X1294676D01*
X1292929Y-210047D01*
X1291619Y-208589D01*
X1290964Y-206547D01*
X1291401Y-204506D01*
X1292492Y-202755D01*
X1294457Y-201589D01*
X1297077Y-201005D01*
X1298606Y-199839D01*
X1299261Y-197797D01*
X1298824Y-195755D01*
X1297732Y-194297D01*
X1296204Y-193422D01*
X1294676D01*
X1293147Y-194005D01*
X1291837Y-195464D01*
G01X1280669Y-193422D02*
X1275429D01*
G01X1278049D02*
Y-210922D01*
G01X1280669D02*
X1275429D01*
G01X1264916Y-193422D02*
Y-210922D01*
X1256182D01*
G01X1247852D02*
Y-193422D01*
G01X1239556D02*
X1247852Y-204214D01*
G01X1238246Y-210922D02*
X1244141Y-199256D01*
G01X1238682Y-148422D02*
Y-165922D01*
X1247416D01*
G01X1264479D02*
Y-154256D01*
G01Y-156297D02*
X1263606Y-155131D01*
X1262295Y-154547D01*
X1260767Y-154256D01*
X1259239Y-154839D01*
X1257929Y-156005D01*
X1257055Y-157755D01*
X1256619Y-160089D01*
X1257055Y-162422D01*
X1257929Y-164172D01*
X1259239Y-165339D01*
X1260767Y-165922D01*
X1262295Y-165630D01*
X1263606Y-164756D01*
X1264479Y-163589D01*
G01X1273464Y-171172D02*
X1274774Y-171755D01*
X1276521Y-171172D01*
X1277612Y-170006D01*
X1278486Y-168547D01*
X1279795Y-163881D01*
X1282634Y-154256D01*
G01X1275647D02*
X1279795Y-163881D01*
G01X1292274Y-158047D02*
X1299261D01*
X1298606Y-156005D01*
X1297514Y-154839D01*
X1295986Y-154256D01*
X1294457Y-154547D01*
X1293147Y-155422D01*
X1292274Y-157464D01*
X1291837Y-159214D01*
Y-160964D01*
X1292274Y-162714D01*
X1293366Y-164464D01*
X1294676Y-165630D01*
X1296204Y-165922D01*
X1297732Y-165339D01*
X1299261Y-163589D01*
G01X1309992Y-165922D02*
Y-154256D01*
G01Y-156589D02*
X1311084Y-155422D01*
X1312176Y-154547D01*
X1313704Y-154256D01*
X1314795Y-154547D01*
X1316106Y-155422D01*
G01X1380796Y-165922D02*
Y-148422D01*
X1385162D01*
X1386909Y-149297D01*
X1388219Y-150464D01*
X1389311Y-152213D01*
X1390184Y-154256D01*
X1390402Y-157172D01*
X1390184Y-160089D01*
X1389311Y-162131D01*
X1388219Y-163881D01*
X1386909Y-165047D01*
X1385162Y-165922D01*
X1380796D01*
G01X1399824Y-158047D02*
X1406811D01*
X1406156Y-156005D01*
X1405064Y-154839D01*
X1403536Y-154256D01*
X1402007Y-154547D01*
X1400697Y-155422D01*
X1399824Y-157464D01*
X1399387Y-159214D01*
Y-160964D01*
X1399824Y-162714D01*
X1400916Y-164464D01*
X1402226Y-165630D01*
X1403754Y-165922D01*
X1405282Y-165339D01*
X1406811Y-163589D01*
G01X1417324Y-163881D02*
X1418416Y-165047D01*
X1419944Y-165922D01*
X1421254D01*
X1422564Y-165339D01*
X1423437Y-164464D01*
X1423874Y-163298D01*
X1423656Y-161547D01*
X1422782Y-160672D01*
X1418852Y-158922D01*
X1417979Y-156880D01*
X1418416Y-155422D01*
X1419289Y-154547D01*
X1420599Y-154256D01*
X1421909Y-154547D01*
X1423219Y-155422D01*
G01X1438099Y-154256D02*
Y-165922D01*
G01Y-149589D02*
X1437662Y-149297D01*
Y-148714D01*
X1438099Y-148422D01*
X1438536Y-148714D01*
Y-149297D01*
X1438099Y-149589D01*
G01X1452542Y-170297D02*
X1454071Y-171464D01*
X1455817Y-171755D01*
X1457345Y-171464D01*
X1458656Y-170006D01*
X1459529Y-167964D01*
Y-154256D01*
G01Y-156589D02*
X1458656Y-155422D01*
X1457345Y-154547D01*
X1455817Y-154256D01*
X1454071Y-154839D01*
X1452979Y-156005D01*
X1452105Y-158047D01*
X1451669Y-160089D01*
X1451887Y-161839D01*
X1452761Y-163881D01*
X1454071Y-165339D01*
X1455817Y-165922D01*
X1457127Y-165630D01*
X1458656Y-164464D01*
X1459529Y-163298D01*
G01X1469387Y-165922D02*
Y-154256D01*
G01Y-157172D02*
X1470261Y-155714D01*
X1471571Y-154547D01*
X1473317Y-154256D01*
X1474845Y-154547D01*
X1476156Y-155714D01*
X1476811Y-157755D01*
Y-165922D01*
G01X1487324Y-158047D02*
X1494311D01*
X1493656Y-156005D01*
X1492564Y-154839D01*
X1491036Y-154256D01*
X1489507Y-154547D01*
X1488197Y-155422D01*
X1487324Y-157464D01*
X1486887Y-159214D01*
Y-160964D01*
X1487324Y-162714D01*
X1488416Y-164464D01*
X1489726Y-165630D01*
X1491254Y-165922D01*
X1492782Y-165339D01*
X1494311Y-163589D01*
G01X1505042Y-165922D02*
Y-154256D01*
G01Y-156589D02*
X1506134Y-155422D01*
X1507226Y-154547D01*
X1508754Y-154256D01*
X1509845Y-154547D01*
X1511156Y-155422D01*
G01X1426729Y-193422D02*
X1431969D01*
G01X1429349D02*
Y-210922D01*
G01X1426729D02*
X1431969D01*
G01X1441390Y-193422D02*
X1446849Y-210922D01*
X1452308Y-193422D01*
G01X1464349Y-210922D02*
Y-203047D01*
X1459982Y-193422D01*
G01X1468716D02*
X1464349Y-203047D01*
G01X1551799Y-193422D02*
X1550052Y-194005D01*
X1548742Y-195464D01*
X1547869Y-197213D01*
X1547214Y-199547D01*
X1546996Y-202172D01*
X1547214Y-204797D01*
X1547869Y-207131D01*
X1548742Y-208881D01*
X1550052Y-210339D01*
X1551799Y-210922D01*
X1553545Y-210339D01*
X1554856Y-208881D01*
X1555729Y-207131D01*
X1556384Y-204797D01*
X1556602Y-202172D01*
X1556384Y-199547D01*
X1555729Y-197213D01*
X1554856Y-195464D01*
X1553545Y-194005D01*
X1551799Y-193422D01*
G01X1565151Y-196339D02*
X1566461Y-194589D01*
X1567989Y-193714D01*
X1569736Y-193422D01*
X1571919Y-194005D01*
X1573447Y-195464D01*
X1573884Y-197213D01*
X1573666Y-198964D01*
X1572792Y-200422D01*
X1568426Y-203339D01*
X1566461Y-205380D01*
X1565151Y-208298D01*
X1564714Y-210922D01*
X1573884D01*
G01X1582869Y-211505D02*
X1590729Y-193422D01*
G01X1604299Y-210922D02*
Y-193422D01*
X1601679Y-196922D01*
G01Y-210922D02*
X1606919D01*
G01X1621799Y-193422D02*
X1620052Y-194005D01*
X1618742Y-195464D01*
X1617869Y-197213D01*
X1617214Y-199547D01*
X1616996Y-202172D01*
X1617214Y-204797D01*
X1617869Y-207131D01*
X1618742Y-208881D01*
X1620052Y-210339D01*
X1621799Y-210922D01*
X1623545Y-210339D01*
X1624856Y-208881D01*
X1625729Y-207131D01*
X1626384Y-204797D01*
X1626602Y-202172D01*
X1626384Y-199547D01*
X1625729Y-197213D01*
X1624856Y-195464D01*
X1623545Y-194005D01*
X1621799Y-193422D01*
G01X1635369Y-211505D02*
X1643229Y-193422D01*
G01X1652651Y-196339D02*
X1653961Y-194589D01*
X1655489Y-193714D01*
X1657236Y-193422D01*
X1659419Y-194005D01*
X1660947Y-195464D01*
X1661384Y-197213D01*
X1661166Y-198964D01*
X1660292Y-200422D01*
X1655926Y-203339D01*
X1653961Y-205380D01*
X1652651Y-208298D01*
X1652214Y-210922D01*
X1661384D01*
G01X1674299Y-193422D02*
X1672552Y-194005D01*
X1671242Y-195464D01*
X1670369Y-197213D01*
X1669714Y-199547D01*
X1669496Y-202172D01*
X1669714Y-204797D01*
X1670369Y-207131D01*
X1671242Y-208881D01*
X1672552Y-210339D01*
X1674299Y-210922D01*
X1676045Y-210339D01*
X1677356Y-208881D01*
X1678229Y-207131D01*
X1678884Y-204797D01*
X1679102Y-202172D01*
X1678884Y-199547D01*
X1678229Y-197213D01*
X1677356Y-195464D01*
X1676045Y-194005D01*
X1674299Y-193422D01*
G01X1691799Y-210922D02*
Y-193422D01*
X1689179Y-196922D01*
G01Y-210922D02*
X1694419D01*
G01X1708862D02*
X1709299Y-207131D01*
X1709954Y-203922D01*
X1710827Y-201005D01*
X1711919Y-197797D01*
X1713666Y-193422D01*
X1704932D01*
G01X1599496Y-165922D02*
Y-148422D01*
X1603862D01*
X1605609Y-149297D01*
X1606919Y-150464D01*
X1608011Y-152213D01*
X1608884Y-154256D01*
X1609102Y-157172D01*
X1608884Y-160089D01*
X1608011Y-162131D01*
X1606919Y-163881D01*
X1605609Y-165047D01*
X1603862Y-165922D01*
X1599496D01*
G01X1625729D02*
Y-154256D01*
G01Y-156297D02*
X1624856Y-155131D01*
X1623545Y-154547D01*
X1622017Y-154256D01*
X1620489Y-154839D01*
X1619179Y-156005D01*
X1618305Y-157755D01*
X1617869Y-160089D01*
X1618305Y-162422D01*
X1619179Y-164172D01*
X1620489Y-165339D01*
X1622017Y-165922D01*
X1623545Y-165630D01*
X1624856Y-164756D01*
X1625729Y-163589D01*
G01X1639299Y-148422D02*
Y-165922D01*
G01X1636242Y-154256D02*
X1642356D01*
G01X1653524Y-158047D02*
X1660511D01*
X1659856Y-156005D01*
X1658764Y-154839D01*
X1657236Y-154256D01*
X1655707Y-154547D01*
X1654397Y-155422D01*
X1653524Y-157464D01*
X1653087Y-159214D01*
Y-160964D01*
X1653524Y-162714D01*
X1654616Y-164464D01*
X1655926Y-165630D01*
X1657454Y-165922D01*
X1658982Y-165339D01*
X1660511Y-163589D01*
G01X-6876Y20752D02*
X-6626Y20877D01*
X-6334Y20960D01*
X-6001D01*
X-5626Y20835D01*
X-5334Y20627D01*
X-5126Y20377D01*
X-4959Y19960D01*
X-4917Y19585D01*
X-5001Y19210D01*
X-5126Y18960D01*
X-5376Y18710D01*
X-5667Y18543D01*
X-5959Y18460D01*
X-6251D01*
X-6542Y18543D01*
X-6792Y18668D01*
X-7001Y18835D01*
G01X-8267Y20543D02*
X-8517Y20793D01*
X-8809Y20918D01*
X-9142Y20960D01*
X-9559Y20877D01*
X-9851Y20668D01*
X-9934Y20418D01*
X-9892Y20168D01*
X-9726Y19960D01*
X-8892Y19543D01*
X-8517Y19252D01*
X-8267Y18835D01*
X-8184Y18460D01*
X-9934D01*
G01X-11367Y20543D02*
X-11617Y20793D01*
X-11909Y20918D01*
X-12242Y20960D01*
X-12659Y20877D01*
X-12951Y20668D01*
X-13034Y20418D01*
X-12992Y20168D01*
X-12826Y19960D01*
X-11992Y19543D01*
X-11617Y19252D01*
X-11367Y18835D01*
X-11284Y18460D01*
X-13034D01*
G01X-14009Y20960D02*
X-14592Y18460D01*
X-15259Y20960D01*
X-15926Y18460D01*
X-16509Y20960D01*
G01X-18359Y18460D02*
Y20960D01*
X-17859Y20460D01*
G01Y18460D02*
X-18859D01*
G01X-6639Y16486D02*
X-6389Y16611D01*
X-6097Y16694D01*
X-5764D01*
X-5389Y16569D01*
X-5097Y16361D01*
X-4889Y16111D01*
X-4722Y15694D01*
X-4680Y15319D01*
X-4764Y14944D01*
X-4889Y14694D01*
X-5139Y14444D01*
X-5430Y14277D01*
X-5722Y14194D01*
X-6014D01*
X-6305Y14277D01*
X-6555Y14402D01*
X-6764Y14569D01*
G01X-8030Y16277D02*
X-8280Y16527D01*
X-8572Y16652D01*
X-8905Y16694D01*
X-9322Y16611D01*
X-9614Y16402D01*
X-9697Y16152D01*
X-9655Y15902D01*
X-9489Y15694D01*
X-8655Y15277D01*
X-8280Y14986D01*
X-8030Y14569D01*
X-7947Y14194D01*
X-9697D01*
G01X-11130Y16277D02*
X-11380Y16527D01*
X-11672Y16652D01*
X-12005Y16694D01*
X-12422Y16611D01*
X-12714Y16402D01*
X-12797Y16152D01*
X-12755Y15902D01*
X-12589Y15694D01*
X-11755Y15277D01*
X-11380Y14986D01*
X-11130Y14569D01*
X-11047Y14194D01*
X-12797D01*
G01X-13772Y16694D02*
X-14355Y14194D01*
X-15022Y16694D01*
X-15689Y14194D01*
X-16272Y16694D01*
G01X-17330Y16277D02*
X-17580Y16527D01*
X-17872Y16652D01*
X-18205Y16694D01*
X-18622Y16611D01*
X-18914Y16402D01*
X-18997Y16152D01*
X-18955Y15902D01*
X-18789Y15694D01*
X-17955Y15277D01*
X-17580Y14986D01*
X-17330Y14569D01*
X-17247Y14194D01*
X-18997D01*
G01X-12157Y85692D02*
X-11907Y85817D01*
X-11615Y85900D01*
X-11282D01*
X-10907Y85775D01*
X-10615Y85567D01*
X-10407Y85317D01*
X-10240Y84900D01*
X-10198Y84525D01*
X-10282Y84150D01*
X-10407Y83900D01*
X-10657Y83650D01*
X-10948Y83483D01*
X-11240Y83400D01*
X-11532D01*
X-11823Y83483D01*
X-12073Y83608D01*
X-12282Y83775D01*
G01X-14340Y83400D02*
Y85900D01*
X-13840Y85400D01*
G01Y83400D02*
X-14840D01*
G01X-17690Y84650D02*
X-18523D01*
Y83900D01*
X-18273Y83650D01*
X-17982Y83483D01*
X-17565Y83400D01*
X-17148Y83483D01*
X-16857Y83650D01*
X-16607Y83900D01*
X-16440Y84192D01*
X-16357Y84525D01*
Y84817D01*
X-16440Y85067D01*
X-16607Y85358D01*
X-16857Y85608D01*
X-17107Y85775D01*
X-17440Y85900D01*
X-17732D01*
X-18065Y85817D01*
X-18315Y85650D01*
G01X-20457Y83400D02*
X-20540Y83942D01*
X-20665Y84400D01*
X-20832Y84817D01*
X-21040Y85275D01*
X-21373Y85900D01*
X-19707D01*
G01X20200Y263812D02*
Y258900D01*
X-19900D01*
Y290700D01*
X5300D01*
G01X-5017Y280363D02*
Y282863D01*
X-6058D01*
X-6392Y282738D01*
X-6600Y282571D01*
X-6683Y282238D01*
X-6600Y281905D01*
X-6350Y281696D01*
X-6058Y281571D01*
X-5017D01*
G01X-6058D02*
X-6683Y280363D01*
G01X-8242Y280655D02*
X-8533Y280446D01*
X-8867Y280363D01*
X-9200Y280446D01*
X-9492Y280696D01*
X-9700Y281071D01*
X-9783Y281446D01*
Y281905D01*
X-9700Y282280D01*
X-9492Y282613D01*
X-9242Y282780D01*
X-8950Y282863D01*
X-8617Y282780D01*
X-8367Y282613D01*
X-8200Y282363D01*
X-8117Y282030D01*
X-8200Y281738D01*
X-8408Y281446D01*
X-8658Y281280D01*
X-8950Y281238D01*
X-9283Y281321D01*
X-9533Y281530D01*
X-9783Y281905D01*
G01X-11217Y280363D02*
Y282863D01*
X-12217D01*
X-12550Y282738D01*
X-12800Y282446D01*
X-12883Y282113D01*
X-12800Y281780D01*
X-12592Y281530D01*
X-12217Y281405D01*
X-11217D01*
G01X-15067Y280363D02*
X-15150Y280905D01*
X-15275Y281363D01*
X-15442Y281780D01*
X-15650Y282238D01*
X-15983Y282863D01*
X-14317D01*
G01X-5017Y273363D02*
Y275863D01*
X-6058D01*
X-6392Y275738D01*
X-6600Y275571D01*
X-6683Y275238D01*
X-6600Y274905D01*
X-6350Y274696D01*
X-6058Y274571D01*
X-5017D01*
G01X-6058D02*
X-6683Y273363D01*
G01X-8242Y273655D02*
X-8533Y273446D01*
X-8867Y273363D01*
X-9200Y273446D01*
X-9492Y273696D01*
X-9700Y274071D01*
X-9783Y274446D01*
Y274905D01*
X-9700Y275280D01*
X-9492Y275613D01*
X-9242Y275780D01*
X-8950Y275863D01*
X-8617Y275780D01*
X-8367Y275613D01*
X-8200Y275363D01*
X-8117Y275030D01*
X-8200Y274738D01*
X-8408Y274446D01*
X-8658Y274280D01*
X-8950Y274238D01*
X-9283Y274321D01*
X-9533Y274530D01*
X-9783Y274905D01*
G01X-11217Y273363D02*
Y275863D01*
X-12217D01*
X-12550Y275738D01*
X-12800Y275446D01*
X-12883Y275113D01*
X-12800Y274780D01*
X-12592Y274530D01*
X-12217Y274405D01*
X-11217D01*
G01X-15150Y273363D02*
Y275863D01*
X-14650Y275363D01*
G01Y273363D02*
X-15650D01*
G01X-18250D02*
Y275863D01*
X-17750Y275363D01*
G01Y273363D02*
X-18750D01*
G01X-5017Y276863D02*
Y279363D01*
X-6058D01*
X-6392Y279238D01*
X-6600Y279071D01*
X-6683Y278738D01*
X-6600Y278405D01*
X-6350Y278196D01*
X-6058Y278071D01*
X-5017D01*
G01X-6058D02*
X-6683Y276863D01*
G01X-8242Y277155D02*
X-8533Y276946D01*
X-8867Y276863D01*
X-9200Y276946D01*
X-9492Y277196D01*
X-9700Y277571D01*
X-9783Y277946D01*
Y278405D01*
X-9700Y278780D01*
X-9492Y279113D01*
X-9242Y279280D01*
X-8950Y279363D01*
X-8617Y279280D01*
X-8367Y279113D01*
X-8200Y278863D01*
X-8117Y278530D01*
X-8200Y278238D01*
X-8408Y277946D01*
X-8658Y277780D01*
X-8950Y277738D01*
X-9283Y277821D01*
X-9533Y278030D01*
X-9783Y278405D01*
G01X-11217Y276863D02*
Y279363D01*
X-12217D01*
X-12550Y279238D01*
X-12800Y278946D01*
X-12883Y278613D01*
X-12800Y278280D01*
X-12592Y278030D01*
X-12217Y277905D01*
X-11217D01*
G01X-14442Y277155D02*
X-14733Y276946D01*
X-15067Y276863D01*
X-15400Y276946D01*
X-15692Y277196D01*
X-15900Y277571D01*
X-15983Y277946D01*
Y278405D01*
X-15900Y278780D01*
X-15692Y279113D01*
X-15442Y279280D01*
X-15150Y279363D01*
X-14817Y279280D01*
X-14567Y279113D01*
X-14400Y278863D01*
X-14317Y278530D01*
X-14400Y278238D01*
X-14608Y277946D01*
X-14858Y277780D01*
X-15150Y277738D01*
X-15483Y277821D01*
X-15733Y278030D01*
X-15983Y278405D01*
G01X-8767Y266492D02*
X-8517Y266617D01*
X-8225Y266700D01*
X-7892D01*
X-7517Y266575D01*
X-7225Y266367D01*
X-7017Y266117D01*
X-6850Y265700D01*
X-6808Y265325D01*
X-6892Y264950D01*
X-7017Y264700D01*
X-7267Y264450D01*
X-7558Y264283D01*
X-7850Y264200D01*
X-8142D01*
X-8433Y264283D01*
X-8683Y264408D01*
X-8892Y264575D01*
G01X-10242Y264492D02*
X-10533Y264283D01*
X-10867Y264200D01*
X-11200Y264283D01*
X-11492Y264533D01*
X-11700Y264908D01*
X-11783Y265283D01*
Y265742D01*
X-11700Y266117D01*
X-11492Y266450D01*
X-11242Y266617D01*
X-10950Y266700D01*
X-10617Y266617D01*
X-10367Y266450D01*
X-10200Y266200D01*
X-10117Y265867D01*
X-10200Y265575D01*
X-10408Y265283D01*
X-10658Y265117D01*
X-10950Y265075D01*
X-11283Y265158D01*
X-11533Y265367D01*
X-11783Y265742D01*
G01X-13217Y264200D02*
Y266700D01*
X-14217D01*
X-14550Y266575D01*
X-14800Y266283D01*
X-14883Y265950D01*
X-14800Y265617D01*
X-14592Y265367D01*
X-14217Y265242D01*
X-13217D01*
G01X-16358D02*
X-16650Y265533D01*
X-16900Y265700D01*
X-17233Y265783D01*
X-17525Y265700D01*
X-17733Y265533D01*
X-17900Y265283D01*
X-17942Y264992D01*
X-17900Y264742D01*
X-17733Y264492D01*
X-17483Y264283D01*
X-17192Y264200D01*
X-16858Y264283D01*
X-16567Y264533D01*
X-16400Y264908D01*
X-16358Y265325D01*
X-16442Y265867D01*
X-16567Y266158D01*
X-16775Y266450D01*
X-17067Y266658D01*
X-17358Y266700D01*
X-17650Y266617D01*
X-17858Y266408D01*
G01X-3611Y444557D02*
X-3361Y444682D01*
X-3069Y444765D01*
X-2736D01*
X-2361Y444640D01*
X-2069Y444432D01*
X-1861Y444182D01*
X-1694Y443765D01*
X-1652Y443390D01*
X-1736Y443015D01*
X-1861Y442765D01*
X-2111Y442515D01*
X-2402Y442348D01*
X-2694Y442265D01*
X-2986D01*
X-3277Y442348D01*
X-3527Y442473D01*
X-3736Y442640D01*
G01X-5086Y442557D02*
X-5377Y442348D01*
X-5711Y442265D01*
X-6044Y442348D01*
X-6336Y442598D01*
X-6544Y442973D01*
X-6627Y443348D01*
Y443807D01*
X-6544Y444182D01*
X-6336Y444515D01*
X-6086Y444682D01*
X-5794Y444765D01*
X-5461Y444682D01*
X-5211Y444515D01*
X-5044Y444265D01*
X-4961Y443932D01*
X-5044Y443640D01*
X-5252Y443348D01*
X-5502Y443182D01*
X-5794Y443140D01*
X-6127Y443223D01*
X-6377Y443432D01*
X-6627Y443807D01*
G01X-7811Y442265D02*
Y444765D01*
X-8894Y442682D01*
X-9977Y444765D01*
Y442265D01*
G01X-11994D02*
Y444765D01*
X-11494Y444265D01*
G01Y442265D02*
X-12494D01*
G01X-15094Y444765D02*
X-14761Y444682D01*
X-14511Y444473D01*
X-14344Y444223D01*
X-14219Y443890D01*
X-14177Y443515D01*
X-14219Y443140D01*
X-14344Y442807D01*
X-14511Y442557D01*
X-14761Y442348D01*
X-15094Y442265D01*
X-15427Y442348D01*
X-15677Y442557D01*
X-15844Y442807D01*
X-15969Y443140D01*
X-16011Y443515D01*
X-15969Y443890D01*
X-15844Y444223D01*
X-15677Y444473D01*
X-15427Y444682D01*
X-15094Y444765D01*
G01X-18704Y451404D02*
X-16204D01*
Y452445D01*
X-16329Y452779D01*
X-16496Y452987D01*
X-16829Y453070D01*
X-17162Y452987D01*
X-17371Y452737D01*
X-17496Y452445D01*
Y451404D01*
G01Y452445D02*
X-18704Y453070D01*
G01X-18412Y454629D02*
X-18621Y454920D01*
X-18704Y455254D01*
X-18621Y455587D01*
X-18371Y455879D01*
X-17996Y456087D01*
X-17621Y456170D01*
X-17162D01*
X-16787Y456087D01*
X-16454Y455879D01*
X-16287Y455629D01*
X-16204Y455337D01*
X-16287Y455004D01*
X-16454Y454754D01*
X-16704Y454587D01*
X-17037Y454504D01*
X-17329Y454587D01*
X-17621Y454795D01*
X-17787Y455045D01*
X-17829Y455337D01*
X-17746Y455670D01*
X-17537Y455920D01*
X-17162Y456170D01*
G01X-18704Y457354D02*
X-16204D01*
X-18287Y458437D01*
X-16204Y459520D01*
X-18704D01*
G01Y461537D02*
X-16204D01*
X-16704Y461037D01*
G01X-18704D02*
Y462037D01*
G01Y464637D02*
X-18662Y464929D01*
X-18537Y465262D01*
X-18329Y465470D01*
X-18037Y465554D01*
X-17746Y465470D01*
X-17496Y465220D01*
X-17371Y464845D01*
Y464429D01*
X-17287Y464179D01*
X-17079Y463970D01*
X-16787Y463887D01*
X-16496Y464012D01*
X-16287Y464304D01*
X-16204Y464637D01*
X-16287Y464970D01*
X-16496Y465262D01*
X-16787Y465387D01*
X-17079Y465304D01*
X-17287Y465095D01*
X-17371Y464845D01*
Y464429D01*
X-17496Y464054D01*
X-17746Y463804D01*
X-18037Y463720D01*
X-18329Y463804D01*
X-18537Y464012D01*
X-18662Y464345D01*
X-18704Y464637D01*
G01X-22204Y451404D02*
X-19704D01*
Y452445D01*
X-19829Y452779D01*
X-19996Y452987D01*
X-20329Y453070D01*
X-20662Y452987D01*
X-20871Y452737D01*
X-20996Y452445D01*
Y451404D01*
G01Y452445D02*
X-22204Y453070D01*
G01X-21912Y454629D02*
X-22121Y454920D01*
X-22204Y455254D01*
X-22121Y455587D01*
X-21871Y455879D01*
X-21496Y456087D01*
X-21121Y456170D01*
X-20662D01*
X-20287Y456087D01*
X-19954Y455879D01*
X-19787Y455629D01*
X-19704Y455337D01*
X-19787Y455004D01*
X-19954Y454754D01*
X-20204Y454587D01*
X-20537Y454504D01*
X-20829Y454587D01*
X-21121Y454795D01*
X-21287Y455045D01*
X-21329Y455337D01*
X-21246Y455670D01*
X-21037Y455920D01*
X-20662Y456170D01*
G01X-22204Y457354D02*
X-19704D01*
X-21787Y458437D01*
X-19704Y459520D01*
X-22204D01*
G01Y461537D02*
X-19704D01*
X-20204Y461037D01*
G01X-22204D02*
Y462037D01*
G01X-21912Y463929D02*
X-22121Y464220D01*
X-22204Y464554D01*
X-22121Y464887D01*
X-21871Y465179D01*
X-21496Y465387D01*
X-21121Y465470D01*
X-20662D01*
X-20287Y465387D01*
X-19954Y465179D01*
X-19787Y464929D01*
X-19704Y464637D01*
X-19787Y464304D01*
X-19954Y464054D01*
X-20204Y463887D01*
X-20537Y463804D01*
X-20829Y463887D01*
X-21121Y464095D01*
X-21287Y464345D01*
X-21329Y464637D01*
X-21246Y464970D01*
X-21037Y465220D01*
X-20662Y465470D01*
G01X-17800Y481667D02*
X-15300D01*
Y482708D01*
X-15425Y483042D01*
X-15592Y483250D01*
X-15925Y483333D01*
X-16258Y483250D01*
X-16467Y483000D01*
X-16592Y482708D01*
Y481667D01*
G01Y482708D02*
X-17800Y483333D01*
G01X-17508Y484892D02*
X-17717Y485183D01*
X-17800Y485517D01*
X-17717Y485850D01*
X-17467Y486142D01*
X-17092Y486350D01*
X-16717Y486433D01*
X-16258D01*
X-15883Y486350D01*
X-15550Y486142D01*
X-15383Y485892D01*
X-15300Y485600D01*
X-15383Y485267D01*
X-15550Y485017D01*
X-15800Y484850D01*
X-16133Y484767D01*
X-16425Y484850D01*
X-16717Y485058D01*
X-16883Y485308D01*
X-16925Y485600D01*
X-16842Y485933D01*
X-16633Y486183D01*
X-16258Y486433D01*
G01X-17800Y487617D02*
X-15300D01*
X-17383Y488700D01*
X-15300Y489783D01*
X-17800D01*
G01Y491800D02*
X-15300D01*
X-15800Y491300D01*
G01X-17800D02*
Y492300D01*
G01Y495400D02*
X-15300D01*
X-17092Y493858D01*
Y495942D01*
G01X-19353Y469629D02*
X-19228Y469379D01*
X-19145Y469087D01*
Y468754D01*
X-19270Y468379D01*
X-19478Y468087D01*
X-19728Y467879D01*
X-20145Y467712D01*
X-20520Y467670D01*
X-20895Y467754D01*
X-21145Y467879D01*
X-21395Y468129D01*
X-21562Y468420D01*
X-21645Y468712D01*
Y469004D01*
X-21562Y469295D01*
X-21437Y469545D01*
X-21270Y469754D01*
G01X-21353Y471104D02*
X-21562Y471395D01*
X-21645Y471729D01*
X-21562Y472062D01*
X-21312Y472354D01*
X-20937Y472562D01*
X-20562Y472645D01*
X-20103D01*
X-19728Y472562D01*
X-19395Y472354D01*
X-19228Y472104D01*
X-19145Y471812D01*
X-19228Y471479D01*
X-19395Y471229D01*
X-19645Y471062D01*
X-19978Y470979D01*
X-20270Y471062D01*
X-20562Y471270D01*
X-20728Y471520D01*
X-20770Y471812D01*
X-20687Y472145D01*
X-20478Y472395D01*
X-20103Y472645D01*
G01X-21645Y473829D02*
X-19145D01*
X-21228Y474912D01*
X-19145Y475995D01*
X-21645D01*
G01Y477929D02*
X-21103Y478012D01*
X-20645Y478137D01*
X-20228Y478304D01*
X-19770Y478512D01*
X-19145Y478845D01*
Y477179D01*
G01X28379Y7793D02*
X28629Y7918D01*
X28921Y8001D01*
X29254D01*
X29629Y7876D01*
X29921Y7668D01*
X30129Y7418D01*
X30296Y7001D01*
X30338Y6626D01*
X30254Y6251D01*
X30129Y6001D01*
X29879Y5751D01*
X29588Y5584D01*
X29296Y5501D01*
X29004D01*
X28713Y5584D01*
X28463Y5709D01*
X28254Y5876D01*
G01X26904Y5793D02*
X26613Y5584D01*
X26279Y5501D01*
X25946Y5584D01*
X25654Y5834D01*
X25446Y6209D01*
X25363Y6584D01*
Y7043D01*
X25446Y7418D01*
X25654Y7751D01*
X25904Y7918D01*
X26196Y8001D01*
X26529Y7918D01*
X26779Y7751D01*
X26946Y7501D01*
X27029Y7168D01*
X26946Y6876D01*
X26738Y6584D01*
X26488Y6418D01*
X26196Y6376D01*
X25863Y6459D01*
X25613Y6668D01*
X25363Y7043D01*
G01X24013Y8001D02*
Y6209D01*
X23846Y5834D01*
X23513Y5584D01*
X23096Y5501D01*
X22679Y5584D01*
X22346Y5834D01*
X22179Y6209D01*
Y8001D01*
G01X20788Y6543D02*
X20496Y6834D01*
X20246Y7001D01*
X19913Y7084D01*
X19621Y7001D01*
X19413Y6834D01*
X19246Y6584D01*
X19204Y6293D01*
X19246Y6043D01*
X19413Y5793D01*
X19663Y5584D01*
X19954Y5501D01*
X20288Y5584D01*
X20579Y5834D01*
X20746Y6209D01*
X20788Y6626D01*
X20704Y7168D01*
X20579Y7459D01*
X20371Y7751D01*
X20079Y7959D01*
X19788Y8001D01*
X19496Y7918D01*
X19288Y7709D01*
G01X28379Y11923D02*
X28629Y12048D01*
X28921Y12131D01*
X29254D01*
X29629Y12006D01*
X29921Y11798D01*
X30129Y11548D01*
X30296Y11131D01*
X30338Y10756D01*
X30254Y10381D01*
X30129Y10131D01*
X29879Y9881D01*
X29588Y9714D01*
X29296Y9631D01*
X29004D01*
X28713Y9714D01*
X28463Y9839D01*
X28254Y10006D01*
G01X26904Y9923D02*
X26613Y9714D01*
X26279Y9631D01*
X25946Y9714D01*
X25654Y9964D01*
X25446Y10339D01*
X25363Y10714D01*
Y11173D01*
X25446Y11548D01*
X25654Y11881D01*
X25904Y12048D01*
X26196Y12131D01*
X26529Y12048D01*
X26779Y11881D01*
X26946Y11631D01*
X27029Y11298D01*
X26946Y11006D01*
X26738Y10714D01*
X26488Y10548D01*
X26196Y10506D01*
X25863Y10589D01*
X25613Y10798D01*
X25363Y11173D01*
G01X24013Y12131D02*
Y10339D01*
X23846Y9964D01*
X23513Y9714D01*
X23096Y9631D01*
X22679Y9714D01*
X22346Y9964D01*
X22179Y10339D01*
Y12131D01*
G01X19496Y9631D02*
Y12131D01*
X21038Y10339D01*
X18954D01*
G01X32209Y9624D02*
X34709D01*
Y10665D01*
X34584Y10999D01*
X34417Y11207D01*
X34084Y11290D01*
X33751Y11207D01*
X33542Y10957D01*
X33417Y10665D01*
Y9624D01*
G01Y10665D02*
X32209Y11290D01*
G01X32501Y12849D02*
X32292Y13140D01*
X32209Y13474D01*
X32292Y13807D01*
X32542Y14099D01*
X32917Y14307D01*
X33292Y14390D01*
X33751D01*
X34126Y14307D01*
X34459Y14099D01*
X34626Y13849D01*
X34709Y13557D01*
X34626Y13224D01*
X34459Y12974D01*
X34209Y12807D01*
X33876Y12724D01*
X33584Y12807D01*
X33292Y13015D01*
X33126Y13265D01*
X33084Y13557D01*
X33167Y13890D01*
X33376Y14140D01*
X33751Y14390D01*
G01X34709Y15740D02*
X32917D01*
X32542Y15907D01*
X32292Y16240D01*
X32209Y16657D01*
X32292Y17074D01*
X32542Y17407D01*
X32917Y17574D01*
X34709D01*
G01X32709Y18840D02*
X32417Y19090D01*
X32251Y19424D01*
X32209Y19799D01*
X32251Y20132D01*
X32459Y20465D01*
X32709Y20674D01*
X32959Y20715D01*
X33251Y20632D01*
X33459Y20340D01*
X33542Y20049D01*
Y19674D01*
G01Y20049D02*
X33667Y20299D01*
X33876Y20507D01*
X34126Y20590D01*
X34376Y20507D01*
X34584Y20299D01*
X34709Y19924D01*
X34667Y19549D01*
X34501Y19174D01*
G01X36148Y6866D02*
X38648D01*
Y7907D01*
X38523Y8241D01*
X38356Y8449D01*
X38023Y8532D01*
X37690Y8449D01*
X37481Y8199D01*
X37356Y7907D01*
Y6866D01*
G01Y7907D02*
X36148Y8532D01*
G01X36440Y10091D02*
X36231Y10382D01*
X36148Y10716D01*
X36231Y11049D01*
X36481Y11341D01*
X36856Y11549D01*
X37231Y11632D01*
X37690D01*
X38065Y11549D01*
X38398Y11341D01*
X38565Y11091D01*
X38648Y10799D01*
X38565Y10466D01*
X38398Y10216D01*
X38148Y10049D01*
X37815Y9966D01*
X37523Y10049D01*
X37231Y10257D01*
X37065Y10507D01*
X37023Y10799D01*
X37106Y11132D01*
X37315Y11382D01*
X37690Y11632D01*
G01X38648Y12982D02*
X36856D01*
X36481Y13149D01*
X36231Y13482D01*
X36148Y13899D01*
X36231Y14316D01*
X36481Y14649D01*
X36856Y14816D01*
X38648D01*
G01X36148Y17499D02*
X38648D01*
X36856Y15957D01*
Y18041D01*
G01X24493Y13040D02*
Y15540D01*
X23452D01*
X23118Y15415D01*
X22910Y15248D01*
X22827Y14915D01*
X22910Y14582D01*
X23160Y14373D01*
X23452Y14248D01*
X24493D01*
G01X23452D02*
X22827Y13040D01*
G01X21268Y13332D02*
X20977Y13123D01*
X20643Y13040D01*
X20310Y13123D01*
X20018Y13373D01*
X19810Y13748D01*
X19727Y14123D01*
Y14582D01*
X19810Y14957D01*
X20018Y15290D01*
X20268Y15457D01*
X20560Y15540D01*
X20893Y15457D01*
X21143Y15290D01*
X21310Y15040D01*
X21393Y14707D01*
X21310Y14415D01*
X21102Y14123D01*
X20852Y13957D01*
X20560Y13915D01*
X20227Y13998D01*
X19977Y14207D01*
X19727Y14582D01*
G01X18377Y15540D02*
Y13748D01*
X18210Y13373D01*
X17877Y13123D01*
X17460Y13040D01*
X17043Y13123D01*
X16710Y13373D01*
X16543Y13748D01*
Y15540D01*
G01X14360Y13040D02*
Y15540D01*
X14860Y15040D01*
G01Y13040D02*
X13860D01*
G01X10579Y18114D02*
X10829Y18239D01*
X11121Y18322D01*
X11454D01*
X11829Y18197D01*
X12121Y17989D01*
X12329Y17739D01*
X12496Y17322D01*
X12538Y16947D01*
X12454Y16572D01*
X12329Y16322D01*
X12079Y16072D01*
X11788Y15905D01*
X11496Y15822D01*
X11204D01*
X10913Y15905D01*
X10663Y16030D01*
X10454Y16197D01*
G01X8396Y18322D02*
Y15822D01*
G01X9354Y18322D02*
X7438D01*
G01X6213Y16322D02*
X5963Y16030D01*
X5629Y15864D01*
X5254Y15822D01*
X4921Y15864D01*
X4588Y16072D01*
X4379Y16322D01*
X4338Y16572D01*
X4421Y16864D01*
X4713Y17072D01*
X5004Y17155D01*
X5379D01*
G01X5004D02*
X4754Y17280D01*
X4546Y17489D01*
X4463Y17739D01*
X4546Y17989D01*
X4754Y18197D01*
X5129Y18322D01*
X5504Y18280D01*
X5879Y18114D01*
G01X2196Y18322D02*
X2529Y18239D01*
X2779Y18030D01*
X2946Y17780D01*
X3071Y17447D01*
X3113Y17072D01*
X3071Y16697D01*
X2946Y16364D01*
X2779Y16114D01*
X2529Y15905D01*
X2196Y15822D01*
X1863Y15905D01*
X1613Y16114D01*
X1446Y16364D01*
X1321Y16697D01*
X1279Y17072D01*
X1321Y17447D01*
X1446Y17780D01*
X1613Y18030D01*
X1863Y18239D01*
X2196Y18322D01*
G01X41800Y26300D02*
X64372D01*
G01X41800D02*
Y28995D01*
G01X30307Y4263D02*
X30557Y4388D01*
X30849Y4471D01*
X31182D01*
X31557Y4346D01*
X31849Y4138D01*
X32057Y3888D01*
X32224Y3471D01*
X32266Y3096D01*
X32182Y2721D01*
X32057Y2471D01*
X31807Y2221D01*
X31516Y2054D01*
X31224Y1971D01*
X30932D01*
X30641Y2054D01*
X30391Y2179D01*
X30182Y2346D01*
G01X28124Y1971D02*
Y4471D01*
X28624Y3971D01*
G01Y1971D02*
X27624D01*
G01X24774Y3221D02*
X23941D01*
Y2471D01*
X24191Y2221D01*
X24482Y2054D01*
X24899Y1971D01*
X25316Y2054D01*
X25607Y2221D01*
X25857Y2471D01*
X26024Y2763D01*
X26107Y3096D01*
Y3388D01*
X26024Y3638D01*
X25857Y3929D01*
X25607Y4179D01*
X25357Y4346D01*
X25024Y4471D01*
X24732D01*
X24399Y4388D01*
X24149Y4221D01*
G01X21424Y1971D02*
Y4471D01*
X22966Y2679D01*
X20882D01*
G01X26445Y-19401D02*
X28945D01*
Y-18360D01*
X28820Y-18026D01*
X28653Y-17818D01*
X28320Y-17735D01*
X27987Y-17818D01*
X27778Y-18068D01*
X27653Y-18360D01*
Y-19401D01*
G01Y-18360D02*
X26445Y-17735D01*
G01Y-15468D02*
X28945D01*
X28445Y-15968D01*
G01X26445D02*
Y-14968D01*
G01X28528Y-13160D02*
X28778Y-12910D01*
X28903Y-12618D01*
X28945Y-12285D01*
X28862Y-11868D01*
X28653Y-11576D01*
X28403Y-11493D01*
X28153Y-11535D01*
X27945Y-11701D01*
X27528Y-12535D01*
X27237Y-12910D01*
X26820Y-13160D01*
X26445Y-13243D01*
Y-11493D01*
G01X28945Y-10518D02*
X26445Y-9935D01*
X28945Y-9268D01*
X26445Y-8601D01*
X28945Y-8018D01*
G01X26445Y-6168D02*
X28945D01*
X28445Y-6668D01*
G01X26445D02*
Y-5668D01*
G01Y-3068D02*
X28945D01*
X28445Y-3568D01*
G01X26445D02*
Y-2568D01*
G01X50277Y-19330D02*
X43277D01*
G01D02*
Y-10630D01*
G01Y-5930D02*
X50277D01*
G01X43277D02*
Y-11130D01*
G01X20780Y-16432D02*
X23280D01*
Y-15391D01*
X23155Y-15057D01*
X22988Y-14849D01*
X22655Y-14766D01*
X22322Y-14849D01*
X22113Y-15099D01*
X21988Y-15391D01*
Y-16432D01*
G01Y-15391D02*
X20780Y-14766D01*
G01Y-12499D02*
X23280D01*
X22780Y-12999D01*
G01X20780D02*
Y-11999D01*
G01X22863Y-10191D02*
X23113Y-9941D01*
X23238Y-9649D01*
X23280Y-9316D01*
X23197Y-8899D01*
X22988Y-8607D01*
X22738Y-8524D01*
X22488Y-8566D01*
X22280Y-8732D01*
X21863Y-9566D01*
X21572Y-9941D01*
X21155Y-10191D01*
X20780Y-10274D01*
Y-8524D01*
G01X23280Y-7549D02*
X20780Y-6966D01*
X23280Y-6299D01*
X20780Y-5632D01*
X23280Y-5049D01*
G01X20780Y-3199D02*
X23280D01*
X22780Y-3699D01*
G01X20780D02*
Y-2699D01*
G01X22863Y-891D02*
X23113Y-641D01*
X23238Y-349D01*
X23280Y-16D01*
X23197Y401D01*
X22988Y693D01*
X22738Y776D01*
X22488Y734D01*
X22280Y568D01*
X21863Y-266D01*
X21572Y-641D01*
X21155Y-891D01*
X20780Y-974D01*
Y776D01*
G01X39177Y-12930D02*
Y-19330D01*
G01D02*
X32177D01*
G01D02*
Y-10630D01*
G01Y-5930D02*
X39177D01*
G01D02*
Y-13730D01*
G01X32177Y-5930D02*
Y-11130D01*
G01X37643Y67892D02*
X37893Y68017D01*
X38185Y68100D01*
X38518D01*
X38893Y67975D01*
X39185Y67767D01*
X39393Y67517D01*
X39560Y67100D01*
X39602Y66725D01*
X39518Y66350D01*
X39393Y66100D01*
X39143Y65850D01*
X38852Y65683D01*
X38560Y65600D01*
X38268D01*
X37977Y65683D01*
X37727Y65808D01*
X37518Y65975D01*
G01X36168Y65892D02*
X35877Y65683D01*
X35543Y65600D01*
X35210Y65683D01*
X34918Y65933D01*
X34710Y66308D01*
X34627Y66683D01*
Y67142D01*
X34710Y67517D01*
X34918Y67850D01*
X35168Y68017D01*
X35460Y68100D01*
X35793Y68017D01*
X36043Y67850D01*
X36210Y67600D01*
X36293Y67267D01*
X36210Y66975D01*
X36002Y66683D01*
X35752Y66517D01*
X35460Y66475D01*
X35127Y66558D01*
X34877Y66767D01*
X34627Y67142D01*
G01X32360Y68100D02*
Y65600D01*
G01X33318Y68100D02*
X31402D01*
G01X29968Y65892D02*
X29677Y65683D01*
X29343Y65600D01*
X29010Y65683D01*
X28718Y65933D01*
X28510Y66308D01*
X28427Y66683D01*
Y67142D01*
X28510Y67517D01*
X28718Y67850D01*
X28968Y68017D01*
X29260Y68100D01*
X29593Y68017D01*
X29843Y67850D01*
X30010Y67600D01*
X30093Y67267D01*
X30010Y66975D01*
X29802Y66683D01*
X29552Y66517D01*
X29260Y66475D01*
X28927Y66558D01*
X28677Y66767D01*
X28427Y67142D01*
G01X22711Y86188D02*
X22961Y86313D01*
X23253Y86396D01*
X23586D01*
X23961Y86271D01*
X24253Y86063D01*
X24461Y85813D01*
X24628Y85396D01*
X24670Y85021D01*
X24586Y84646D01*
X24461Y84396D01*
X24211Y84146D01*
X23920Y83979D01*
X23628Y83896D01*
X23336D01*
X23045Y83979D01*
X22795Y84104D01*
X22586Y84271D01*
G01X21236Y84188D02*
X20945Y83979D01*
X20611Y83896D01*
X20278Y83979D01*
X19986Y84229D01*
X19778Y84604D01*
X19695Y84979D01*
Y85438D01*
X19778Y85813D01*
X19986Y86146D01*
X20236Y86313D01*
X20528Y86396D01*
X20861Y86313D01*
X21111Y86146D01*
X21278Y85896D01*
X21361Y85563D01*
X21278Y85271D01*
X21070Y84979D01*
X20820Y84813D01*
X20528Y84771D01*
X20195Y84854D01*
X19945Y85063D01*
X19695Y85438D01*
G01X17428Y86396D02*
Y83896D01*
G01X18386Y86396D02*
X16470D01*
G01X15120Y84938D02*
X14828Y85229D01*
X14578Y85396D01*
X14245Y85479D01*
X13953Y85396D01*
X13745Y85229D01*
X13578Y84979D01*
X13536Y84688D01*
X13578Y84438D01*
X13745Y84188D01*
X13995Y83979D01*
X14286Y83896D01*
X14620Y83979D01*
X14911Y84229D01*
X15078Y84604D01*
X15120Y85021D01*
X15036Y85563D01*
X14911Y85854D01*
X14703Y86146D01*
X14411Y86354D01*
X14120Y86396D01*
X13828Y86313D01*
X13620Y86104D01*
G01X22651Y89802D02*
X22901Y89927D01*
X23193Y90010D01*
X23526D01*
X23901Y89885D01*
X24193Y89677D01*
X24401Y89427D01*
X24568Y89010D01*
X24610Y88635D01*
X24526Y88260D01*
X24401Y88010D01*
X24151Y87760D01*
X23860Y87593D01*
X23568Y87510D01*
X23276D01*
X22985Y87593D01*
X22735Y87718D01*
X22526Y87885D01*
G01X21176Y87802D02*
X20885Y87593D01*
X20551Y87510D01*
X20218Y87593D01*
X19926Y87843D01*
X19718Y88218D01*
X19635Y88593D01*
Y89052D01*
X19718Y89427D01*
X19926Y89760D01*
X20176Y89927D01*
X20468Y90010D01*
X20801Y89927D01*
X21051Y89760D01*
X21218Y89510D01*
X21301Y89177D01*
X21218Y88885D01*
X21010Y88593D01*
X20760Y88427D01*
X20468Y88385D01*
X20135Y88468D01*
X19885Y88677D01*
X19635Y89052D01*
G01X17368Y90010D02*
Y87510D01*
G01X18326Y90010D02*
X16410D01*
G01X13768Y87510D02*
Y90010D01*
X15310Y88218D01*
X13226D01*
G01X37463Y45732D02*
X37713Y45857D01*
X38005Y45940D01*
X38338D01*
X38713Y45815D01*
X39005Y45607D01*
X39213Y45357D01*
X39380Y44940D01*
X39422Y44565D01*
X39338Y44190D01*
X39213Y43940D01*
X38963Y43690D01*
X38672Y43523D01*
X38380Y43440D01*
X38088D01*
X37797Y43523D01*
X37547Y43648D01*
X37338Y43815D01*
G01X35988Y43732D02*
X35697Y43523D01*
X35363Y43440D01*
X35030Y43523D01*
X34738Y43773D01*
X34530Y44148D01*
X34447Y44523D01*
Y44982D01*
X34530Y45357D01*
X34738Y45690D01*
X34988Y45857D01*
X35280Y45940D01*
X35613Y45857D01*
X35863Y45690D01*
X36030Y45440D01*
X36113Y45107D01*
X36030Y44815D01*
X35822Y44523D01*
X35572Y44357D01*
X35280Y44315D01*
X34947Y44398D01*
X34697Y44607D01*
X34447Y44982D01*
G01X33097Y45940D02*
Y44148D01*
X32930Y43773D01*
X32597Y43523D01*
X32180Y43440D01*
X31763Y43523D01*
X31430Y43773D01*
X31263Y44148D01*
Y45940D01*
G01X29997Y43940D02*
X29747Y43648D01*
X29413Y43482D01*
X29038Y43440D01*
X28705Y43482D01*
X28372Y43690D01*
X28163Y43940D01*
X28122Y44190D01*
X28205Y44482D01*
X28497Y44690D01*
X28788Y44773D01*
X29163D01*
G01X28788D02*
X28538Y44898D01*
X28330Y45107D01*
X28247Y45357D01*
X28330Y45607D01*
X28538Y45815D01*
X28913Y45940D01*
X29288Y45898D01*
X29663Y45732D01*
G01X11409Y58055D02*
Y60555D01*
X10368D01*
X10034Y60430D01*
X9826Y60263D01*
X9743Y59930D01*
X9826Y59597D01*
X10076Y59388D01*
X10368Y59263D01*
X11409D01*
G01X10368D02*
X9743Y58055D01*
G01X8184Y58347D02*
X7893Y58138D01*
X7559Y58055D01*
X7226Y58138D01*
X6934Y58388D01*
X6726Y58763D01*
X6643Y59138D01*
Y59597D01*
X6726Y59972D01*
X6934Y60305D01*
X7184Y60472D01*
X7476Y60555D01*
X7809Y60472D01*
X8059Y60305D01*
X8226Y60055D01*
X8309Y59722D01*
X8226Y59430D01*
X8018Y59138D01*
X7768Y58972D01*
X7476Y58930D01*
X7143Y59013D01*
X6893Y59222D01*
X6643Y59597D01*
G01X5293Y60555D02*
Y58763D01*
X5126Y58388D01*
X4793Y58138D01*
X4376Y58055D01*
X3959Y58138D01*
X3626Y58388D01*
X3459Y58763D01*
Y60555D01*
G01X1276Y58055D02*
Y60555D01*
X1776Y60055D01*
G01Y58055D02*
X776D01*
G01X-1032Y60138D02*
X-1282Y60388D01*
X-1574Y60513D01*
X-1907Y60555D01*
X-2324Y60472D01*
X-2616Y60263D01*
X-2699Y60013D01*
X-2657Y59763D01*
X-2491Y59555D01*
X-1657Y59138D01*
X-1282Y58847D01*
X-1032Y58430D01*
X-949Y58055D01*
X-2699D01*
G01X34383Y50792D02*
X34633Y50917D01*
X34925Y51000D01*
X35258D01*
X35633Y50875D01*
X35925Y50667D01*
X36133Y50417D01*
X36300Y50000D01*
X36342Y49625D01*
X36258Y49250D01*
X36133Y49000D01*
X35883Y48750D01*
X35592Y48583D01*
X35300Y48500D01*
X35008D01*
X34717Y48583D01*
X34467Y48708D01*
X34258Y48875D01*
G01X32200Y48500D02*
Y51000D01*
X32700Y50500D01*
G01Y48500D02*
X31700D01*
G01X28850Y49750D02*
X28017D01*
Y49000D01*
X28267Y48750D01*
X28558Y48583D01*
X28975Y48500D01*
X29392Y48583D01*
X29683Y48750D01*
X29933Y49000D01*
X30100Y49292D01*
X30183Y49625D01*
Y49917D01*
X30100Y50167D01*
X29933Y50458D01*
X29683Y50708D01*
X29433Y50875D01*
X29100Y51000D01*
X28808D01*
X28475Y50917D01*
X28225Y50750D01*
G01X26000Y48500D02*
Y51000D01*
X26500Y50500D01*
G01Y48500D02*
X25500D01*
G01X23817Y49000D02*
X23567Y48708D01*
X23233Y48542D01*
X22858Y48500D01*
X22525Y48542D01*
X22192Y48750D01*
X21983Y49000D01*
X21942Y49250D01*
X22025Y49542D01*
X22317Y49750D01*
X22608Y49833D01*
X22983D01*
G01X22608D02*
X22358Y49958D01*
X22150Y50167D01*
X22067Y50417D01*
X22150Y50667D01*
X22358Y50875D01*
X22733Y51000D01*
X23108Y50958D01*
X23483Y50792D01*
G01X7573Y38162D02*
X7823Y38287D01*
X8115Y38370D01*
X8448D01*
X8823Y38245D01*
X9115Y38037D01*
X9323Y37787D01*
X9490Y37370D01*
X9532Y36995D01*
X9448Y36620D01*
X9323Y36370D01*
X9073Y36120D01*
X8782Y35953D01*
X8490Y35870D01*
X8198D01*
X7907Y35953D01*
X7657Y36078D01*
X7448Y36245D01*
G01X5390Y38370D02*
Y35870D01*
G01X6348Y38370D02*
X4432D01*
G01X3082Y37953D02*
X2832Y38203D01*
X2540Y38328D01*
X2207Y38370D01*
X1790Y38287D01*
X1498Y38078D01*
X1415Y37828D01*
X1457Y37578D01*
X1623Y37370D01*
X2457Y36953D01*
X2832Y36662D01*
X3082Y36245D01*
X3165Y35870D01*
X1415D01*
G01X-810D02*
X-1102Y35912D01*
X-1435Y36037D01*
X-1643Y36245D01*
X-1727Y36537D01*
X-1643Y36828D01*
X-1393Y37078D01*
X-1018Y37203D01*
X-602D01*
X-352Y37287D01*
X-143Y37495D01*
X-60Y37787D01*
X-185Y38078D01*
X-477Y38287D01*
X-810Y38370D01*
X-1143Y38287D01*
X-1435Y38078D01*
X-1560Y37787D01*
X-1477Y37495D01*
X-1268Y37287D01*
X-1018Y37203D01*
X-602D01*
X-227Y37078D01*
X23Y36828D01*
X107Y36537D01*
X23Y36245D01*
X-185Y36037D01*
X-518Y35912D01*
X-810Y35870D01*
G01X403Y63822D02*
X653Y63947D01*
X945Y64030D01*
X1278D01*
X1653Y63905D01*
X1945Y63697D01*
X2153Y63447D01*
X2320Y63030D01*
X2362Y62655D01*
X2278Y62280D01*
X2153Y62030D01*
X1903Y61780D01*
X1612Y61613D01*
X1320Y61530D01*
X1028D01*
X737Y61613D01*
X487Y61738D01*
X278Y61905D01*
G01X-1780Y64030D02*
Y61530D01*
G01X-822Y64030D02*
X-2738D01*
G01X-3963Y62030D02*
X-4213Y61738D01*
X-4547Y61572D01*
X-4922Y61530D01*
X-5255Y61572D01*
X-5588Y61780D01*
X-5797Y62030D01*
X-5838Y62280D01*
X-5755Y62572D01*
X-5463Y62780D01*
X-5172Y62863D01*
X-4797D01*
G01X-5172D02*
X-5422Y62988D01*
X-5630Y63197D01*
X-5713Y63447D01*
X-5630Y63697D01*
X-5422Y63905D01*
X-5047Y64030D01*
X-4672Y63988D01*
X-4297Y63822D01*
G01X-7188Y63613D02*
X-7438Y63863D01*
X-7730Y63988D01*
X-8063Y64030D01*
X-8480Y63947D01*
X-8772Y63738D01*
X-8855Y63488D01*
X-8813Y63238D01*
X-8647Y63030D01*
X-7813Y62613D01*
X-7438Y62322D01*
X-7188Y61905D01*
X-7105Y61530D01*
X-8855D01*
G01X41800Y65300D02*
X64375D01*
G01X41800Y47300D02*
X64372D01*
G01X41800D02*
Y49995D01*
G01Y65300D02*
Y62602D01*
G01Y44300D02*
X64375D01*
G01X41800D02*
Y41602D01*
G01Y86300D02*
X64375D01*
G01X41800Y68300D02*
X64372D01*
G01X41800D02*
Y70995D01*
G01Y86300D02*
Y83602D01*
G01X34397Y54900D02*
X34647Y55025D01*
X34939Y55108D01*
X35272D01*
X35647Y54983D01*
X35939Y54775D01*
X36147Y54525D01*
X36314Y54108D01*
X36356Y53733D01*
X36272Y53358D01*
X36147Y53108D01*
X35897Y52858D01*
X35606Y52691D01*
X35314Y52608D01*
X35022D01*
X34731Y52691D01*
X34481Y52816D01*
X34272Y52983D01*
G01X32214Y52608D02*
Y55108D01*
X32714Y54608D01*
G01Y52608D02*
X31714D01*
G01X29906D02*
Y55108D01*
X28322D01*
G01X28906Y53900D02*
X29906D01*
G01X26806Y54691D02*
X26556Y54941D01*
X26264Y55066D01*
X25931Y55108D01*
X25514Y55025D01*
X25222Y54816D01*
X25139Y54566D01*
X25181Y54316D01*
X25347Y54108D01*
X26181Y53691D01*
X26556Y53400D01*
X26806Y52983D01*
X26889Y52608D01*
X25139D01*
G01X22914D02*
Y55108D01*
X23414Y54608D01*
G01Y52608D02*
X22414D01*
G01X7953Y45822D02*
X8203Y45947D01*
X8495Y46030D01*
X8828D01*
X9203Y45905D01*
X9495Y45697D01*
X9703Y45447D01*
X9870Y45030D01*
X9912Y44655D01*
X9828Y44280D01*
X9703Y44030D01*
X9453Y43780D01*
X9162Y43613D01*
X8870Y43530D01*
X8578D01*
X8287Y43613D01*
X8037Y43738D01*
X7828Y43905D01*
G01X6562Y45613D02*
X6312Y45863D01*
X6020Y45988D01*
X5687Y46030D01*
X5270Y45947D01*
X4978Y45738D01*
X4895Y45488D01*
X4937Y45238D01*
X5103Y45030D01*
X5937Y44613D01*
X6312Y44322D01*
X6562Y43905D01*
X6645Y43530D01*
X4895D01*
G01X3462Y45613D02*
X3212Y45863D01*
X2920Y45988D01*
X2587Y46030D01*
X2170Y45947D01*
X1878Y45738D01*
X1795Y45488D01*
X1837Y45238D01*
X2003Y45030D01*
X2837Y44613D01*
X3212Y44322D01*
X3462Y43905D01*
X3545Y43530D01*
X1795D01*
G01X820Y46030D02*
X237Y43530D01*
X-430Y46030D01*
X-1097Y43530D01*
X-1680Y46030D01*
G01X-4030Y43530D02*
Y46030D01*
X-2488Y44238D01*
X-4572D01*
G01X7497Y52722D02*
X7747Y52847D01*
X8039Y52930D01*
X8372D01*
X8747Y52805D01*
X9039Y52597D01*
X9247Y52347D01*
X9414Y51930D01*
X9456Y51555D01*
X9372Y51180D01*
X9247Y50930D01*
X8997Y50680D01*
X8706Y50513D01*
X8414Y50430D01*
X8122D01*
X7831Y50513D01*
X7581Y50638D01*
X7372Y50805D01*
G01X6106Y52513D02*
X5856Y52763D01*
X5564Y52888D01*
X5231Y52930D01*
X4814Y52847D01*
X4522Y52638D01*
X4439Y52388D01*
X4481Y52138D01*
X4647Y51930D01*
X5481Y51513D01*
X5856Y51222D01*
X6106Y50805D01*
X6189Y50430D01*
X4439D01*
G01X3006Y52513D02*
X2756Y52763D01*
X2464Y52888D01*
X2131Y52930D01*
X1714Y52847D01*
X1422Y52638D01*
X1339Y52388D01*
X1381Y52138D01*
X1547Y51930D01*
X2381Y51513D01*
X2756Y51222D01*
X3006Y50805D01*
X3089Y50430D01*
X1339D01*
G01X364Y52930D02*
X-219Y50430D01*
X-886Y52930D01*
X-1553Y50430D01*
X-2136Y52930D01*
G01X-3069Y50930D02*
X-3319Y50638D01*
X-3653Y50472D01*
X-4028Y50430D01*
X-4361Y50472D01*
X-4694Y50680D01*
X-4903Y50930D01*
X-4944Y51180D01*
X-4861Y51472D01*
X-4569Y51680D01*
X-4278Y51763D01*
X-3903D01*
G01X-4278D02*
X-4528Y51888D01*
X-4736Y52097D01*
X-4819Y52347D01*
X-4736Y52597D01*
X-4528Y52805D01*
X-4153Y52930D01*
X-3778Y52888D01*
X-3403Y52722D01*
G01X-12130Y65230D02*
X-8330D01*
G01Y77430D02*
X-12130D01*
G01X56033Y164750D02*
Y167250D01*
X54992D01*
X54658Y167125D01*
X54450Y166958D01*
X54367Y166625D01*
X54450Y166292D01*
X54700Y166083D01*
X54992Y165958D01*
X56033D01*
G01X54992D02*
X54367Y164750D01*
G01X52808Y165042D02*
X52517Y164833D01*
X52183Y164750D01*
X51850Y164833D01*
X51558Y165083D01*
X51350Y165458D01*
X51267Y165833D01*
Y166292D01*
X51350Y166667D01*
X51558Y167000D01*
X51808Y167167D01*
X52100Y167250D01*
X52433Y167167D01*
X52683Y167000D01*
X52850Y166750D01*
X52933Y166417D01*
X52850Y166125D01*
X52642Y165833D01*
X52392Y165667D01*
X52100Y165625D01*
X51767Y165708D01*
X51517Y165917D01*
X51267Y166292D01*
G01X49833Y164750D02*
Y167250D01*
X48792D01*
X48458Y167125D01*
X48250Y166958D01*
X48167Y166625D01*
X48250Y166292D01*
X48500Y166083D01*
X48792Y165958D01*
X49833D01*
G01X48792D02*
X48167Y164750D01*
G01X45900D02*
Y167250D01*
X46400Y166750D01*
G01Y164750D02*
X45400D01*
G01X42800Y167250D02*
X43133Y167167D01*
X43383Y166958D01*
X43550Y166708D01*
X43675Y166375D01*
X43717Y166000D01*
X43675Y165625D01*
X43550Y165292D01*
X43383Y165042D01*
X43133Y164833D01*
X42800Y164750D01*
X42467Y164833D01*
X42217Y165042D01*
X42050Y165292D01*
X41925Y165625D01*
X41883Y166000D01*
X41925Y166375D01*
X42050Y166708D01*
X42217Y166958D01*
X42467Y167167D01*
X42800Y167250D01*
G01X41483Y159650D02*
Y162150D01*
X40442D01*
X40108Y162025D01*
X39900Y161858D01*
X39817Y161525D01*
X39900Y161192D01*
X40150Y160983D01*
X40442Y160858D01*
X41483D01*
G01X40442D02*
X39817Y159650D01*
G01X38258Y159942D02*
X37967Y159733D01*
X37633Y159650D01*
X37300Y159733D01*
X37008Y159983D01*
X36800Y160358D01*
X36717Y160733D01*
Y161192D01*
X36800Y161567D01*
X37008Y161900D01*
X37258Y162067D01*
X37550Y162150D01*
X37883Y162067D01*
X38133Y161900D01*
X38300Y161650D01*
X38383Y161317D01*
X38300Y161025D01*
X38092Y160733D01*
X37842Y160567D01*
X37550Y160525D01*
X37217Y160608D01*
X36967Y160817D01*
X36717Y161192D01*
G01X35283Y159650D02*
Y162150D01*
X34242D01*
X33908Y162025D01*
X33700Y161858D01*
X33617Y161525D01*
X33700Y161192D01*
X33950Y160983D01*
X34242Y160858D01*
X35283D01*
G01X34242D02*
X33617Y159650D01*
G01X32058Y159942D02*
X31767Y159733D01*
X31433Y159650D01*
X31100Y159733D01*
X30808Y159983D01*
X30600Y160358D01*
X30517Y160733D01*
Y161192D01*
X30600Y161567D01*
X30808Y161900D01*
X31058Y162067D01*
X31350Y162150D01*
X31683Y162067D01*
X31933Y161900D01*
X32100Y161650D01*
X32183Y161317D01*
X32100Y161025D01*
X31892Y160733D01*
X31642Y160567D01*
X31350Y160525D01*
X31017Y160608D01*
X30767Y160817D01*
X30517Y161192D01*
G01X12083Y194742D02*
X12333Y194867D01*
X12625Y194950D01*
X12958D01*
X13333Y194825D01*
X13625Y194617D01*
X13833Y194367D01*
X14000Y193950D01*
X14042Y193575D01*
X13958Y193200D01*
X13833Y192950D01*
X13583Y192700D01*
X13292Y192533D01*
X13000Y192450D01*
X12708D01*
X12417Y192533D01*
X12167Y192658D01*
X11958Y192825D01*
G01X10608Y192742D02*
X10317Y192533D01*
X9983Y192450D01*
X9650Y192533D01*
X9358Y192783D01*
X9150Y193158D01*
X9067Y193533D01*
Y193992D01*
X9150Y194367D01*
X9358Y194700D01*
X9608Y194867D01*
X9900Y194950D01*
X10233Y194867D01*
X10483Y194700D01*
X10650Y194450D01*
X10733Y194117D01*
X10650Y193825D01*
X10442Y193533D01*
X10192Y193367D01*
X9900Y193325D01*
X9567Y193408D01*
X9317Y193617D01*
X9067Y193992D01*
G01X7633Y192450D02*
Y194950D01*
X6592D01*
X6258Y194825D01*
X6050Y194658D01*
X5967Y194325D01*
X6050Y193992D01*
X6300Y193783D01*
X6592Y193658D01*
X7633D01*
G01X6592D02*
X5967Y192450D01*
G01X3700D02*
Y194950D01*
X4200Y194450D01*
G01Y192450D02*
X3200D01*
G01X1392Y194533D02*
X1142Y194783D01*
X850Y194908D01*
X517Y194950D01*
X100Y194867D01*
X-192Y194658D01*
X-275Y194408D01*
X-233Y194158D01*
X-67Y193950D01*
X767Y193533D01*
X1142Y193242D01*
X1392Y192825D01*
X1475Y192450D01*
X-275D01*
G01X5300Y290700D02*
X32000D01*
Y272800D01*
X20200D01*
Y269084D01*
G01X11633Y256392D02*
X11883Y256517D01*
X12175Y256600D01*
X12508D01*
X12883Y256475D01*
X13175Y256267D01*
X13383Y256017D01*
X13550Y255600D01*
X13592Y255225D01*
X13508Y254850D01*
X13383Y254600D01*
X13133Y254350D01*
X12842Y254183D01*
X12550Y254100D01*
X12258D01*
X11967Y254183D01*
X11717Y254308D01*
X11508Y254475D01*
G01X10158Y254392D02*
X9867Y254183D01*
X9533Y254100D01*
X9200Y254183D01*
X8908Y254433D01*
X8700Y254808D01*
X8617Y255183D01*
Y255642D01*
X8700Y256017D01*
X8908Y256350D01*
X9158Y256517D01*
X9450Y256600D01*
X9783Y256517D01*
X10033Y256350D01*
X10200Y256100D01*
X10283Y255767D01*
X10200Y255475D01*
X9992Y255183D01*
X9742Y255017D01*
X9450Y254975D01*
X9117Y255058D01*
X8867Y255267D01*
X8617Y255642D01*
G01X7183Y254100D02*
Y256600D01*
X6142D01*
X5808Y256475D01*
X5600Y256308D01*
X5517Y255975D01*
X5600Y255642D01*
X5850Y255433D01*
X6142Y255308D01*
X7183D01*
G01X6142D02*
X5517Y254100D01*
G01X4167Y254475D02*
X3917Y254267D01*
X3625Y254142D01*
X3250Y254100D01*
X2875Y254183D01*
X2583Y254350D01*
X2375Y254642D01*
X2333Y254975D01*
X2417Y255308D01*
X2625Y255517D01*
X2917Y255683D01*
X3208Y255725D01*
X3500Y255683D01*
X3875Y255517D01*
X3750Y256600D01*
X2625D01*
G01X30883Y278200D02*
Y280700D01*
X29842D01*
X29508Y280575D01*
X29300Y280408D01*
X29217Y280075D01*
X29300Y279742D01*
X29550Y279533D01*
X29842Y279408D01*
X30883D01*
G01X29842D02*
X29217Y278200D01*
G01X27658Y278492D02*
X27367Y278283D01*
X27033Y278200D01*
X26700Y278283D01*
X26408Y278533D01*
X26200Y278908D01*
X26117Y279283D01*
Y279742D01*
X26200Y280117D01*
X26408Y280450D01*
X26658Y280617D01*
X26950Y280700D01*
X27283Y280617D01*
X27533Y280450D01*
X27700Y280200D01*
X27783Y279867D01*
X27700Y279575D01*
X27492Y279283D01*
X27242Y279117D01*
X26950Y279075D01*
X26617Y279158D01*
X26367Y279367D01*
X26117Y279742D01*
G01X24683Y278200D02*
Y280700D01*
X23683D01*
X23350Y280575D01*
X23100Y280283D01*
X23017Y279950D01*
X23100Y279617D01*
X23308Y279367D01*
X23683Y279242D01*
X24683D01*
G01X21667Y278575D02*
X21417Y278367D01*
X21125Y278242D01*
X20750Y278200D01*
X20375Y278283D01*
X20083Y278450D01*
X19875Y278742D01*
X19833Y279075D01*
X19917Y279408D01*
X20125Y279617D01*
X20417Y279783D01*
X20708Y279825D01*
X21000Y279783D01*
X21375Y279617D01*
X21250Y280700D01*
X20125D01*
G01X17683Y278200D02*
Y280700D01*
X16642D01*
X16308Y280575D01*
X16100Y280408D01*
X16017Y280075D01*
X16100Y279742D01*
X16350Y279533D01*
X16642Y279408D01*
X17683D01*
G01X16642D02*
X16017Y278200D01*
G01X14458Y278492D02*
X14167Y278283D01*
X13833Y278200D01*
X13500Y278283D01*
X13208Y278533D01*
X13000Y278908D01*
X12917Y279283D01*
Y279742D01*
X13000Y280117D01*
X13208Y280450D01*
X13458Y280617D01*
X13750Y280700D01*
X14083Y280617D01*
X14333Y280450D01*
X14500Y280200D01*
X14583Y279867D01*
X14500Y279575D01*
X14292Y279283D01*
X14042Y279117D01*
X13750Y279075D01*
X13417Y279158D01*
X13167Y279367D01*
X12917Y279742D01*
G01X11483Y278200D02*
Y280700D01*
X10483D01*
X10150Y280575D01*
X9900Y280283D01*
X9817Y279950D01*
X9900Y279617D01*
X10108Y279367D01*
X10483Y279242D01*
X11483D01*
G01X8342D02*
X8050Y279533D01*
X7800Y279700D01*
X7467Y279783D01*
X7175Y279700D01*
X6967Y279533D01*
X6800Y279283D01*
X6758Y278992D01*
X6800Y278742D01*
X6967Y278492D01*
X7217Y278283D01*
X7508Y278200D01*
X7842Y278283D01*
X8133Y278533D01*
X8300Y278908D01*
X8342Y279325D01*
X8258Y279867D01*
X8133Y280158D01*
X7925Y280450D01*
X7633Y280658D01*
X7342Y280700D01*
X7050Y280617D01*
X6842Y280408D01*
G01X16533Y269167D02*
Y271667D01*
X15492D01*
X15158Y271542D01*
X14950Y271375D01*
X14867Y271042D01*
X14950Y270709D01*
X15200Y270500D01*
X15492Y270375D01*
X16533D01*
G01X15492D02*
X14867Y269167D01*
G01X13308Y269459D02*
X13017Y269250D01*
X12683Y269167D01*
X12350Y269250D01*
X12058Y269500D01*
X11850Y269875D01*
X11767Y270250D01*
Y270709D01*
X11850Y271084D01*
X12058Y271417D01*
X12308Y271584D01*
X12600Y271667D01*
X12933Y271584D01*
X13183Y271417D01*
X13350Y271167D01*
X13433Y270834D01*
X13350Y270542D01*
X13142Y270250D01*
X12892Y270084D01*
X12600Y270042D01*
X12267Y270125D01*
X12017Y270334D01*
X11767Y270709D01*
G01X10333Y269167D02*
Y271667D01*
X9333D01*
X9000Y271542D01*
X8750Y271250D01*
X8667Y270917D01*
X8750Y270584D01*
X8958Y270334D01*
X9333Y270209D01*
X10333D01*
G01X6400Y269167D02*
Y271667D01*
X6900Y271167D01*
G01Y269167D02*
X5900D01*
G01X3300Y271667D02*
X3633Y271584D01*
X3883Y271375D01*
X4050Y271125D01*
X4175Y270792D01*
X4217Y270417D01*
X4175Y270042D01*
X4050Y269709D01*
X3883Y269459D01*
X3633Y269250D01*
X3300Y269167D01*
X2967Y269250D01*
X2717Y269459D01*
X2550Y269709D01*
X2425Y270042D01*
X2383Y270417D01*
X2425Y270792D01*
X2550Y271125D01*
X2717Y271375D01*
X2967Y271584D01*
X3300Y271667D01*
G01X9283Y264200D02*
Y266700D01*
X8242D01*
X7908Y266575D01*
X7700Y266408D01*
X7617Y266075D01*
X7700Y265742D01*
X7950Y265533D01*
X8242Y265408D01*
X9283D01*
G01X8242D02*
X7617Y264200D01*
G01X6058Y264492D02*
X5767Y264283D01*
X5433Y264200D01*
X5100Y264283D01*
X4808Y264533D01*
X4600Y264908D01*
X4517Y265283D01*
Y265742D01*
X4600Y266117D01*
X4808Y266450D01*
X5058Y266617D01*
X5350Y266700D01*
X5683Y266617D01*
X5933Y266450D01*
X6100Y266200D01*
X6183Y265867D01*
X6100Y265575D01*
X5892Y265283D01*
X5642Y265117D01*
X5350Y265075D01*
X5017Y265158D01*
X4767Y265367D01*
X4517Y265742D01*
G01X3083Y264200D02*
Y266700D01*
X2083D01*
X1750Y266575D01*
X1500Y266283D01*
X1417Y265950D01*
X1500Y265617D01*
X1708Y265367D01*
X2083Y265242D01*
X3083D01*
G01X67Y264700D02*
X-183Y264408D01*
X-517Y264242D01*
X-892Y264200D01*
X-1225Y264242D01*
X-1558Y264450D01*
X-1767Y264700D01*
X-1808Y264950D01*
X-1725Y265242D01*
X-1433Y265450D01*
X-1142Y265533D01*
X-767D01*
G01X-1142D02*
X-1392Y265658D01*
X-1600Y265867D01*
X-1683Y266117D01*
X-1600Y266367D01*
X-1392Y266575D01*
X-1017Y266700D01*
X-642Y266658D01*
X-267Y266492D01*
G01X-3033Y264700D02*
X-3283Y264408D01*
X-3617Y264242D01*
X-3992Y264200D01*
X-4325Y264242D01*
X-4658Y264450D01*
X-4867Y264700D01*
X-4908Y264950D01*
X-4825Y265242D01*
X-4533Y265450D01*
X-4242Y265533D01*
X-3867D01*
G01X-4242D02*
X-4492Y265658D01*
X-4700Y265867D01*
X-4783Y266117D01*
X-4700Y266367D01*
X-4492Y266575D01*
X-4117Y266700D01*
X-3742Y266658D01*
X-3367Y266492D01*
G01X3033Y259667D02*
Y262167D01*
X1992D01*
X1658Y262042D01*
X1450Y261875D01*
X1367Y261542D01*
X1450Y261209D01*
X1700Y261000D01*
X1992Y260875D01*
X3033D01*
G01X1992D02*
X1367Y259667D01*
G01X-192Y259959D02*
X-483Y259750D01*
X-817Y259667D01*
X-1150Y259750D01*
X-1442Y260000D01*
X-1650Y260375D01*
X-1733Y260750D01*
Y261209D01*
X-1650Y261584D01*
X-1442Y261917D01*
X-1192Y262084D01*
X-900Y262167D01*
X-567Y262084D01*
X-317Y261917D01*
X-150Y261667D01*
X-67Y261334D01*
X-150Y261042D01*
X-358Y260750D01*
X-608Y260584D01*
X-900Y260542D01*
X-1233Y260625D01*
X-1483Y260834D01*
X-1733Y261209D01*
G01X-3167Y259667D02*
Y262167D01*
X-4167D01*
X-4500Y262042D01*
X-4750Y261750D01*
X-4833Y261417D01*
X-4750Y261084D01*
X-4542Y260834D01*
X-4167Y260709D01*
X-3167D01*
G01X-7100Y259667D02*
Y262167D01*
X-6600Y261667D01*
G01Y259667D02*
X-7600D01*
G01X-9408Y261750D02*
X-9658Y262000D01*
X-9950Y262125D01*
X-10283Y262167D01*
X-10700Y262084D01*
X-10992Y261875D01*
X-11075Y261625D01*
X-11033Y261375D01*
X-10867Y261167D01*
X-10033Y260750D01*
X-9658Y260459D01*
X-9408Y260042D01*
X-9325Y259667D01*
X-11075D01*
G01X39700Y276367D02*
X42200D01*
Y277408D01*
X42075Y277742D01*
X41908Y277950D01*
X41575Y278033D01*
X41242Y277950D01*
X41033Y277700D01*
X40908Y277408D01*
Y276367D01*
G01Y277408D02*
X39700Y278033D01*
G01X39992Y279592D02*
X39783Y279883D01*
X39700Y280217D01*
X39783Y280550D01*
X40033Y280842D01*
X40408Y281050D01*
X40783Y281133D01*
X41242D01*
X41617Y281050D01*
X41950Y280842D01*
X42117Y280592D01*
X42200Y280300D01*
X42117Y279967D01*
X41950Y279717D01*
X41700Y279550D01*
X41367Y279467D01*
X41075Y279550D01*
X40783Y279758D01*
X40617Y280008D01*
X40575Y280300D01*
X40658Y280633D01*
X40867Y280883D01*
X41242Y281133D01*
G01X39700Y282567D02*
X42200D01*
Y283567D01*
X42075Y283900D01*
X41783Y284150D01*
X41450Y284233D01*
X41117Y284150D01*
X40867Y283942D01*
X40742Y283567D01*
Y282567D01*
G01X41783Y285708D02*
X42033Y285958D01*
X42158Y286250D01*
X42200Y286583D01*
X42117Y287000D01*
X41908Y287292D01*
X41658Y287375D01*
X41408Y287333D01*
X41200Y287167D01*
X40783Y286333D01*
X40492Y285958D01*
X40075Y285708D01*
X39700Y285625D01*
Y287375D01*
G01X40742Y288808D02*
X41033Y289100D01*
X41200Y289350D01*
X41283Y289683D01*
X41200Y289975D01*
X41033Y290183D01*
X40783Y290350D01*
X40492Y290392D01*
X40242Y290350D01*
X39992Y290183D01*
X39783Y289933D01*
X39700Y289642D01*
X39783Y289308D01*
X40033Y289017D01*
X40408Y288850D01*
X40825Y288808D01*
X41367Y288892D01*
X41658Y289017D01*
X41950Y289225D01*
X42158Y289517D01*
X42200Y289808D01*
X42117Y290100D01*
X41908Y290308D01*
G01X36200Y276367D02*
X38700D01*
Y277408D01*
X38575Y277742D01*
X38408Y277950D01*
X38075Y278033D01*
X37742Y277950D01*
X37533Y277700D01*
X37408Y277408D01*
Y276367D01*
G01Y277408D02*
X36200Y278033D01*
G01X36492Y279592D02*
X36283Y279883D01*
X36200Y280217D01*
X36283Y280550D01*
X36533Y280842D01*
X36908Y281050D01*
X37283Y281133D01*
X37742D01*
X38117Y281050D01*
X38450Y280842D01*
X38617Y280592D01*
X38700Y280300D01*
X38617Y279967D01*
X38450Y279717D01*
X38200Y279550D01*
X37867Y279467D01*
X37575Y279550D01*
X37283Y279758D01*
X37117Y280008D01*
X37075Y280300D01*
X37158Y280633D01*
X37367Y280883D01*
X37742Y281133D01*
G01X36200Y282567D02*
X38700D01*
Y283567D01*
X38575Y283900D01*
X38283Y284150D01*
X37950Y284233D01*
X37617Y284150D01*
X37367Y283942D01*
X37242Y283567D01*
Y282567D01*
G01X38283Y285708D02*
X38533Y285958D01*
X38658Y286250D01*
X38700Y286583D01*
X38617Y287000D01*
X38408Y287292D01*
X38158Y287375D01*
X37908Y287333D01*
X37700Y287167D01*
X37283Y286333D01*
X36992Y285958D01*
X36575Y285708D01*
X36200Y285625D01*
Y287375D01*
G01Y289517D02*
X36742Y289600D01*
X37200Y289725D01*
X37617Y289892D01*
X38075Y290100D01*
X38700Y290433D01*
Y288767D01*
G01X11633Y252892D02*
X11883Y253017D01*
X12175Y253100D01*
X12508D01*
X12883Y252975D01*
X13175Y252767D01*
X13383Y252517D01*
X13550Y252100D01*
X13592Y251725D01*
X13508Y251350D01*
X13383Y251100D01*
X13133Y250850D01*
X12842Y250683D01*
X12550Y250600D01*
X12258D01*
X11967Y250683D01*
X11717Y250808D01*
X11508Y250975D01*
G01X10158Y250892D02*
X9867Y250683D01*
X9533Y250600D01*
X9200Y250683D01*
X8908Y250933D01*
X8700Y251308D01*
X8617Y251683D01*
Y252142D01*
X8700Y252517D01*
X8908Y252850D01*
X9158Y253017D01*
X9450Y253100D01*
X9783Y253017D01*
X10033Y252850D01*
X10200Y252600D01*
X10283Y252267D01*
X10200Y251975D01*
X9992Y251683D01*
X9742Y251517D01*
X9450Y251475D01*
X9117Y251558D01*
X8867Y251767D01*
X8617Y252142D01*
G01X7183Y250600D02*
Y253100D01*
X6142D01*
X5808Y252975D01*
X5600Y252808D01*
X5517Y252475D01*
X5600Y252142D01*
X5850Y251933D01*
X6142Y251808D01*
X7183D01*
G01X6142D02*
X5517Y250600D01*
G01X4042Y251642D02*
X3750Y251933D01*
X3500Y252100D01*
X3167Y252183D01*
X2875Y252100D01*
X2667Y251933D01*
X2500Y251683D01*
X2458Y251392D01*
X2500Y251142D01*
X2667Y250892D01*
X2917Y250683D01*
X3208Y250600D01*
X3542Y250683D01*
X3833Y250933D01*
X4000Y251308D01*
X4042Y251725D01*
X3958Y252267D01*
X3833Y252558D01*
X3625Y252850D01*
X3333Y253058D01*
X3042Y253100D01*
X2750Y253017D01*
X2542Y252808D01*
G01X49283Y243200D02*
Y245700D01*
X48242D01*
X47908Y245575D01*
X47700Y245408D01*
X47617Y245075D01*
X47700Y244742D01*
X47950Y244533D01*
X48242Y244408D01*
X49283D01*
G01X48242D02*
X47617Y243200D01*
G01X46058Y243492D02*
X45767Y243283D01*
X45433Y243200D01*
X45100Y243283D01*
X44808Y243533D01*
X44600Y243908D01*
X44517Y244283D01*
Y244742D01*
X44600Y245117D01*
X44808Y245450D01*
X45058Y245617D01*
X45350Y245700D01*
X45683Y245617D01*
X45933Y245450D01*
X46100Y245200D01*
X46183Y244867D01*
X46100Y244575D01*
X45892Y244283D01*
X45642Y244117D01*
X45350Y244075D01*
X45017Y244158D01*
X44767Y244367D01*
X44517Y244742D01*
G01X43083Y243200D02*
Y245700D01*
X42042D01*
X41708Y245575D01*
X41500Y245408D01*
X41417Y245075D01*
X41500Y244742D01*
X41750Y244533D01*
X42042Y244408D01*
X43083D01*
G01X42042D02*
X41417Y243200D01*
G01X39150D02*
Y245700D01*
X39650Y245200D01*
G01Y243200D02*
X38650D01*
G01X22683Y276842D02*
X22933Y276967D01*
X23225Y277050D01*
X23558D01*
X23933Y276925D01*
X24225Y276717D01*
X24433Y276467D01*
X24600Y276050D01*
X24642Y275675D01*
X24558Y275300D01*
X24433Y275050D01*
X24183Y274800D01*
X23892Y274633D01*
X23600Y274550D01*
X23308D01*
X23017Y274633D01*
X22767Y274758D01*
X22558Y274925D01*
G01X21333Y274550D02*
Y277050D01*
X20292D01*
X19958Y276925D01*
X19750Y276758D01*
X19667Y276425D01*
X19750Y276092D01*
X20000Y275883D01*
X20292Y275758D01*
X21333D01*
G01X20292D02*
X19667Y274550D01*
G01X18108Y274842D02*
X17817Y274633D01*
X17483Y274550D01*
X17150Y274633D01*
X16858Y274883D01*
X16650Y275258D01*
X16567Y275633D01*
Y276092D01*
X16650Y276467D01*
X16858Y276800D01*
X17108Y276967D01*
X17400Y277050D01*
X17733Y276967D01*
X17983Y276800D01*
X18150Y276550D01*
X18233Y276217D01*
X18150Y275925D01*
X17942Y275633D01*
X17692Y275467D01*
X17400Y275425D01*
X17067Y275508D01*
X16817Y275717D01*
X16567Y276092D01*
G01X15133Y274550D02*
Y277050D01*
X14133D01*
X13800Y276925D01*
X13550Y276633D01*
X13467Y276300D01*
X13550Y275967D01*
X13758Y275717D01*
X14133Y275592D01*
X15133D01*
G01X11992Y276633D02*
X11742Y276883D01*
X11450Y277008D01*
X11117Y277050D01*
X10700Y276967D01*
X10408Y276758D01*
X10325Y276508D01*
X10367Y276258D01*
X10533Y276050D01*
X11367Y275633D01*
X11742Y275342D01*
X11992Y274925D01*
X12075Y274550D01*
X10325D01*
G01X-1187Y273088D02*
X-2979D01*
X-3354Y273255D01*
X-3604Y273588D01*
X-3687Y274005D01*
X-3604Y274422D01*
X-3354Y274755D01*
X-2979Y274922D01*
X-1187D01*
G01X-3395Y276397D02*
X-3604Y276688D01*
X-3687Y277022D01*
X-3604Y277355D01*
X-3354Y277647D01*
X-2979Y277855D01*
X-2604Y277938D01*
X-2145D01*
X-1770Y277855D01*
X-1437Y277647D01*
X-1270Y277397D01*
X-1187Y277105D01*
X-1270Y276772D01*
X-1437Y276522D01*
X-1687Y276355D01*
X-2020Y276272D01*
X-2312Y276355D01*
X-2604Y276563D01*
X-2770Y276813D01*
X-2812Y277105D01*
X-2729Y277438D01*
X-2520Y277688D01*
X-2145Y277938D01*
G01X-3687Y279372D02*
X-1187D01*
Y280372D01*
X-1312Y280705D01*
X-1604Y280955D01*
X-1937Y281038D01*
X-2270Y280955D01*
X-2520Y280747D01*
X-2645Y280372D01*
Y279372D01*
G01X-3687Y283305D02*
X-1187D01*
X-1687Y282805D01*
G01X-3687D02*
Y283805D01*
G01X-467Y268450D02*
Y270950D01*
X-1508D01*
X-1842Y270825D01*
X-2050Y270658D01*
X-2133Y270325D01*
X-2050Y269992D01*
X-1800Y269783D01*
X-1508Y269658D01*
X-467D01*
G01X-1508D02*
X-2133Y268450D01*
G01X-3692Y268742D02*
X-3983Y268533D01*
X-4317Y268450D01*
X-4650Y268533D01*
X-4942Y268783D01*
X-5150Y269158D01*
X-5233Y269533D01*
Y269992D01*
X-5150Y270367D01*
X-4942Y270700D01*
X-4692Y270867D01*
X-4400Y270950D01*
X-4067Y270867D01*
X-3817Y270700D01*
X-3650Y270450D01*
X-3567Y270117D01*
X-3650Y269825D01*
X-3858Y269533D01*
X-4108Y269367D01*
X-4400Y269325D01*
X-4733Y269408D01*
X-4983Y269617D01*
X-5233Y269992D01*
G01X-6667Y268450D02*
Y270950D01*
X-7667D01*
X-8000Y270825D01*
X-8250Y270533D01*
X-8333Y270200D01*
X-8250Y269867D01*
X-8042Y269617D01*
X-7667Y269492D01*
X-6667D01*
G01X-10600Y268450D02*
Y270950D01*
X-10100Y270450D01*
G01Y268450D02*
X-11100D01*
G01X-12783Y268950D02*
X-13033Y268658D01*
X-13367Y268492D01*
X-13742Y268450D01*
X-14075Y268492D01*
X-14408Y268700D01*
X-14617Y268950D01*
X-14658Y269200D01*
X-14575Y269492D01*
X-14283Y269700D01*
X-13992Y269783D01*
X-13617D01*
G01X-13992D02*
X-14242Y269908D01*
X-14450Y270117D01*
X-14533Y270367D01*
X-14450Y270617D01*
X-14242Y270825D01*
X-13867Y270950D01*
X-13492Y270908D01*
X-13117Y270742D01*
G01X5732Y282150D02*
Y289150D01*
X3066D01*
X1999Y288800D01*
X1199Y288333D01*
X532Y287633D01*
X-1Y286817D01*
X-134Y285650D01*
X-1Y284483D01*
X532Y283667D01*
X1199Y282966D01*
X1999Y282500D01*
X3066Y282150D01*
X5732D01*
G01X41800Y335817D02*
X44300D01*
Y336858D01*
X44175Y337192D01*
X44008Y337400D01*
X43675Y337483D01*
X43342Y337400D01*
X43133Y337150D01*
X43008Y336858D01*
Y335817D01*
G01Y336858D02*
X41800Y337483D01*
G01X42092Y339042D02*
X41883Y339333D01*
X41800Y339667D01*
X41883Y340000D01*
X42133Y340292D01*
X42508Y340500D01*
X42883Y340583D01*
X43342D01*
X43717Y340500D01*
X44050Y340292D01*
X44217Y340042D01*
X44300Y339750D01*
X44217Y339417D01*
X44050Y339167D01*
X43800Y339000D01*
X43467Y338917D01*
X43175Y339000D01*
X42883Y339208D01*
X42717Y339458D01*
X42675Y339750D01*
X42758Y340083D01*
X42967Y340333D01*
X43342Y340583D01*
G01X41800Y342017D02*
X44300D01*
Y343017D01*
X44175Y343350D01*
X43883Y343600D01*
X43550Y343683D01*
X43217Y343600D01*
X42967Y343392D01*
X42842Y343017D01*
Y342017D01*
G01X43883Y345158D02*
X44133Y345408D01*
X44258Y345700D01*
X44300Y346033D01*
X44217Y346450D01*
X44008Y346742D01*
X43758Y346825D01*
X43508Y346783D01*
X43300Y346617D01*
X42883Y345783D01*
X42592Y345408D01*
X42175Y345158D01*
X41800Y345075D01*
Y346825D01*
G01X34800Y340317D02*
X37300D01*
Y341358D01*
X37175Y341692D01*
X37008Y341900D01*
X36675Y341983D01*
X36342Y341900D01*
X36133Y341650D01*
X36008Y341358D01*
Y340317D01*
G01Y341358D02*
X34800Y341983D01*
G01X35092Y343542D02*
X34883Y343833D01*
X34800Y344167D01*
X34883Y344500D01*
X35133Y344792D01*
X35508Y345000D01*
X35883Y345083D01*
X36342D01*
X36717Y345000D01*
X37050Y344792D01*
X37217Y344542D01*
X37300Y344250D01*
X37217Y343917D01*
X37050Y343667D01*
X36800Y343500D01*
X36467Y343417D01*
X36175Y343500D01*
X35883Y343708D01*
X35717Y343958D01*
X35675Y344250D01*
X35758Y344583D01*
X35967Y344833D01*
X36342Y345083D01*
G01X34800Y346517D02*
X37300D01*
Y347517D01*
X37175Y347850D01*
X36883Y348100D01*
X36550Y348183D01*
X36217Y348100D01*
X35967Y347892D01*
X35842Y347517D01*
Y346517D01*
G01X35300Y349533D02*
X35008Y349783D01*
X34842Y350117D01*
X34800Y350492D01*
X34842Y350825D01*
X35050Y351158D01*
X35300Y351367D01*
X35550Y351408D01*
X35842Y351325D01*
X36050Y351033D01*
X36133Y350742D01*
Y350367D01*
G01Y350742D02*
X36258Y350992D01*
X36467Y351200D01*
X36717Y351283D01*
X36967Y351200D01*
X37175Y350992D01*
X37300Y350617D01*
X37258Y350242D01*
X37092Y349867D01*
G01X28300Y293217D02*
X30800D01*
Y294258D01*
X30675Y294592D01*
X30508Y294800D01*
X30175Y294883D01*
X29842Y294800D01*
X29633Y294550D01*
X29508Y294258D01*
Y293217D01*
G01Y294258D02*
X28300Y294883D01*
G01X28592Y296442D02*
X28383Y296733D01*
X28300Y297067D01*
X28383Y297400D01*
X28633Y297692D01*
X29008Y297900D01*
X29383Y297983D01*
X29842D01*
X30217Y297900D01*
X30550Y297692D01*
X30717Y297442D01*
X30800Y297150D01*
X30717Y296817D01*
X30550Y296567D01*
X30300Y296400D01*
X29967Y296317D01*
X29675Y296400D01*
X29383Y296608D01*
X29217Y296858D01*
X29175Y297150D01*
X29258Y297483D01*
X29467Y297733D01*
X29842Y297983D01*
G01X28300Y299417D02*
X30800D01*
Y300417D01*
X30675Y300750D01*
X30383Y301000D01*
X30050Y301083D01*
X29717Y301000D01*
X29467Y300792D01*
X29342Y300417D01*
Y299417D01*
G01X30383Y302558D02*
X30633Y302808D01*
X30758Y303100D01*
X30800Y303433D01*
X30717Y303850D01*
X30508Y304142D01*
X30258Y304225D01*
X30008Y304183D01*
X29800Y304017D01*
X29383Y303183D01*
X29092Y302808D01*
X28675Y302558D01*
X28300Y302475D01*
Y304225D01*
G01X28800Y305533D02*
X28508Y305783D01*
X28342Y306117D01*
X28300Y306492D01*
X28342Y306825D01*
X28550Y307158D01*
X28800Y307367D01*
X29050Y307408D01*
X29342Y307325D01*
X29550Y307033D01*
X29633Y306742D01*
Y306367D01*
G01Y306742D02*
X29758Y306992D01*
X29967Y307200D01*
X30217Y307283D01*
X30467Y307200D01*
X30675Y306992D01*
X30800Y306617D01*
X30758Y306242D01*
X30592Y305867D01*
G01X55360Y322497D02*
Y324997D01*
X54319D01*
X53985Y324872D01*
X53777Y324705D01*
X53694Y324372D01*
X53777Y324039D01*
X54027Y323830D01*
X54319Y323705D01*
X55360D01*
G01X54319D02*
X53694Y322497D01*
G01X52135Y322789D02*
X51844Y322580D01*
X51510Y322497D01*
X51177Y322580D01*
X50885Y322830D01*
X50677Y323205D01*
X50594Y323580D01*
Y324039D01*
X50677Y324414D01*
X50885Y324747D01*
X51135Y324914D01*
X51427Y324997D01*
X51760Y324914D01*
X52010Y324747D01*
X52177Y324497D01*
X52260Y324164D01*
X52177Y323872D01*
X51969Y323580D01*
X51719Y323414D01*
X51427Y323372D01*
X51094Y323455D01*
X50844Y323664D01*
X50594Y324039D01*
G01X49160Y322497D02*
Y324997D01*
X48160D01*
X47827Y324872D01*
X47577Y324580D01*
X47494Y324247D01*
X47577Y323914D01*
X47785Y323664D01*
X48160Y323539D01*
X49160D01*
G01X45227Y322497D02*
Y324997D01*
X45727Y324497D01*
G01Y322497D02*
X44727D01*
G01X43044Y322872D02*
X42794Y322664D01*
X42502Y322539D01*
X42127Y322497D01*
X41752Y322580D01*
X41460Y322747D01*
X41252Y323039D01*
X41210Y323372D01*
X41294Y323705D01*
X41502Y323914D01*
X41794Y324080D01*
X42085Y324122D01*
X42377Y324080D01*
X42752Y323914D01*
X42627Y324997D01*
X41502D01*
G01X38300Y340317D02*
X40800D01*
Y341358D01*
X40675Y341692D01*
X40508Y341900D01*
X40175Y341983D01*
X39842Y341900D01*
X39633Y341650D01*
X39508Y341358D01*
Y340317D01*
G01Y341358D02*
X38300Y341983D01*
G01X38592Y343542D02*
X38383Y343833D01*
X38300Y344167D01*
X38383Y344500D01*
X38633Y344792D01*
X39008Y345000D01*
X39383Y345083D01*
X39842D01*
X40217Y345000D01*
X40550Y344792D01*
X40717Y344542D01*
X40800Y344250D01*
X40717Y343917D01*
X40550Y343667D01*
X40300Y343500D01*
X39967Y343417D01*
X39675Y343500D01*
X39383Y343708D01*
X39217Y343958D01*
X39175Y344250D01*
X39258Y344583D01*
X39467Y344833D01*
X39842Y345083D01*
G01X38300Y346517D02*
X40800D01*
Y347517D01*
X40675Y347850D01*
X40383Y348100D01*
X40050Y348183D01*
X39717Y348100D01*
X39467Y347892D01*
X39342Y347517D01*
Y346517D01*
G01X38300Y350950D02*
X40800D01*
X39008Y349408D01*
Y351492D01*
G01X45300Y335817D02*
X47800D01*
Y336858D01*
X47675Y337192D01*
X47508Y337400D01*
X47175Y337483D01*
X46842Y337400D01*
X46633Y337150D01*
X46508Y336858D01*
Y335817D01*
G01Y336858D02*
X45300Y337483D01*
G01X45592Y339042D02*
X45383Y339333D01*
X45300Y339667D01*
X45383Y340000D01*
X45633Y340292D01*
X46008Y340500D01*
X46383Y340583D01*
X46842D01*
X47217Y340500D01*
X47550Y340292D01*
X47717Y340042D01*
X47800Y339750D01*
X47717Y339417D01*
X47550Y339167D01*
X47300Y339000D01*
X46967Y338917D01*
X46675Y339000D01*
X46383Y339208D01*
X46217Y339458D01*
X46175Y339750D01*
X46258Y340083D01*
X46467Y340333D01*
X46842Y340583D01*
G01X45300Y342017D02*
X47800D01*
Y343017D01*
X47675Y343350D01*
X47383Y343600D01*
X47050Y343683D01*
X46717Y343600D01*
X46467Y343392D01*
X46342Y343017D01*
Y342017D01*
G01X45300Y345950D02*
X47800D01*
X47300Y345450D01*
G01X45300D02*
Y346450D01*
G01X46153Y300380D02*
Y302880D01*
X45112D01*
X44778Y302755D01*
X44570Y302588D01*
X44487Y302255D01*
X44570Y301922D01*
X44820Y301713D01*
X45112Y301588D01*
X46153D01*
G01X45112D02*
X44487Y300380D01*
G01X42928Y300672D02*
X42637Y300463D01*
X42303Y300380D01*
X41970Y300463D01*
X41678Y300713D01*
X41470Y301088D01*
X41387Y301463D01*
Y301922D01*
X41470Y302297D01*
X41678Y302630D01*
X41928Y302797D01*
X42220Y302880D01*
X42553Y302797D01*
X42803Y302630D01*
X42970Y302380D01*
X43053Y302047D01*
X42970Y301755D01*
X42762Y301463D01*
X42512Y301297D01*
X42220Y301255D01*
X41887Y301338D01*
X41637Y301547D01*
X41387Y301922D01*
G01X39953Y300380D02*
Y302880D01*
X38953D01*
X38620Y302755D01*
X38370Y302463D01*
X38287Y302130D01*
X38370Y301797D01*
X38578Y301547D01*
X38953Y301422D01*
X39953D01*
G01X36812Y302463D02*
X36562Y302713D01*
X36270Y302838D01*
X35937Y302880D01*
X35520Y302797D01*
X35228Y302588D01*
X35145Y302338D01*
X35187Y302088D01*
X35353Y301880D01*
X36187Y301463D01*
X36562Y301172D01*
X36812Y300755D01*
X36895Y300380D01*
X35145D01*
G01X32420D02*
Y302880D01*
X33962Y301088D01*
X31878D01*
G01X24300Y293217D02*
X26800D01*
Y294258D01*
X26675Y294592D01*
X26508Y294800D01*
X26175Y294883D01*
X25842Y294800D01*
X25633Y294550D01*
X25508Y294258D01*
Y293217D01*
G01Y294258D02*
X24300Y294883D01*
G01X24592Y296442D02*
X24383Y296733D01*
X24300Y297067D01*
X24383Y297400D01*
X24633Y297692D01*
X25008Y297900D01*
X25383Y297983D01*
X25842D01*
X26217Y297900D01*
X26550Y297692D01*
X26717Y297442D01*
X26800Y297150D01*
X26717Y296817D01*
X26550Y296567D01*
X26300Y296400D01*
X25967Y296317D01*
X25675Y296400D01*
X25383Y296608D01*
X25217Y296858D01*
X25175Y297150D01*
X25258Y297483D01*
X25467Y297733D01*
X25842Y297983D01*
G01X24300Y299417D02*
X26800D01*
Y300417D01*
X26675Y300750D01*
X26383Y301000D01*
X26050Y301083D01*
X25717Y301000D01*
X25467Y300792D01*
X25342Y300417D01*
Y299417D01*
G01X24300Y303350D02*
X26800D01*
X26300Y302850D01*
G01X24300D02*
Y303850D01*
G01Y306450D02*
X24342Y306742D01*
X24467Y307075D01*
X24675Y307283D01*
X24967Y307367D01*
X25258Y307283D01*
X25508Y307033D01*
X25633Y306658D01*
Y306242D01*
X25717Y305992D01*
X25925Y305783D01*
X26217Y305700D01*
X26508Y305825D01*
X26717Y306117D01*
X26800Y306450D01*
X26717Y306783D01*
X26508Y307075D01*
X26217Y307200D01*
X25925Y307117D01*
X25717Y306908D01*
X25633Y306658D01*
Y306242D01*
X25508Y305867D01*
X25258Y305617D01*
X24967Y305533D01*
X24675Y305617D01*
X24467Y305825D01*
X24342Y306158D01*
X24300Y306450D01*
G01X48903Y306172D02*
X49153Y306297D01*
X49445Y306380D01*
X49778D01*
X50153Y306255D01*
X50445Y306047D01*
X50653Y305797D01*
X50820Y305380D01*
X50862Y305005D01*
X50778Y304630D01*
X50653Y304380D01*
X50403Y304130D01*
X50112Y303963D01*
X49820Y303880D01*
X49528D01*
X49237Y303963D01*
X48987Y304088D01*
X48778Y304255D01*
G01X47428Y304172D02*
X47137Y303963D01*
X46803Y303880D01*
X46470Y303963D01*
X46178Y304213D01*
X45970Y304588D01*
X45887Y304963D01*
Y305422D01*
X45970Y305797D01*
X46178Y306130D01*
X46428Y306297D01*
X46720Y306380D01*
X47053Y306297D01*
X47303Y306130D01*
X47470Y305880D01*
X47553Y305547D01*
X47470Y305255D01*
X47262Y304963D01*
X47012Y304797D01*
X46720Y304755D01*
X46387Y304838D01*
X46137Y305047D01*
X45887Y305422D01*
G01X44453Y303880D02*
Y306380D01*
X43453D01*
X43120Y306255D01*
X42870Y305963D01*
X42787Y305630D01*
X42870Y305297D01*
X43078Y305047D01*
X43453Y304922D01*
X44453D01*
G01X40520Y303880D02*
Y306380D01*
X41020Y305880D01*
G01Y303880D02*
X40020D01*
G01X38212Y305963D02*
X37962Y306213D01*
X37670Y306338D01*
X37337Y306380D01*
X36920Y306297D01*
X36628Y306088D01*
X36545Y305838D01*
X36587Y305588D01*
X36753Y305380D01*
X37587Y304963D01*
X37962Y304672D01*
X38212Y304255D01*
X38295Y303880D01*
X36545D01*
G01X23183Y284142D02*
X23433Y284267D01*
X23725Y284350D01*
X24058D01*
X24433Y284225D01*
X24725Y284017D01*
X24933Y283767D01*
X25100Y283350D01*
X25142Y282975D01*
X25058Y282600D01*
X24933Y282350D01*
X24683Y282100D01*
X24392Y281933D01*
X24100Y281850D01*
X23808D01*
X23517Y281933D01*
X23267Y282058D01*
X23058Y282225D01*
G01X21833Y281850D02*
Y284350D01*
X20792D01*
X20458Y284225D01*
X20250Y284058D01*
X20167Y283725D01*
X20250Y283392D01*
X20500Y283183D01*
X20792Y283058D01*
X21833D01*
G01X20792D02*
X20167Y281850D01*
G01X18608Y282142D02*
X18317Y281933D01*
X17983Y281850D01*
X17650Y281933D01*
X17358Y282183D01*
X17150Y282558D01*
X17067Y282933D01*
Y283392D01*
X17150Y283767D01*
X17358Y284100D01*
X17608Y284267D01*
X17900Y284350D01*
X18233Y284267D01*
X18483Y284100D01*
X18650Y283850D01*
X18733Y283517D01*
X18650Y283225D01*
X18442Y282933D01*
X18192Y282767D01*
X17900Y282725D01*
X17567Y282808D01*
X17317Y283017D01*
X17067Y283392D01*
G01X15633Y281850D02*
Y284350D01*
X14633D01*
X14300Y284225D01*
X14050Y283933D01*
X13967Y283600D01*
X14050Y283267D01*
X14258Y283017D01*
X14633Y282892D01*
X15633D01*
G01X11700Y281850D02*
Y284350D01*
X12200Y283850D01*
G01Y281850D02*
X11200D01*
G01X41515Y309550D02*
X41557Y309217D01*
X41723Y308925D01*
X41973Y308675D01*
X42265Y308508D01*
X42598Y308425D01*
X42932D01*
X43265Y308508D01*
X43557Y308675D01*
X43807Y308925D01*
X43973Y309217D01*
X44015Y309550D01*
X43973Y309883D01*
X43807Y310175D01*
X43557Y310425D01*
X43265Y310592D01*
X42932Y310675D01*
X42598D01*
X42265Y310592D01*
X41973Y310425D01*
X41723Y310175D01*
X41557Y309883D01*
X41515Y309550D01*
G01X42182Y309883D02*
X41515Y310383D01*
G01Y312650D02*
X44015D01*
X43515Y312150D01*
G01X41515D02*
Y313150D01*
G01X44015Y314500D02*
X41515Y315083D01*
X44015Y315750D01*
X41515Y316417D01*
X44015Y317000D01*
G01X41890Y317933D02*
X41682Y318183D01*
X41557Y318475D01*
X41515Y318850D01*
X41598Y319225D01*
X41765Y319517D01*
X42057Y319725D01*
X42390Y319767D01*
X42723Y319683D01*
X42932Y319475D01*
X43098Y319183D01*
X43140Y318892D01*
X43098Y318600D01*
X42932Y318225D01*
X44015Y318350D01*
Y319475D01*
G01X53733Y360800D02*
Y363300D01*
X52692D01*
X52358Y363175D01*
X52150Y363008D01*
X52067Y362675D01*
X52150Y362342D01*
X52400Y362133D01*
X52692Y362008D01*
X53733D01*
G01X52692D02*
X52067Y360800D01*
G01X50508Y361092D02*
X50217Y360883D01*
X49883Y360800D01*
X49550Y360883D01*
X49258Y361133D01*
X49050Y361508D01*
X48967Y361883D01*
Y362342D01*
X49050Y362717D01*
X49258Y363050D01*
X49508Y363217D01*
X49800Y363300D01*
X50133Y363217D01*
X50383Y363050D01*
X50550Y362800D01*
X50633Y362467D01*
X50550Y362175D01*
X50342Y361883D01*
X50092Y361717D01*
X49800Y361675D01*
X49467Y361758D01*
X49217Y361967D01*
X48967Y362342D01*
G01X47658Y360800D02*
Y363300D01*
X45742Y360800D01*
Y363300D01*
G01X43600Y360800D02*
Y363300D01*
X44100Y362800D01*
G01Y360800D02*
X43100D01*
G01X40000D02*
Y363300D01*
X41542Y361508D01*
X39458D01*
G01X53533Y355967D02*
Y358467D01*
X52492D01*
X52158Y358342D01*
X51950Y358175D01*
X51867Y357842D01*
X51950Y357509D01*
X52200Y357300D01*
X52492Y357175D01*
X53533D01*
G01X52492D02*
X51867Y355967D01*
G01X50308Y356259D02*
X50017Y356050D01*
X49683Y355967D01*
X49350Y356050D01*
X49058Y356300D01*
X48850Y356675D01*
X48767Y357050D01*
Y357509D01*
X48850Y357884D01*
X49058Y358217D01*
X49308Y358384D01*
X49600Y358467D01*
X49933Y358384D01*
X50183Y358217D01*
X50350Y357967D01*
X50433Y357634D01*
X50350Y357342D01*
X50142Y357050D01*
X49892Y356884D01*
X49600Y356842D01*
X49267Y356925D01*
X49017Y357134D01*
X48767Y357509D01*
G01X47458Y355967D02*
Y358467D01*
X45542Y355967D01*
Y358467D01*
G01X43400Y355967D02*
Y358467D01*
X43900Y357967D01*
G01Y355967D02*
X42900D01*
G01X41092Y357009D02*
X40800Y357300D01*
X40550Y357467D01*
X40217Y357550D01*
X39925Y357467D01*
X39717Y357300D01*
X39550Y357050D01*
X39508Y356759D01*
X39550Y356509D01*
X39717Y356259D01*
X39967Y356050D01*
X40258Y355967D01*
X40592Y356050D01*
X40883Y356300D01*
X41050Y356675D01*
X41092Y357092D01*
X41008Y357634D01*
X40883Y357925D01*
X40675Y358217D01*
X40383Y358425D01*
X40092Y358467D01*
X39800Y358384D01*
X39592Y358175D01*
G01X47783Y387092D02*
X48033Y387217D01*
X48325Y387300D01*
X48658D01*
X49033Y387175D01*
X49325Y386967D01*
X49533Y386717D01*
X49700Y386300D01*
X49742Y385925D01*
X49658Y385550D01*
X49533Y385300D01*
X49283Y385050D01*
X48992Y384883D01*
X48700Y384800D01*
X48408D01*
X48117Y384883D01*
X47867Y385008D01*
X47658Y385175D01*
G01X46308Y385092D02*
X46017Y384883D01*
X45683Y384800D01*
X45350Y384883D01*
X45058Y385133D01*
X44850Y385508D01*
X44767Y385883D01*
Y386342D01*
X44850Y386717D01*
X45058Y387050D01*
X45308Y387217D01*
X45600Y387300D01*
X45933Y387217D01*
X46183Y387050D01*
X46350Y386800D01*
X46433Y386467D01*
X46350Y386175D01*
X46142Y385883D01*
X45892Y385717D01*
X45600Y385675D01*
X45267Y385758D01*
X45017Y385967D01*
X44767Y386342D01*
G01X43458Y384800D02*
Y387300D01*
X41542Y384800D01*
Y387300D01*
G01X39400Y384800D02*
Y387300D01*
X39900Y386800D01*
G01Y384800D02*
X38900D01*
G01X36383D02*
X36300Y385342D01*
X36175Y385800D01*
X36008Y386217D01*
X35800Y386675D01*
X35467Y387300D01*
X37133D01*
G01X47683Y396692D02*
X47933Y396817D01*
X48225Y396900D01*
X48558D01*
X48933Y396775D01*
X49225Y396567D01*
X49433Y396317D01*
X49600Y395900D01*
X49642Y395525D01*
X49558Y395150D01*
X49433Y394900D01*
X49183Y394650D01*
X48892Y394483D01*
X48600Y394400D01*
X48308D01*
X48017Y394483D01*
X47767Y394608D01*
X47558Y394775D01*
G01X46208Y394692D02*
X45917Y394483D01*
X45583Y394400D01*
X45250Y394483D01*
X44958Y394733D01*
X44750Y395108D01*
X44667Y395483D01*
Y395942D01*
X44750Y396317D01*
X44958Y396650D01*
X45208Y396817D01*
X45500Y396900D01*
X45833Y396817D01*
X46083Y396650D01*
X46250Y396400D01*
X46333Y396067D01*
X46250Y395775D01*
X46042Y395483D01*
X45792Y395317D01*
X45500Y395275D01*
X45167Y395358D01*
X44917Y395567D01*
X44667Y395942D01*
G01X43358Y394400D02*
Y396900D01*
X41442Y394400D01*
Y396900D01*
G01X39300Y394400D02*
Y396900D01*
X39800Y396400D01*
G01Y394400D02*
X38800D01*
G01X35700D02*
Y396900D01*
X37242Y395108D01*
X35158D01*
G01X47683Y393192D02*
X47933Y393317D01*
X48225Y393400D01*
X48558D01*
X48933Y393275D01*
X49225Y393067D01*
X49433Y392817D01*
X49600Y392400D01*
X49642Y392025D01*
X49558Y391650D01*
X49433Y391400D01*
X49183Y391150D01*
X48892Y390983D01*
X48600Y390900D01*
X48308D01*
X48017Y390983D01*
X47767Y391108D01*
X47558Y391275D01*
G01X46208Y391192D02*
X45917Y390983D01*
X45583Y390900D01*
X45250Y390983D01*
X44958Y391233D01*
X44750Y391608D01*
X44667Y391983D01*
Y392442D01*
X44750Y392817D01*
X44958Y393150D01*
X45208Y393317D01*
X45500Y393400D01*
X45833Y393317D01*
X46083Y393150D01*
X46250Y392900D01*
X46333Y392567D01*
X46250Y392275D01*
X46042Y391983D01*
X45792Y391817D01*
X45500Y391775D01*
X45167Y391858D01*
X44917Y392067D01*
X44667Y392442D01*
G01X43358Y390900D02*
Y393400D01*
X41442Y390900D01*
Y393400D01*
G01X39300Y390900D02*
Y393400D01*
X39800Y392900D01*
G01Y390900D02*
X38800D01*
G01X36992Y391942D02*
X36700Y392233D01*
X36450Y392400D01*
X36117Y392483D01*
X35825Y392400D01*
X35617Y392233D01*
X35450Y391983D01*
X35408Y391692D01*
X35450Y391442D01*
X35617Y391192D01*
X35867Y390983D01*
X36158Y390900D01*
X36492Y390983D01*
X36783Y391233D01*
X36950Y391608D01*
X36992Y392025D01*
X36908Y392567D01*
X36783Y392858D01*
X36575Y393150D01*
X36283Y393358D01*
X35992Y393400D01*
X35700Y393317D01*
X35492Y393108D01*
G01X47783Y383592D02*
X48033Y383717D01*
X48325Y383800D01*
X48658D01*
X49033Y383675D01*
X49325Y383467D01*
X49533Y383217D01*
X49700Y382800D01*
X49742Y382425D01*
X49658Y382050D01*
X49533Y381800D01*
X49283Y381550D01*
X48992Y381383D01*
X48700Y381300D01*
X48408D01*
X48117Y381383D01*
X47867Y381508D01*
X47658Y381675D01*
G01X46308Y381592D02*
X46017Y381383D01*
X45683Y381300D01*
X45350Y381383D01*
X45058Y381633D01*
X44850Y382008D01*
X44767Y382383D01*
Y382842D01*
X44850Y383217D01*
X45058Y383550D01*
X45308Y383717D01*
X45600Y383800D01*
X45933Y383717D01*
X46183Y383550D01*
X46350Y383300D01*
X46433Y382967D01*
X46350Y382675D01*
X46142Y382383D01*
X45892Y382217D01*
X45600Y382175D01*
X45267Y382258D01*
X45017Y382467D01*
X44767Y382842D01*
G01X43458Y381300D02*
Y383800D01*
X41542Y381300D01*
Y383800D01*
G01X39400Y381300D02*
Y383800D01*
X39900Y383300D01*
G01Y381300D02*
X38900D01*
G01X36300D02*
X36008Y381342D01*
X35675Y381467D01*
X35467Y381675D01*
X35383Y381967D01*
X35467Y382258D01*
X35717Y382508D01*
X36092Y382633D01*
X36508D01*
X36758Y382717D01*
X36967Y382925D01*
X37050Y383217D01*
X36925Y383508D01*
X36633Y383717D01*
X36300Y383800D01*
X35967Y383717D01*
X35675Y383508D01*
X35550Y383217D01*
X35633Y382925D01*
X35842Y382717D01*
X36092Y382633D01*
X36508D01*
X36883Y382508D01*
X37133Y382258D01*
X37217Y381967D01*
X37133Y381675D01*
X36925Y381467D01*
X36592Y381342D01*
X36300Y381300D01*
G01X52983Y376600D02*
Y379100D01*
X51942D01*
X51608Y378975D01*
X51400Y378808D01*
X51317Y378475D01*
X51400Y378142D01*
X51650Y377933D01*
X51942Y377808D01*
X52983D01*
G01X51942D02*
X51317Y376600D01*
G01X49842Y377642D02*
X49550Y377933D01*
X49300Y378100D01*
X48967Y378183D01*
X48675Y378100D01*
X48467Y377933D01*
X48300Y377683D01*
X48258Y377392D01*
X48300Y377142D01*
X48467Y376892D01*
X48717Y376683D01*
X49008Y376600D01*
X49342Y376683D01*
X49633Y376933D01*
X49800Y377308D01*
X49842Y377725D01*
X49758Y378267D01*
X49633Y378558D01*
X49425Y378850D01*
X49133Y379058D01*
X48842Y379100D01*
X48550Y379017D01*
X48342Y378808D01*
G01X47200Y379100D02*
X46617Y376600D01*
X45950Y379100D01*
X45283Y376600D01*
X44700Y379100D01*
G01X43767Y377100D02*
X43517Y376808D01*
X43183Y376642D01*
X42808Y376600D01*
X42475Y376642D01*
X42142Y376850D01*
X41933Y377100D01*
X41892Y377350D01*
X41975Y377642D01*
X42267Y377850D01*
X42558Y377933D01*
X42933D01*
G01X42558D02*
X42308Y378058D01*
X42100Y378267D01*
X42017Y378517D01*
X42100Y378767D01*
X42308Y378975D01*
X42683Y379100D01*
X43058Y379058D01*
X43433Y378892D01*
G01X48292Y366367D02*
X48417Y366117D01*
X48500Y365825D01*
Y365492D01*
X48375Y365117D01*
X48167Y364825D01*
X47917Y364617D01*
X47500Y364450D01*
X47125Y364408D01*
X46750Y364492D01*
X46500Y364617D01*
X46250Y364867D01*
X46083Y365158D01*
X46000Y365450D01*
Y365742D01*
X46083Y366033D01*
X46208Y366283D01*
X46375Y366492D01*
G01X46292Y367842D02*
X46083Y368133D01*
X46000Y368467D01*
X46083Y368800D01*
X46333Y369092D01*
X46708Y369300D01*
X47083Y369383D01*
X47542D01*
X47917Y369300D01*
X48250Y369092D01*
X48417Y368842D01*
X48500Y368550D01*
X48417Y368217D01*
X48250Y367967D01*
X48000Y367800D01*
X47667Y367717D01*
X47375Y367800D01*
X47083Y368008D01*
X46917Y368258D01*
X46875Y368550D01*
X46958Y368883D01*
X47167Y369133D01*
X47542Y369383D01*
G01X48500Y370400D02*
X46000Y370983D01*
X48500Y371650D01*
X46000Y372317D01*
X48500Y372900D01*
G01X48083Y373958D02*
X48333Y374208D01*
X48458Y374500D01*
X48500Y374833D01*
X48417Y375250D01*
X48208Y375542D01*
X47958Y375625D01*
X47708Y375583D01*
X47500Y375417D01*
X47083Y374583D01*
X46792Y374208D01*
X46375Y373958D01*
X46000Y373875D01*
Y375625D01*
G01X3900Y462822D02*
X6400D01*
Y463863D01*
X6275Y464197D01*
X6108Y464405D01*
X5775Y464488D01*
X5442Y464405D01*
X5233Y464155D01*
X5108Y463863D01*
Y462822D01*
G01Y463863D02*
X3900Y464488D01*
G01X4192Y466047D02*
X3983Y466338D01*
X3900Y466672D01*
X3983Y467005D01*
X4233Y467297D01*
X4608Y467505D01*
X4983Y467588D01*
X5442D01*
X5817Y467505D01*
X6150Y467297D01*
X6317Y467047D01*
X6400Y466755D01*
X6317Y466422D01*
X6150Y466172D01*
X5900Y466005D01*
X5567Y465922D01*
X5275Y466005D01*
X4983Y466213D01*
X4817Y466463D01*
X4775Y466755D01*
X4858Y467088D01*
X5067Y467338D01*
X5442Y467588D01*
G01X3900Y468772D02*
X6400D01*
X4317Y469855D01*
X6400Y470938D01*
X3900D01*
G01Y472955D02*
X6400D01*
X5900Y472455D01*
G01X3900D02*
Y473455D01*
G01X4942Y475263D02*
X5233Y475555D01*
X5400Y475805D01*
X5483Y476138D01*
X5400Y476430D01*
X5233Y476638D01*
X4983Y476805D01*
X4692Y476847D01*
X4442Y476805D01*
X4192Y476638D01*
X3983Y476388D01*
X3900Y476097D01*
X3983Y475763D01*
X4233Y475472D01*
X4608Y475305D01*
X5025Y475263D01*
X5567Y475347D01*
X5858Y475472D01*
X6150Y475680D01*
X6358Y475972D01*
X6400Y476263D01*
X6317Y476555D01*
X6108Y476763D01*
G01X400Y462822D02*
X2900D01*
Y463863D01*
X2775Y464197D01*
X2608Y464405D01*
X2275Y464488D01*
X1942Y464405D01*
X1733Y464155D01*
X1608Y463863D01*
Y462822D01*
G01Y463863D02*
X400Y464488D01*
G01X692Y466047D02*
X483Y466338D01*
X400Y466672D01*
X483Y467005D01*
X733Y467297D01*
X1108Y467505D01*
X1483Y467588D01*
X1942D01*
X2317Y467505D01*
X2650Y467297D01*
X2817Y467047D01*
X2900Y466755D01*
X2817Y466422D01*
X2650Y466172D01*
X2400Y466005D01*
X2067Y465922D01*
X1775Y466005D01*
X1483Y466213D01*
X1317Y466463D01*
X1275Y466755D01*
X1358Y467088D01*
X1567Y467338D01*
X1942Y467588D01*
G01X400Y468772D02*
X2900D01*
X817Y469855D01*
X2900Y470938D01*
X400D01*
G01Y472955D02*
X2900D01*
X2400Y472455D01*
G01X400D02*
Y473455D01*
G01Y475972D02*
X942Y476055D01*
X1400Y476180D01*
X1817Y476347D01*
X2275Y476555D01*
X2900Y476888D01*
Y475222D01*
G01X47933Y411292D02*
X48183Y411417D01*
X48475Y411500D01*
X48808D01*
X49183Y411375D01*
X49475Y411167D01*
X49683Y410917D01*
X49850Y410500D01*
X49892Y410125D01*
X49808Y409750D01*
X49683Y409500D01*
X49433Y409250D01*
X49142Y409083D01*
X48850Y409000D01*
X48558D01*
X48267Y409083D01*
X48017Y409208D01*
X47808Y409375D01*
G01X46458Y409292D02*
X46167Y409083D01*
X45833Y409000D01*
X45500Y409083D01*
X45208Y409333D01*
X45000Y409708D01*
X44917Y410083D01*
Y410542D01*
X45000Y410917D01*
X45208Y411250D01*
X45458Y411417D01*
X45750Y411500D01*
X46083Y411417D01*
X46333Y411250D01*
X46500Y411000D01*
X46583Y410667D01*
X46500Y410375D01*
X46292Y410083D01*
X46042Y409917D01*
X45750Y409875D01*
X45417Y409958D01*
X45167Y410167D01*
X44917Y410542D01*
G01X43608Y409000D02*
Y411500D01*
X41692Y409000D01*
Y411500D01*
G01X39550Y409000D02*
X39258Y409042D01*
X38925Y409167D01*
X38717Y409375D01*
X38633Y409667D01*
X38717Y409958D01*
X38967Y410208D01*
X39342Y410333D01*
X39758D01*
X40008Y410417D01*
X40217Y410625D01*
X40300Y410917D01*
X40175Y411208D01*
X39883Y411417D01*
X39550Y411500D01*
X39217Y411417D01*
X38925Y411208D01*
X38800Y410917D01*
X38883Y410625D01*
X39092Y410417D01*
X39342Y410333D01*
X39758D01*
X40133Y410208D01*
X40383Y409958D01*
X40467Y409667D01*
X40383Y409375D01*
X40175Y409167D01*
X39842Y409042D01*
X39550Y409000D01*
G01X47933Y407792D02*
X48183Y407917D01*
X48475Y408000D01*
X48808D01*
X49183Y407875D01*
X49475Y407667D01*
X49683Y407417D01*
X49850Y407000D01*
X49892Y406625D01*
X49808Y406250D01*
X49683Y406000D01*
X49433Y405750D01*
X49142Y405583D01*
X48850Y405500D01*
X48558D01*
X48267Y405583D01*
X48017Y405708D01*
X47808Y405875D01*
G01X46458Y405792D02*
X46167Y405583D01*
X45833Y405500D01*
X45500Y405583D01*
X45208Y405833D01*
X45000Y406208D01*
X44917Y406583D01*
Y407042D01*
X45000Y407417D01*
X45208Y407750D01*
X45458Y407917D01*
X45750Y408000D01*
X46083Y407917D01*
X46333Y407750D01*
X46500Y407500D01*
X46583Y407167D01*
X46500Y406875D01*
X46292Y406583D01*
X46042Y406417D01*
X45750Y406375D01*
X45417Y406458D01*
X45167Y406667D01*
X44917Y407042D01*
G01X43608Y405500D02*
Y408000D01*
X41692Y405500D01*
Y408000D01*
G01X39550Y405500D02*
Y408000D01*
X40050Y407500D01*
G01Y405500D02*
X39050D01*
G01X36450Y408000D02*
X36783Y407917D01*
X37033Y407708D01*
X37200Y407458D01*
X37325Y407125D01*
X37367Y406750D01*
X37325Y406375D01*
X37200Y406042D01*
X37033Y405792D01*
X36783Y405583D01*
X36450Y405500D01*
X36117Y405583D01*
X35867Y405792D01*
X35700Y406042D01*
X35575Y406375D01*
X35533Y406750D01*
X35575Y407125D01*
X35700Y407458D01*
X35867Y407708D01*
X36117Y407917D01*
X36450Y408000D01*
G01X-3717Y440675D02*
X-3467Y440800D01*
X-3175Y440883D01*
X-2842D01*
X-2467Y440758D01*
X-2175Y440550D01*
X-1967Y440300D01*
X-1800Y439883D01*
X-1758Y439508D01*
X-1842Y439133D01*
X-1967Y438883D01*
X-2217Y438633D01*
X-2508Y438466D01*
X-2800Y438383D01*
X-3092D01*
X-3383Y438466D01*
X-3633Y438591D01*
X-3842Y438758D01*
G01X-5192Y438675D02*
X-5483Y438466D01*
X-5817Y438383D01*
X-6150Y438466D01*
X-6442Y438716D01*
X-6650Y439091D01*
X-6733Y439466D01*
Y439925D01*
X-6650Y440300D01*
X-6442Y440633D01*
X-6192Y440800D01*
X-5900Y440883D01*
X-5567Y440800D01*
X-5317Y440633D01*
X-5150Y440383D01*
X-5067Y440050D01*
X-5150Y439758D01*
X-5358Y439466D01*
X-5608Y439300D01*
X-5900Y439258D01*
X-6233Y439341D01*
X-6483Y439550D01*
X-6733Y439925D01*
G01X-7917Y438383D02*
Y440883D01*
X-9000Y438800D01*
X-10083Y440883D01*
Y438383D01*
G01X-11392Y438675D02*
X-11683Y438466D01*
X-12017Y438383D01*
X-12350Y438466D01*
X-12642Y438716D01*
X-12850Y439091D01*
X-12933Y439466D01*
Y439925D01*
X-12850Y440300D01*
X-12642Y440633D01*
X-12392Y440800D01*
X-12100Y440883D01*
X-11767Y440800D01*
X-11517Y440633D01*
X-11350Y440383D01*
X-11267Y440050D01*
X-11350Y439758D01*
X-11558Y439466D01*
X-11808Y439300D01*
X-12100Y439258D01*
X-12433Y439341D01*
X-12683Y439550D01*
X-12933Y439925D01*
G01X-1183Y466449D02*
X-1058Y466199D01*
X-975Y465907D01*
Y465574D01*
X-1100Y465199D01*
X-1308Y464907D01*
X-1558Y464699D01*
X-1975Y464532D01*
X-2350Y464490D01*
X-2725Y464574D01*
X-2975Y464699D01*
X-3225Y464949D01*
X-3392Y465240D01*
X-3475Y465532D01*
Y465824D01*
X-3392Y466115D01*
X-3267Y466365D01*
X-3100Y466574D01*
G01X-3183Y467924D02*
X-3392Y468215D01*
X-3475Y468549D01*
X-3392Y468882D01*
X-3142Y469174D01*
X-2767Y469382D01*
X-2392Y469465D01*
X-1933D01*
X-1558Y469382D01*
X-1225Y469174D01*
X-1058Y468924D01*
X-975Y468632D01*
X-1058Y468299D01*
X-1225Y468049D01*
X-1475Y467882D01*
X-1808Y467799D01*
X-2100Y467882D01*
X-2392Y468090D01*
X-2558Y468340D01*
X-2600Y468632D01*
X-2517Y468965D01*
X-2308Y469215D01*
X-1933Y469465D01*
G01X-3475Y470649D02*
X-975D01*
X-3058Y471732D01*
X-975Y472815D01*
X-3475D01*
G01Y474832D02*
X-3433Y475124D01*
X-3308Y475457D01*
X-3100Y475665D01*
X-2808Y475749D01*
X-2517Y475665D01*
X-2267Y475415D01*
X-2142Y475040D01*
Y474624D01*
X-2058Y474374D01*
X-1850Y474165D01*
X-1558Y474082D01*
X-1267Y474207D01*
X-1058Y474499D01*
X-975Y474832D01*
X-1058Y475165D01*
X-1267Y475457D01*
X-1558Y475582D01*
X-1850Y475499D01*
X-2058Y475290D01*
X-2142Y475040D01*
Y474624D01*
X-2267Y474249D01*
X-2517Y473999D01*
X-2808Y473915D01*
X-3100Y473999D01*
X-3308Y474207D01*
X-3433Y474540D01*
X-3475Y474832D01*
G01X17250Y442700D02*
X17583Y442742D01*
X17875Y442908D01*
X18125Y443158D01*
X18292Y443450D01*
X18375Y443783D01*
Y444117D01*
X18292Y444450D01*
X18125Y444742D01*
X17875Y444992D01*
X17583Y445158D01*
X17250Y445200D01*
X16917Y445158D01*
X16625Y444992D01*
X16375Y444742D01*
X16208Y444450D01*
X16125Y444117D01*
Y443783D01*
X16208Y443450D01*
X16375Y443158D01*
X16625Y442908D01*
X16917Y442742D01*
X17250Y442700D01*
G01X16917Y443367D02*
X16417Y442700D01*
G01X14150D02*
Y445200D01*
X14650Y444700D01*
G01Y442700D02*
X13650D01*
G01X10717Y444033D02*
X10550Y444158D01*
X10425Y444367D01*
X10342Y444658D01*
X10425Y444908D01*
X10592Y445075D01*
X10883Y445200D01*
X12008D01*
Y442700D01*
X10633D01*
X10342Y442867D01*
X10175Y443117D01*
X10092Y443408D01*
X10175Y443700D01*
X10425Y443950D01*
X10717Y444033D01*
X12008D01*
G01X7950Y442700D02*
Y445200D01*
X8450Y444700D01*
G01Y442700D02*
X7450D01*
G01X18266Y447377D02*
X4880D01*
G01X18266Y460763D02*
X4880D01*
G01X2593Y518969D02*
X5093D01*
Y520010D01*
X4968Y520344D01*
X4801Y520552D01*
X4468Y520635D01*
X4135Y520552D01*
X3926Y520302D01*
X3801Y520010D01*
Y518969D01*
G01Y520010D02*
X2593Y520635D01*
G01X2885Y522194D02*
X2676Y522485D01*
X2593Y522819D01*
X2676Y523152D01*
X2926Y523444D01*
X3301Y523652D01*
X3676Y523735D01*
X4135D01*
X4510Y523652D01*
X4843Y523444D01*
X5010Y523194D01*
X5093Y522902D01*
X5010Y522569D01*
X4843Y522319D01*
X4593Y522152D01*
X4260Y522069D01*
X3968Y522152D01*
X3676Y522360D01*
X3510Y522610D01*
X3468Y522902D01*
X3551Y523235D01*
X3760Y523485D01*
X4135Y523735D01*
G01X2593Y524919D02*
X5093D01*
X3010Y526002D01*
X5093Y527085D01*
X2593D01*
G01X2968Y528185D02*
X2760Y528435D01*
X2635Y528727D01*
X2593Y529102D01*
X2676Y529477D01*
X2843Y529769D01*
X3135Y529977D01*
X3468Y530019D01*
X3801Y529935D01*
X4010Y529727D01*
X4176Y529435D01*
X4218Y529144D01*
X4176Y528852D01*
X4010Y528477D01*
X5093Y528602D01*
Y529727D01*
G01X-7538Y526552D02*
X-5038D01*
Y527593D01*
X-5163Y527927D01*
X-5330Y528135D01*
X-5663Y528218D01*
X-5996Y528135D01*
X-6205Y527885D01*
X-6330Y527593D01*
Y526552D01*
G01Y527593D02*
X-7538Y528218D01*
G01X-7246Y529777D02*
X-7455Y530068D01*
X-7538Y530402D01*
X-7455Y530735D01*
X-7205Y531027D01*
X-6830Y531235D01*
X-6455Y531318D01*
X-5996D01*
X-5621Y531235D01*
X-5288Y531027D01*
X-5121Y530777D01*
X-5038Y530485D01*
X-5121Y530152D01*
X-5288Y529902D01*
X-5538Y529735D01*
X-5871Y529652D01*
X-6163Y529735D01*
X-6455Y529943D01*
X-6621Y530193D01*
X-6663Y530485D01*
X-6580Y530818D01*
X-6371Y531068D01*
X-5996Y531318D01*
G01X-7538Y532502D02*
X-5038D01*
X-7121Y533585D01*
X-5038Y534668D01*
X-7538D01*
G01X-7246Y535977D02*
X-7455Y536268D01*
X-7538Y536602D01*
X-7455Y536935D01*
X-7205Y537227D01*
X-6830Y537435D01*
X-6455Y537518D01*
X-5996D01*
X-5621Y537435D01*
X-5288Y537227D01*
X-5121Y536977D01*
X-5038Y536685D01*
X-5121Y536352D01*
X-5288Y536102D01*
X-5538Y535935D01*
X-5871Y535852D01*
X-6163Y535935D01*
X-6455Y536143D01*
X-6621Y536393D01*
X-6663Y536685D01*
X-6580Y537018D01*
X-6371Y537268D01*
X-5996Y537518D01*
G01X30567Y523717D02*
X33067D01*
Y524758D01*
X32942Y525092D01*
X32775Y525300D01*
X32442Y525383D01*
X32109Y525300D01*
X31900Y525050D01*
X31775Y524758D01*
Y523717D01*
G01Y524758D02*
X30567Y525383D01*
G01X30859Y526942D02*
X30650Y527233D01*
X30567Y527567D01*
X30650Y527900D01*
X30900Y528192D01*
X31275Y528400D01*
X31650Y528483D01*
X32109D01*
X32484Y528400D01*
X32817Y528192D01*
X32984Y527942D01*
X33067Y527650D01*
X32984Y527317D01*
X32817Y527067D01*
X32567Y526900D01*
X32234Y526817D01*
X31942Y526900D01*
X31650Y527108D01*
X31484Y527358D01*
X31442Y527650D01*
X31525Y527983D01*
X31734Y528233D01*
X32109Y528483D01*
G01X30567Y529667D02*
X33067D01*
X30984Y530750D01*
X33067Y531833D01*
X30567D01*
G01X31067Y532933D02*
X30775Y533183D01*
X30609Y533517D01*
X30567Y533892D01*
X30609Y534225D01*
X30817Y534558D01*
X31067Y534767D01*
X31317Y534808D01*
X31609Y534725D01*
X31817Y534433D01*
X31900Y534142D01*
Y533767D01*
G01Y534142D02*
X32025Y534392D01*
X32234Y534600D01*
X32484Y534683D01*
X32734Y534600D01*
X32942Y534392D01*
X33067Y534017D01*
X33025Y533642D01*
X32859Y533267D01*
G01X6883Y501400D02*
Y503900D01*
X5842D01*
X5508Y503775D01*
X5300Y503608D01*
X5217Y503275D01*
X5300Y502942D01*
X5550Y502733D01*
X5842Y502608D01*
X6883D01*
G01X5842D02*
X5217Y501400D01*
G01X3658Y501692D02*
X3367Y501483D01*
X3033Y501400D01*
X2700Y501483D01*
X2408Y501733D01*
X2200Y502108D01*
X2117Y502483D01*
Y502942D01*
X2200Y503317D01*
X2408Y503650D01*
X2658Y503817D01*
X2950Y503900D01*
X3283Y503817D01*
X3533Y503650D01*
X3700Y503400D01*
X3783Y503067D01*
X3700Y502775D01*
X3492Y502483D01*
X3242Y502317D01*
X2950Y502275D01*
X2617Y502358D01*
X2367Y502567D01*
X2117Y502942D01*
G01X933Y501400D02*
Y503900D01*
X-150Y501817D01*
X-1233Y503900D01*
Y501400D01*
G01X-3167D02*
X-3250Y501942D01*
X-3375Y502400D01*
X-3542Y502817D01*
X-3750Y503275D01*
X-4083Y503900D01*
X-2417D01*
G01X-10098Y483958D02*
X-7598D01*
Y484999D01*
X-7723Y485333D01*
X-7890Y485541D01*
X-8223Y485624D01*
X-8556Y485541D01*
X-8765Y485291D01*
X-8890Y484999D01*
Y483958D01*
G01Y484999D02*
X-10098Y485624D01*
G01X-9806Y487183D02*
X-10015Y487474D01*
X-10098Y487808D01*
X-10015Y488141D01*
X-9765Y488433D01*
X-9390Y488641D01*
X-9015Y488724D01*
X-8556D01*
X-8181Y488641D01*
X-7848Y488433D01*
X-7681Y488183D01*
X-7598Y487891D01*
X-7681Y487558D01*
X-7848Y487308D01*
X-8098Y487141D01*
X-8431Y487058D01*
X-8723Y487141D01*
X-9015Y487349D01*
X-9181Y487599D01*
X-9223Y487891D01*
X-9140Y488224D01*
X-8931Y488474D01*
X-8556Y488724D01*
G01X-10098Y489908D02*
X-7598D01*
X-9681Y490991D01*
X-7598Y492074D01*
X-10098D01*
G01Y494091D02*
X-7598D01*
X-8098Y493591D01*
G01X-10098D02*
Y494591D01*
G01X-9598Y496274D02*
X-9890Y496524D01*
X-10056Y496858D01*
X-10098Y497233D01*
X-10056Y497566D01*
X-9848Y497899D01*
X-9598Y498108D01*
X-9348Y498149D01*
X-9056Y498066D01*
X-8848Y497774D01*
X-8765Y497483D01*
Y497108D01*
G01Y497483D02*
X-8640Y497733D01*
X-8431Y497941D01*
X-8181Y498024D01*
X-7931Y497941D01*
X-7723Y497733D01*
X-7598Y497358D01*
X-7640Y496983D01*
X-7806Y496608D01*
G01X6883Y504900D02*
Y507400D01*
X5842D01*
X5508Y507275D01*
X5300Y507108D01*
X5217Y506775D01*
X5300Y506442D01*
X5550Y506233D01*
X5842Y506108D01*
X6883D01*
G01X5842D02*
X5217Y504900D01*
G01X3658Y505192D02*
X3367Y504983D01*
X3033Y504900D01*
X2700Y504983D01*
X2408Y505233D01*
X2200Y505608D01*
X2117Y505983D01*
Y506442D01*
X2200Y506817D01*
X2408Y507150D01*
X2658Y507317D01*
X2950Y507400D01*
X3283Y507317D01*
X3533Y507150D01*
X3700Y506900D01*
X3783Y506567D01*
X3700Y506275D01*
X3492Y505983D01*
X3242Y505817D01*
X2950Y505775D01*
X2617Y505858D01*
X2367Y506067D01*
X2117Y506442D01*
G01X933Y504900D02*
Y507400D01*
X-150Y505317D01*
X-1233Y507400D01*
Y504900D01*
G01X-2458Y505942D02*
X-2750Y506233D01*
X-3000Y506400D01*
X-3333Y506483D01*
X-3625Y506400D01*
X-3833Y506233D01*
X-4000Y505983D01*
X-4042Y505692D01*
X-4000Y505442D01*
X-3833Y505192D01*
X-3583Y504983D01*
X-3292Y504900D01*
X-2958Y504983D01*
X-2667Y505233D01*
X-2500Y505608D01*
X-2458Y506025D01*
X-2542Y506567D01*
X-2667Y506858D01*
X-2875Y507150D01*
X-3167Y507358D01*
X-3458Y507400D01*
X-3750Y507317D01*
X-3958Y507108D01*
G01X40333Y477259D02*
X40583Y477384D01*
X40875Y477467D01*
X41208D01*
X41583Y477342D01*
X41875Y477134D01*
X42083Y476884D01*
X42250Y476467D01*
X42292Y476092D01*
X42208Y475717D01*
X42083Y475467D01*
X41833Y475217D01*
X41542Y475050D01*
X41250Y474967D01*
X40958D01*
X40667Y475050D01*
X40417Y475175D01*
X40208Y475342D01*
G01X38858Y475259D02*
X38567Y475050D01*
X38233Y474967D01*
X37900Y475050D01*
X37608Y475300D01*
X37400Y475675D01*
X37317Y476050D01*
Y476509D01*
X37400Y476884D01*
X37608Y477217D01*
X37858Y477384D01*
X38150Y477467D01*
X38483Y477384D01*
X38733Y477217D01*
X38900Y476967D01*
X38983Y476634D01*
X38900Y476342D01*
X38692Y476050D01*
X38442Y475884D01*
X38150Y475842D01*
X37817Y475925D01*
X37567Y476134D01*
X37317Y476509D01*
G01X36133Y474967D02*
Y477467D01*
X35050Y475384D01*
X33967Y477467D01*
Y474967D01*
G01X32742Y476009D02*
X32450Y476300D01*
X32200Y476467D01*
X31867Y476550D01*
X31575Y476467D01*
X31367Y476300D01*
X31200Y476050D01*
X31158Y475759D01*
X31200Y475509D01*
X31367Y475259D01*
X31617Y475050D01*
X31908Y474967D01*
X32242Y475050D01*
X32533Y475300D01*
X32700Y475675D01*
X32742Y476092D01*
X32658Y476634D01*
X32533Y476925D01*
X32325Y477217D01*
X32033Y477425D01*
X31742Y477467D01*
X31450Y477384D01*
X31242Y477175D01*
G01X45183Y525350D02*
Y527850D01*
X44142D01*
X43808Y527725D01*
X43600Y527558D01*
X43517Y527225D01*
X43600Y526892D01*
X43850Y526683D01*
X44142Y526558D01*
X45183D01*
G01X44142D02*
X43517Y525350D01*
G01X41958Y525642D02*
X41667Y525433D01*
X41333Y525350D01*
X41000Y525433D01*
X40708Y525683D01*
X40500Y526058D01*
X40417Y526433D01*
Y526892D01*
X40500Y527267D01*
X40708Y527600D01*
X40958Y527767D01*
X41250Y527850D01*
X41583Y527767D01*
X41833Y527600D01*
X42000Y527350D01*
X42083Y527017D01*
X42000Y526725D01*
X41792Y526433D01*
X41542Y526267D01*
X41250Y526225D01*
X40917Y526308D01*
X40667Y526517D01*
X40417Y526892D01*
G01X39233Y525350D02*
Y527850D01*
X38150Y525767D01*
X37067Y527850D01*
Y525350D01*
G01X34550D02*
Y527850D01*
X36092Y526058D01*
X34008D01*
G01X44687Y512050D02*
X40362D01*
G01X44684Y519150D02*
X40242D01*
G01X23167Y487400D02*
X24833D01*
Y489900D01*
X23167D01*
G01X23833Y488692D02*
X24833D01*
G01X21817Y489900D02*
Y488108D01*
X21650Y487733D01*
X21317Y487483D01*
X20900Y487400D01*
X20483Y487483D01*
X20150Y487733D01*
X19983Y488108D01*
Y489900D01*
G01X18508Y487692D02*
X18217Y487483D01*
X17883Y487400D01*
X17550Y487483D01*
X17258Y487733D01*
X17050Y488108D01*
X16967Y488483D01*
Y488942D01*
X17050Y489317D01*
X17258Y489650D01*
X17508Y489817D01*
X17800Y489900D01*
X18133Y489817D01*
X18383Y489650D01*
X18550Y489400D01*
X18633Y489067D01*
X18550Y488775D01*
X18342Y488483D01*
X18092Y488317D01*
X17800Y488275D01*
X17467Y488358D01*
X17217Y488567D01*
X16967Y488942D01*
G01X15783Y487400D02*
Y489900D01*
X14700Y487817D01*
X13617Y489900D01*
Y487400D01*
G01X11600D02*
Y489900D01*
X12100Y489400D01*
G01Y487400D02*
X11100D01*
G01X8842Y480802D02*
X9203Y481070D01*
X9410Y481300D01*
X9513Y481607D01*
X9410Y481875D01*
X9203Y482067D01*
X8893Y482220D01*
X8532Y482258D01*
X8222Y482220D01*
X7912Y482067D01*
X7653Y481837D01*
X7550Y481568D01*
X7653Y481262D01*
X7963Y480993D01*
X8428Y480840D01*
X8945Y480802D01*
X9617Y480878D01*
X9978Y480993D01*
X10340Y481185D01*
X10598Y481453D01*
X10650Y481722D01*
X10547Y481990D01*
X10288Y482182D01*
G01X36283Y505150D02*
Y507650D01*
X35242D01*
X34908Y507525D01*
X34700Y507358D01*
X34617Y507025D01*
X34700Y506692D01*
X34950Y506483D01*
X35242Y506358D01*
X36283D01*
G01X35242D02*
X34617Y505150D01*
G01X32350D02*
Y507650D01*
X32850Y507150D01*
G01Y505150D02*
X31850D01*
G01X30042Y507233D02*
X29792Y507483D01*
X29500Y507608D01*
X29167Y507650D01*
X28750Y507567D01*
X28458Y507358D01*
X28375Y507108D01*
X28417Y506858D01*
X28583Y506650D01*
X29417Y506233D01*
X29792Y505942D01*
X30042Y505525D01*
X30125Y505150D01*
X28375D01*
G01X27400Y507650D02*
X26817Y505150D01*
X26150Y507650D01*
X25483Y505150D01*
X24900Y507650D01*
G01X23050Y505150D02*
Y507650D01*
X23550Y507150D01*
G01Y505150D02*
X22550D01*
G01X19950D02*
X19658Y505192D01*
X19325Y505317D01*
X19117Y505525D01*
X19033Y505817D01*
X19117Y506108D01*
X19367Y506358D01*
X19742Y506483D01*
X20158D01*
X20408Y506567D01*
X20617Y506775D01*
X20700Y507067D01*
X20575Y507358D01*
X20283Y507567D01*
X19950Y507650D01*
X19617Y507567D01*
X19325Y507358D01*
X19200Y507067D01*
X19283Y506775D01*
X19492Y506567D01*
X19742Y506483D01*
X20158D01*
X20533Y506358D01*
X20783Y506108D01*
X20867Y505817D01*
X20783Y505525D01*
X20575Y505317D01*
X20242Y505192D01*
X19950Y505150D01*
G01X42100Y505100D02*
Y509100D01*
X49500D01*
G01X24290Y527988D02*
X24540Y528113D01*
X24832Y528196D01*
X25165D01*
X25540Y528071D01*
X25832Y527863D01*
X26040Y527613D01*
X26207Y527196D01*
X26249Y526821D01*
X26165Y526446D01*
X26040Y526196D01*
X25790Y525946D01*
X25499Y525779D01*
X25207Y525696D01*
X24915D01*
X24624Y525779D01*
X24374Y525904D01*
X24165Y526071D01*
G01X22107Y525696D02*
Y528196D01*
X22607Y527696D01*
G01Y525696D02*
X21607D01*
G01X20049D02*
X19007Y528196D01*
X17965Y525696D01*
G01X18340Y526571D02*
X19674D01*
G01X16699Y527779D02*
X16449Y528029D01*
X16157Y528154D01*
X15824Y528196D01*
X15407Y528113D01*
X15115Y527904D01*
X15032Y527654D01*
X15074Y527404D01*
X15240Y527196D01*
X16074Y526779D01*
X16449Y526488D01*
X16699Y526071D01*
X16782Y525696D01*
X15032D01*
G01X25600Y491800D02*
X25933Y491842D01*
X26225Y492008D01*
X26475Y492258D01*
X26642Y492550D01*
X26725Y492883D01*
Y493217D01*
X26642Y493550D01*
X26475Y493842D01*
X26225Y494092D01*
X25933Y494258D01*
X25600Y494300D01*
X25267Y494258D01*
X24975Y494092D01*
X24725Y493842D01*
X24558Y493550D01*
X24475Y493217D01*
Y492883D01*
X24558Y492550D01*
X24725Y492258D01*
X24975Y492008D01*
X25267Y491842D01*
X25600Y491800D01*
G01X25267Y492467D02*
X24767Y491800D01*
G01X22500D02*
Y494300D01*
X23000Y493800D01*
G01Y491800D02*
X22000D01*
G01X20192Y493883D02*
X19942Y494133D01*
X19650Y494258D01*
X19317Y494300D01*
X18900Y494217D01*
X18608Y494008D01*
X18525Y493758D01*
X18567Y493508D01*
X18733Y493300D01*
X19567Y492883D01*
X19942Y492592D01*
X20192Y492175D01*
X20275Y491800D01*
X18525D01*
G01X17550Y494300D02*
X16967Y491800D01*
X16300Y494300D01*
X15633Y491800D01*
X15050Y494300D01*
G01X12700Y491800D02*
Y494300D01*
X14242Y492508D01*
X12158D01*
G01X47600Y492121D02*
X35858D01*
Y491479D01*
X47600D01*
Y492121D01*
X46200Y491800D01*
X47600Y491479D01*
G01X31833Y583666D02*
X32083Y583791D01*
X32375Y583874D01*
X32708D01*
X33083Y583749D01*
X33375Y583541D01*
X33583Y583291D01*
X33750Y582874D01*
X33792Y582499D01*
X33708Y582124D01*
X33583Y581874D01*
X33333Y581624D01*
X33042Y581457D01*
X32750Y581374D01*
X32458D01*
X32167Y581457D01*
X31917Y581582D01*
X31708Y581749D01*
G01X30358Y581666D02*
X30067Y581457D01*
X29733Y581374D01*
X29400Y581457D01*
X29108Y581707D01*
X28900Y582082D01*
X28817Y582457D01*
Y582916D01*
X28900Y583291D01*
X29108Y583624D01*
X29358Y583791D01*
X29650Y583874D01*
X29983Y583791D01*
X30233Y583624D01*
X30400Y583374D01*
X30483Y583041D01*
X30400Y582749D01*
X30192Y582457D01*
X29942Y582291D01*
X29650Y582249D01*
X29317Y582332D01*
X29067Y582541D01*
X28817Y582916D01*
G01X27383Y583874D02*
Y581374D01*
X25717D01*
G01X23450D02*
Y583874D01*
X23950Y583374D01*
G01Y581374D02*
X22950D01*
G01X19850D02*
Y583874D01*
X21392Y582082D01*
X19308D01*
G01X31598Y588808D02*
X31848Y588933D01*
X32140Y589016D01*
X32473D01*
X32848Y588891D01*
X33140Y588683D01*
X33348Y588433D01*
X33515Y588016D01*
X33557Y587641D01*
X33473Y587266D01*
X33348Y587016D01*
X33098Y586766D01*
X32807Y586599D01*
X32515Y586516D01*
X32223D01*
X31932Y586599D01*
X31682Y586724D01*
X31473Y586891D01*
G01X30123Y586808D02*
X29832Y586599D01*
X29498Y586516D01*
X29165Y586599D01*
X28873Y586849D01*
X28665Y587224D01*
X28582Y587599D01*
Y588058D01*
X28665Y588433D01*
X28873Y588766D01*
X29123Y588933D01*
X29415Y589016D01*
X29748Y588933D01*
X29998Y588766D01*
X30165Y588516D01*
X30248Y588183D01*
X30165Y587891D01*
X29957Y587599D01*
X29707Y587433D01*
X29415Y587391D01*
X29082Y587474D01*
X28832Y587683D01*
X28582Y588058D01*
G01X27148Y589016D02*
Y586516D01*
X25482D01*
G01X24132Y586891D02*
X23882Y586683D01*
X23590Y586558D01*
X23215Y586516D01*
X22840Y586599D01*
X22548Y586766D01*
X22340Y587058D01*
X22298Y587391D01*
X22382Y587724D01*
X22590Y587933D01*
X22882Y588099D01*
X23173Y588141D01*
X23465Y588099D01*
X23840Y587933D01*
X23715Y589016D01*
X22590D01*
G01X31989Y578446D02*
X32239Y578571D01*
X32531Y578654D01*
X32864D01*
X33239Y578529D01*
X33531Y578321D01*
X33739Y578071D01*
X33906Y577654D01*
X33948Y577279D01*
X33864Y576904D01*
X33739Y576654D01*
X33489Y576404D01*
X33198Y576237D01*
X32906Y576154D01*
X32614D01*
X32323Y576237D01*
X32073Y576362D01*
X31864Y576529D01*
G01X30514Y576446D02*
X30223Y576237D01*
X29889Y576154D01*
X29556Y576237D01*
X29264Y576487D01*
X29056Y576862D01*
X28973Y577237D01*
Y577696D01*
X29056Y578071D01*
X29264Y578404D01*
X29514Y578571D01*
X29806Y578654D01*
X30139Y578571D01*
X30389Y578404D01*
X30556Y578154D01*
X30639Y577821D01*
X30556Y577529D01*
X30348Y577237D01*
X30098Y577071D01*
X29806Y577029D01*
X29473Y577112D01*
X29223Y577321D01*
X28973Y577696D01*
G01X27539Y578654D02*
Y576154D01*
X25873D01*
G01X23606D02*
Y578654D01*
X24106Y578154D01*
G01Y576154D02*
X23106D01*
G01X21423Y576654D02*
X21173Y576362D01*
X20839Y576196D01*
X20464Y576154D01*
X20131Y576196D01*
X19798Y576404D01*
X19589Y576654D01*
X19548Y576904D01*
X19631Y577196D01*
X19923Y577404D01*
X20214Y577487D01*
X20589D01*
G01X20214D02*
X19964Y577612D01*
X19756Y577821D01*
X19673Y578071D01*
X19756Y578321D01*
X19964Y578529D01*
X20339Y578654D01*
X20714Y578612D01*
X21089Y578446D01*
G01X31083Y553692D02*
X31333Y553817D01*
X31625Y553900D01*
X31958D01*
X32333Y553775D01*
X32625Y553567D01*
X32833Y553317D01*
X33000Y552900D01*
X33042Y552525D01*
X32958Y552150D01*
X32833Y551900D01*
X32583Y551650D01*
X32292Y551483D01*
X32000Y551400D01*
X31708D01*
X31417Y551483D01*
X31167Y551608D01*
X30958Y551775D01*
G01X29608Y551692D02*
X29317Y551483D01*
X28983Y551400D01*
X28650Y551483D01*
X28358Y551733D01*
X28150Y552108D01*
X28067Y552483D01*
Y552942D01*
X28150Y553317D01*
X28358Y553650D01*
X28608Y553817D01*
X28900Y553900D01*
X29233Y553817D01*
X29483Y553650D01*
X29650Y553400D01*
X29733Y553067D01*
X29650Y552775D01*
X29442Y552483D01*
X29192Y552317D01*
X28900Y552275D01*
X28567Y552358D01*
X28317Y552567D01*
X28067Y552942D01*
G01X26633Y553900D02*
Y551400D01*
X24967D01*
G01X22700D02*
Y553900D01*
X23200Y553400D01*
G01Y551400D02*
X22200D01*
G01X19600D02*
Y553900D01*
X20100Y553400D01*
G01Y551400D02*
X19100D01*
G01X31083Y550192D02*
X31333Y550317D01*
X31625Y550400D01*
X31958D01*
X32333Y550275D01*
X32625Y550067D01*
X32833Y549817D01*
X33000Y549400D01*
X33042Y549025D01*
X32958Y548650D01*
X32833Y548400D01*
X32583Y548150D01*
X32292Y547983D01*
X32000Y547900D01*
X31708D01*
X31417Y547983D01*
X31167Y548108D01*
X30958Y548275D01*
G01X29608Y548192D02*
X29317Y547983D01*
X28983Y547900D01*
X28650Y547983D01*
X28358Y548233D01*
X28150Y548608D01*
X28067Y548983D01*
Y549442D01*
X28150Y549817D01*
X28358Y550150D01*
X28608Y550317D01*
X28900Y550400D01*
X29233Y550317D01*
X29483Y550150D01*
X29650Y549900D01*
X29733Y549567D01*
X29650Y549275D01*
X29442Y548983D01*
X29192Y548817D01*
X28900Y548775D01*
X28567Y548858D01*
X28317Y549067D01*
X28067Y549442D01*
G01X26633Y550400D02*
Y547900D01*
X24967D01*
G01X23492Y548942D02*
X23200Y549233D01*
X22950Y549400D01*
X22617Y549483D01*
X22325Y549400D01*
X22117Y549233D01*
X21950Y548983D01*
X21908Y548692D01*
X21950Y548442D01*
X22117Y548192D01*
X22367Y547983D01*
X22658Y547900D01*
X22992Y547983D01*
X23283Y548233D01*
X23450Y548608D01*
X23492Y549025D01*
X23408Y549567D01*
X23283Y549858D01*
X23075Y550150D01*
X22783Y550358D01*
X22492Y550400D01*
X22200Y550317D01*
X21992Y550108D01*
G01X31083Y546692D02*
X31333Y546817D01*
X31625Y546900D01*
X31958D01*
X32333Y546775D01*
X32625Y546567D01*
X32833Y546317D01*
X33000Y545900D01*
X33042Y545525D01*
X32958Y545150D01*
X32833Y544900D01*
X32583Y544650D01*
X32292Y544483D01*
X32000Y544400D01*
X31708D01*
X31417Y544483D01*
X31167Y544608D01*
X30958Y544775D01*
G01X29608Y544692D02*
X29317Y544483D01*
X28983Y544400D01*
X28650Y544483D01*
X28358Y544733D01*
X28150Y545108D01*
X28067Y545483D01*
Y545942D01*
X28150Y546317D01*
X28358Y546650D01*
X28608Y546817D01*
X28900Y546900D01*
X29233Y546817D01*
X29483Y546650D01*
X29650Y546400D01*
X29733Y546067D01*
X29650Y545775D01*
X29442Y545483D01*
X29192Y545317D01*
X28900Y545275D01*
X28567Y545358D01*
X28317Y545567D01*
X28067Y545942D01*
G01X26633Y546900D02*
Y544400D01*
X24967D01*
G01X22700D02*
Y546900D01*
X23200Y546400D01*
G01Y544400D02*
X22200D01*
G01X19600Y546900D02*
X19933Y546817D01*
X20183Y546608D01*
X20350Y546358D01*
X20475Y546025D01*
X20517Y545650D01*
X20475Y545275D01*
X20350Y544942D01*
X20183Y544692D01*
X19933Y544483D01*
X19600Y544400D01*
X19267Y544483D01*
X19017Y544692D01*
X18850Y544942D01*
X18725Y545275D01*
X18683Y545650D01*
X18725Y546025D01*
X18850Y546358D01*
X19017Y546608D01*
X19267Y546817D01*
X19600Y546900D01*
G01X-2009Y564108D02*
Y566608D01*
X-3050D01*
X-3384Y566483D01*
X-3592Y566316D01*
X-3675Y565983D01*
X-3592Y565650D01*
X-3342Y565441D01*
X-3050Y565316D01*
X-2009D01*
G01X-3050D02*
X-3675Y564108D01*
G01X-5234Y564400D02*
X-5525Y564191D01*
X-5859Y564108D01*
X-6192Y564191D01*
X-6484Y564441D01*
X-6692Y564816D01*
X-6775Y565191D01*
Y565650D01*
X-6692Y566025D01*
X-6484Y566358D01*
X-6234Y566525D01*
X-5942Y566608D01*
X-5609Y566525D01*
X-5359Y566358D01*
X-5192Y566108D01*
X-5109Y565775D01*
X-5192Y565483D01*
X-5400Y565191D01*
X-5650Y565025D01*
X-5942Y564983D01*
X-6275Y565066D01*
X-6525Y565275D01*
X-6775Y565650D01*
G01X-8209Y566608D02*
Y564108D01*
X-9875D01*
G01X-12642D02*
Y566608D01*
X-11100Y564816D01*
X-13184D01*
G01X29893Y535177D02*
Y537677D01*
X28852D01*
X28518Y537552D01*
X28310Y537385D01*
X28227Y537052D01*
X28310Y536719D01*
X28560Y536510D01*
X28852Y536385D01*
X29893D01*
G01X28852D02*
X28227Y535177D01*
G01X26668Y535469D02*
X26377Y535260D01*
X26043Y535177D01*
X25710Y535260D01*
X25418Y535510D01*
X25210Y535885D01*
X25127Y536260D01*
Y536719D01*
X25210Y537094D01*
X25418Y537427D01*
X25668Y537594D01*
X25960Y537677D01*
X26293Y537594D01*
X26543Y537427D01*
X26710Y537177D01*
X26793Y536844D01*
X26710Y536552D01*
X26502Y536260D01*
X26252Y536094D01*
X25960Y536052D01*
X25627Y536135D01*
X25377Y536344D01*
X25127Y536719D01*
G01X23693Y537677D02*
Y535177D01*
X22027D01*
G01X20468Y535469D02*
X20177Y535260D01*
X19843Y535177D01*
X19510Y535260D01*
X19218Y535510D01*
X19010Y535885D01*
X18927Y536260D01*
Y536719D01*
X19010Y537094D01*
X19218Y537427D01*
X19468Y537594D01*
X19760Y537677D01*
X20093Y537594D01*
X20343Y537427D01*
X20510Y537177D01*
X20593Y536844D01*
X20510Y536552D01*
X20302Y536260D01*
X20052Y536094D01*
X19760Y536052D01*
X19427Y536135D01*
X19177Y536344D01*
X18927Y536719D01*
G01X-4246Y579887D02*
X-3996Y580012D01*
X-3704Y580095D01*
X-3371D01*
X-2996Y579970D01*
X-2704Y579762D01*
X-2496Y579512D01*
X-2329Y579095D01*
X-2287Y578720D01*
X-2371Y578345D01*
X-2496Y578095D01*
X-2746Y577845D01*
X-3037Y577678D01*
X-3329Y577595D01*
X-3621D01*
X-3912Y577678D01*
X-4162Y577803D01*
X-4371Y577970D01*
G01X-6429Y580095D02*
Y577595D01*
G01X-5471Y580095D02*
X-7387D01*
G01X-9529Y577595D02*
Y580095D01*
X-9029Y579595D01*
G01Y577595D02*
X-10029D01*
G01X-12629Y580095D02*
X-12296Y580012D01*
X-12046Y579803D01*
X-11879Y579553D01*
X-11754Y579220D01*
X-11712Y578845D01*
X-11754Y578470D01*
X-11879Y578137D01*
X-12046Y577887D01*
X-12296Y577678D01*
X-12629Y577595D01*
X-12962Y577678D01*
X-13212Y577887D01*
X-13379Y578137D01*
X-13504Y578470D01*
X-13546Y578845D01*
X-13504Y579220D01*
X-13379Y579553D01*
X-13212Y579803D01*
X-12962Y580012D01*
X-12629Y580095D01*
G01X-1842Y546869D02*
X-1717Y546619D01*
X-1634Y546327D01*
Y545994D01*
X-1759Y545619D01*
X-1967Y545327D01*
X-2217Y545119D01*
X-2634Y544952D01*
X-3009Y544910D01*
X-3384Y544994D01*
X-3634Y545119D01*
X-3884Y545369D01*
X-4051Y545660D01*
X-4134Y545952D01*
Y546244D01*
X-4051Y546535D01*
X-3926Y546785D01*
X-3759Y546994D01*
G01X-1634Y549052D02*
X-4134D01*
G01X-1634Y548094D02*
Y550010D01*
G01X-4134Y552152D02*
X-4092Y552444D01*
X-3967Y552777D01*
X-3759Y552985D01*
X-3467Y553069D01*
X-3176Y552985D01*
X-2926Y552735D01*
X-2801Y552360D01*
Y551944D01*
X-2717Y551694D01*
X-2509Y551485D01*
X-2217Y551402D01*
X-1926Y551527D01*
X-1717Y551819D01*
X-1634Y552152D01*
X-1717Y552485D01*
X-1926Y552777D01*
X-2217Y552902D01*
X-2509Y552819D01*
X-2717Y552610D01*
X-2801Y552360D01*
Y551944D01*
X-2926Y551569D01*
X-3176Y551319D01*
X-3467Y551235D01*
X-3759Y551319D01*
X-3967Y551527D01*
X-4092Y551860D01*
X-4134Y552152D01*
G01X42100Y577100D02*
Y574402D01*
G01Y559100D02*
Y561795D01*
G01Y559100D02*
X64672D01*
G01X42100Y577100D02*
X64675D01*
G01X41900Y556900D02*
X64475D01*
G01X41900Y538900D02*
X64472D01*
G01X41900D02*
Y541595D01*
G01Y556900D02*
Y554202D01*
G01X42100Y579600D02*
Y582295D01*
G01Y579600D02*
X64672D01*
G01X25713Y565342D02*
X25963Y565467D01*
X26255Y565550D01*
X26588D01*
X26963Y565425D01*
X27255Y565217D01*
X27463Y564967D01*
X27630Y564550D01*
X27672Y564175D01*
X27588Y563800D01*
X27463Y563550D01*
X27213Y563300D01*
X26922Y563133D01*
X26630Y563050D01*
X26338D01*
X26047Y563133D01*
X25797Y563258D01*
X25588Y563425D01*
G01X23530Y563050D02*
Y565550D01*
X24030Y565050D01*
G01Y563050D02*
X23030D01*
G01X21472D02*
X20430Y565550D01*
X19388Y563050D01*
G01X19763Y563925D02*
X21097D01*
G01X17330Y563050D02*
Y565550D01*
X17830Y565050D01*
G01Y563050D02*
X16830D01*
G01X14230D02*
Y565550D01*
X14730Y565050D01*
G01Y563050D02*
X13730D01*
G01X42100Y617600D02*
Y614902D01*
G01Y599600D02*
Y602295D01*
G01Y599600D02*
X64672D01*
G01X42100Y617600D02*
X64675D01*
G01X42100Y597600D02*
Y594902D01*
G01Y597600D02*
X64675D01*
G01X38860Y640270D02*
X71560D01*
Y658970D01*
X38860D01*
Y640270D01*
G01X111383Y-13008D02*
X111633Y-12883D01*
X111925Y-12800D01*
X112258D01*
X112633Y-12925D01*
X112925Y-13133D01*
X113133Y-13383D01*
X113300Y-13800D01*
X113342Y-14175D01*
X113258Y-14550D01*
X113133Y-14800D01*
X112883Y-15050D01*
X112592Y-15217D01*
X112300Y-15300D01*
X112008D01*
X111717Y-15217D01*
X111467Y-15092D01*
X111258Y-14925D01*
G01X109908Y-15008D02*
X109617Y-15217D01*
X109283Y-15300D01*
X108950Y-15217D01*
X108658Y-14967D01*
X108450Y-14592D01*
X108367Y-14217D01*
Y-13758D01*
X108450Y-13383D01*
X108658Y-13050D01*
X108908Y-12883D01*
X109200Y-12800D01*
X109533Y-12883D01*
X109783Y-13050D01*
X109950Y-13300D01*
X110033Y-13633D01*
X109950Y-13925D01*
X109742Y-14217D01*
X109492Y-14383D01*
X109200Y-14425D01*
X108867Y-14342D01*
X108617Y-14133D01*
X108367Y-13758D01*
G01X107017Y-12800D02*
Y-14592D01*
X106850Y-14967D01*
X106517Y-15217D01*
X106100Y-15300D01*
X105683Y-15217D01*
X105350Y-14967D01*
X105183Y-14592D01*
Y-12800D01*
G01X103000Y-15300D02*
Y-12800D01*
X103500Y-13300D01*
G01Y-15300D02*
X102500D01*
G01X99900D02*
Y-12800D01*
X100400Y-13300D01*
G01Y-15300D02*
X99400D01*
G01X58788Y9807D02*
Y12307D01*
X57747D01*
X57413Y12182D01*
X57205Y12015D01*
X57122Y11682D01*
X57205Y11349D01*
X57455Y11140D01*
X57747Y11015D01*
X58788D01*
G01X57747D02*
X57122Y9807D01*
G01X55563Y10099D02*
X55272Y9890D01*
X54938Y9807D01*
X54605Y9890D01*
X54313Y10140D01*
X54105Y10515D01*
X54022Y10890D01*
Y11349D01*
X54105Y11724D01*
X54313Y12057D01*
X54563Y12224D01*
X54855Y12307D01*
X55188Y12224D01*
X55438Y12057D01*
X55605Y11807D01*
X55688Y11474D01*
X55605Y11182D01*
X55397Y10890D01*
X55147Y10724D01*
X54855Y10682D01*
X54522Y10765D01*
X54272Y10974D01*
X54022Y11349D01*
G01X52672Y12307D02*
Y10515D01*
X52505Y10140D01*
X52172Y9890D01*
X51755Y9807D01*
X51338Y9890D01*
X51005Y10140D01*
X50838Y10515D01*
Y12307D01*
G01X48655Y9807D02*
X48363Y9849D01*
X48030Y9974D01*
X47822Y10182D01*
X47738Y10474D01*
X47822Y10765D01*
X48072Y11015D01*
X48447Y11140D01*
X48863D01*
X49113Y11224D01*
X49322Y11432D01*
X49405Y11724D01*
X49280Y12015D01*
X48988Y12224D01*
X48655Y12307D01*
X48322Y12224D01*
X48030Y12015D01*
X47905Y11724D01*
X47988Y11432D01*
X48197Y11224D01*
X48447Y11140D01*
X48863D01*
X49238Y11015D01*
X49488Y10765D01*
X49572Y10474D01*
X49488Y10182D01*
X49280Y9974D01*
X48947Y9849D01*
X48655Y9807D01*
G01X61515Y2080D02*
Y4580D01*
X60474D01*
X60140Y4455D01*
X59932Y4288D01*
X59849Y3955D01*
X59932Y3622D01*
X60182Y3413D01*
X60474Y3288D01*
X61515D01*
G01X60474D02*
X59849Y2080D01*
G01X58290Y2372D02*
X57999Y2163D01*
X57665Y2080D01*
X57332Y2163D01*
X57040Y2413D01*
X56832Y2788D01*
X56749Y3163D01*
Y3622D01*
X56832Y3997D01*
X57040Y4330D01*
X57290Y4497D01*
X57582Y4580D01*
X57915Y4497D01*
X58165Y4330D01*
X58332Y4080D01*
X58415Y3747D01*
X58332Y3455D01*
X58124Y3163D01*
X57874Y2997D01*
X57582Y2955D01*
X57249Y3038D01*
X56999Y3247D01*
X56749Y3622D01*
G01X55399Y4580D02*
Y2788D01*
X55232Y2413D01*
X54899Y2163D01*
X54482Y2080D01*
X54065Y2163D01*
X53732Y2413D01*
X53565Y2788D01*
Y4580D01*
G01X51382Y2080D02*
Y4580D01*
X51882Y4080D01*
G01Y2080D02*
X50882D01*
G01X48282Y4580D02*
X48615Y4497D01*
X48865Y4288D01*
X49032Y4038D01*
X49157Y3705D01*
X49199Y3330D01*
X49157Y2955D01*
X49032Y2622D01*
X48865Y2372D01*
X48615Y2163D01*
X48282Y2080D01*
X47949Y2163D01*
X47699Y2372D01*
X47532Y2622D01*
X47407Y2955D01*
X47365Y3330D01*
X47407Y3705D01*
X47532Y4038D01*
X47699Y4288D01*
X47949Y4497D01*
X48282Y4580D01*
G01X58728Y13317D02*
Y15817D01*
X57687D01*
X57353Y15692D01*
X57145Y15525D01*
X57062Y15192D01*
X57145Y14859D01*
X57395Y14650D01*
X57687Y14525D01*
X58728D01*
G01X57687D02*
X57062Y13317D01*
G01X55503Y13609D02*
X55212Y13400D01*
X54878Y13317D01*
X54545Y13400D01*
X54253Y13650D01*
X54045Y14025D01*
X53962Y14400D01*
Y14859D01*
X54045Y15234D01*
X54253Y15567D01*
X54503Y15734D01*
X54795Y15817D01*
X55128Y15734D01*
X55378Y15567D01*
X55545Y15317D01*
X55628Y14984D01*
X55545Y14692D01*
X55337Y14400D01*
X55087Y14234D01*
X54795Y14192D01*
X54462Y14275D01*
X54212Y14484D01*
X53962Y14859D01*
G01X52612Y15817D02*
Y14025D01*
X52445Y13650D01*
X52112Y13400D01*
X51695Y13317D01*
X51278Y13400D01*
X50945Y13650D01*
X50778Y14025D01*
Y15817D01*
G01X48678Y13317D02*
X48595Y13859D01*
X48470Y14317D01*
X48303Y14734D01*
X48095Y15192D01*
X47762Y15817D01*
X49428D01*
G01X56403Y24782D02*
X56653Y24907D01*
X56945Y24990D01*
X57278D01*
X57653Y24865D01*
X57945Y24657D01*
X58153Y24407D01*
X58320Y23990D01*
X58362Y23615D01*
X58278Y23240D01*
X58153Y22990D01*
X57903Y22740D01*
X57612Y22573D01*
X57320Y22490D01*
X57028D01*
X56737Y22573D01*
X56487Y22698D01*
X56278Y22865D01*
G01X54928Y22782D02*
X54637Y22573D01*
X54303Y22490D01*
X53970Y22573D01*
X53678Y22823D01*
X53470Y23198D01*
X53387Y23573D01*
Y24032D01*
X53470Y24407D01*
X53678Y24740D01*
X53928Y24907D01*
X54220Y24990D01*
X54553Y24907D01*
X54803Y24740D01*
X54970Y24490D01*
X55053Y24157D01*
X54970Y23865D01*
X54762Y23573D01*
X54512Y23407D01*
X54220Y23365D01*
X53887Y23448D01*
X53637Y23657D01*
X53387Y24032D01*
G01X52037Y24990D02*
Y23198D01*
X51870Y22823D01*
X51537Y22573D01*
X51120Y22490D01*
X50703Y22573D01*
X50370Y22823D01*
X50203Y23198D01*
Y24990D01*
G01X48937Y22865D02*
X48687Y22657D01*
X48395Y22532D01*
X48020Y22490D01*
X47645Y22573D01*
X47353Y22740D01*
X47145Y23032D01*
X47103Y23365D01*
X47187Y23698D01*
X47395Y23907D01*
X47687Y24073D01*
X47978Y24115D01*
X48270Y24073D01*
X48645Y23907D01*
X48520Y24990D01*
X47395D01*
G01X77164Y29000D02*
Y25209D01*
X64368D01*
Y29000D01*
G01X85060Y-482D02*
X85185Y-732D01*
X85268Y-1024D01*
Y-1357D01*
X85143Y-1732D01*
X84935Y-2024D01*
X84685Y-2232D01*
X84268Y-2399D01*
X83893Y-2441D01*
X83518Y-2357D01*
X83268Y-2232D01*
X83018Y-1982D01*
X82851Y-1691D01*
X82768Y-1399D01*
Y-1107D01*
X82851Y-816D01*
X82976Y-566D01*
X83143Y-357D01*
G01X83060Y993D02*
X82851Y1284D01*
X82768Y1618D01*
X82851Y1951D01*
X83101Y2243D01*
X83476Y2451D01*
X83851Y2534D01*
X84310D01*
X84685Y2451D01*
X85018Y2243D01*
X85185Y1993D01*
X85268Y1701D01*
X85185Y1368D01*
X85018Y1118D01*
X84768Y951D01*
X84435Y868D01*
X84143Y951D01*
X83851Y1159D01*
X83685Y1409D01*
X83643Y1701D01*
X83726Y2034D01*
X83935Y2284D01*
X84310Y2534D01*
G01X85268Y3884D02*
X83476D01*
X83101Y4051D01*
X82851Y4384D01*
X82768Y4801D01*
X82851Y5218D01*
X83101Y5551D01*
X83476Y5718D01*
X85268D01*
G01X83060Y7193D02*
X82851Y7484D01*
X82768Y7818D01*
X82851Y8151D01*
X83101Y8443D01*
X83476Y8651D01*
X83851Y8734D01*
X84310D01*
X84685Y8651D01*
X85018Y8443D01*
X85185Y8193D01*
X85268Y7901D01*
X85185Y7568D01*
X85018Y7318D01*
X84768Y7151D01*
X84435Y7068D01*
X84143Y7151D01*
X83851Y7359D01*
X83685Y7609D01*
X83643Y7901D01*
X83726Y8234D01*
X83935Y8484D01*
X84310Y8734D01*
G01X63600Y-11500D02*
Y11075D01*
G01X81600Y-11500D02*
Y11072D01*
G01Y-11500D02*
X78905D01*
G01X63600D02*
X66298D01*
G01X66300Y23864D02*
X62738D01*
Y11068D01*
X66300D01*
G01X78900Y23864D02*
X82691D01*
Y11068D01*
X78900D01*
G01X111100Y25873D02*
X86710D01*
Y283D01*
X111100D01*
G01X50277Y-12930D02*
Y-19330D01*
G01Y-5930D02*
Y-13730D01*
G01X81312Y54487D02*
X81437Y54237D01*
X81520Y53945D01*
Y53612D01*
X81395Y53237D01*
X81187Y52945D01*
X80937Y52737D01*
X80520Y52570D01*
X80145Y52528D01*
X79770Y52612D01*
X79520Y52737D01*
X79270Y52987D01*
X79103Y53278D01*
X79020Y53570D01*
Y53862D01*
X79103Y54153D01*
X79228Y54403D01*
X79395Y54612D01*
G01X79312Y55962D02*
X79103Y56253D01*
X79020Y56587D01*
X79103Y56920D01*
X79353Y57212D01*
X79728Y57420D01*
X80103Y57503D01*
X80562D01*
X80937Y57420D01*
X81270Y57212D01*
X81437Y56962D01*
X81520Y56670D01*
X81437Y56337D01*
X81270Y56087D01*
X81020Y55920D01*
X80687Y55837D01*
X80395Y55920D01*
X80103Y56128D01*
X79937Y56378D01*
X79895Y56670D01*
X79978Y57003D01*
X80187Y57253D01*
X80562Y57503D01*
G01X81520Y58853D02*
X79728D01*
X79353Y59020D01*
X79103Y59353D01*
X79020Y59770D01*
X79103Y60187D01*
X79353Y60520D01*
X79728Y60687D01*
X81520D01*
G01X81103Y62078D02*
X81353Y62328D01*
X81478Y62620D01*
X81520Y62953D01*
X81437Y63370D01*
X81228Y63662D01*
X80978Y63745D01*
X80728Y63703D01*
X80520Y63537D01*
X80103Y62703D01*
X79812Y62328D01*
X79395Y62078D01*
X79020Y61995D01*
Y63745D01*
G01X77164Y62600D02*
Y66162D01*
X64368D01*
Y62600D01*
G01X77164Y50000D02*
Y46209D01*
X64368D01*
Y50000D01*
G01X77164Y41600D02*
Y45162D01*
X64368D01*
Y41600D01*
G01X57923Y89752D02*
X58173Y89877D01*
X58465Y89960D01*
X58798D01*
X59173Y89835D01*
X59465Y89627D01*
X59673Y89377D01*
X59840Y88960D01*
X59882Y88585D01*
X59798Y88210D01*
X59673Y87960D01*
X59423Y87710D01*
X59132Y87543D01*
X58840Y87460D01*
X58548D01*
X58257Y87543D01*
X58007Y87668D01*
X57798Y87835D01*
G01X56448Y87752D02*
X56157Y87543D01*
X55823Y87460D01*
X55490Y87543D01*
X55198Y87793D01*
X54990Y88168D01*
X54907Y88543D01*
Y89002D01*
X54990Y89377D01*
X55198Y89710D01*
X55448Y89877D01*
X55740Y89960D01*
X56073Y89877D01*
X56323Y89710D01*
X56490Y89460D01*
X56573Y89127D01*
X56490Y88835D01*
X56282Y88543D01*
X56032Y88377D01*
X55740Y88335D01*
X55407Y88418D01*
X55157Y88627D01*
X54907Y89002D01*
G01X52640Y89960D02*
Y87460D01*
G01X53598Y89960D02*
X51682D01*
G01X50457Y87835D02*
X50207Y87627D01*
X49915Y87502D01*
X49540Y87460D01*
X49165Y87543D01*
X48873Y87710D01*
X48665Y88002D01*
X48623Y88335D01*
X48707Y88668D01*
X48915Y88877D01*
X49207Y89043D01*
X49498Y89085D01*
X49790Y89043D01*
X50165Y88877D01*
X50040Y89960D01*
X48915D01*
G01X77164Y83600D02*
Y87162D01*
X64368D01*
Y83600D01*
G01X77164Y71000D02*
Y67209D01*
X64368D01*
Y71000D01*
G01X83700Y46117D02*
X83450Y46325D01*
X83283Y46575D01*
X83200Y46867D01*
X83283Y47200D01*
X83450Y47450D01*
X83700Y47700D01*
X84033Y47783D01*
X85700D01*
G01X83492Y49342D02*
X83283Y49633D01*
X83200Y49967D01*
X83283Y50300D01*
X83533Y50592D01*
X83908Y50800D01*
X84283Y50883D01*
X84742D01*
X85117Y50800D01*
X85450Y50592D01*
X85617Y50342D01*
X85700Y50050D01*
X85617Y49717D01*
X85450Y49467D01*
X85200Y49300D01*
X84867Y49217D01*
X84575Y49300D01*
X84283Y49508D01*
X84117Y49758D01*
X84075Y50050D01*
X84158Y50383D01*
X84367Y50633D01*
X84742Y50883D01*
G01X85700Y52233D02*
X83908D01*
X83533Y52400D01*
X83283Y52733D01*
X83200Y53150D01*
X83283Y53567D01*
X83533Y53900D01*
X83908Y54067D01*
X85700D01*
G01X83200Y56250D02*
X85700D01*
X85200Y55750D01*
G01X83200D02*
Y56750D01*
G01X111100Y63673D02*
X86710D01*
Y38083D01*
X111100D01*
G01X83600Y82417D02*
X83350Y82625D01*
X83183Y82875D01*
X83100Y83167D01*
X83183Y83500D01*
X83350Y83750D01*
X83600Y84000D01*
X83933Y84083D01*
X85600D01*
G01X83392Y85642D02*
X83183Y85933D01*
X83100Y86267D01*
X83183Y86600D01*
X83433Y86892D01*
X83808Y87100D01*
X84183Y87183D01*
X84642D01*
X85017Y87100D01*
X85350Y86892D01*
X85517Y86642D01*
X85600Y86350D01*
X85517Y86017D01*
X85350Y85767D01*
X85100Y85600D01*
X84767Y85517D01*
X84475Y85600D01*
X84183Y85808D01*
X84017Y86058D01*
X83975Y86350D01*
X84058Y86683D01*
X84267Y86933D01*
X84642Y87183D01*
G01X85600Y89450D02*
X83100D01*
G01X85600Y88492D02*
Y90408D01*
G01X83100Y92550D02*
X85600D01*
X85100Y92050D01*
G01X83100D02*
Y93050D01*
G01X111100Y101473D02*
X86710D01*
Y75883D01*
X111100D01*
G01X78617Y113120D02*
X78425Y112810D01*
X78195Y112603D01*
X77927Y112500D01*
X77620Y112603D01*
X77390Y112810D01*
X77160Y113120D01*
X77083Y113533D01*
Y115600D01*
G01X75248Y113533D02*
X74252D01*
G01X72378Y115083D02*
X72148Y115393D01*
X71880Y115548D01*
X71573Y115600D01*
X71190Y115497D01*
X70922Y115238D01*
X70845Y114928D01*
X70883Y114618D01*
X71037Y114360D01*
X71803Y113843D01*
X72148Y113482D01*
X72378Y112965D01*
X72455Y112500D01*
X70845D01*
G01X110883Y124200D02*
Y126700D01*
X109842D01*
X109508Y126575D01*
X109300Y126408D01*
X109217Y126075D01*
X109300Y125742D01*
X109550Y125533D01*
X109842Y125408D01*
X110883D01*
G01X109842D02*
X109217Y124200D01*
G01X107658Y124492D02*
X107367Y124283D01*
X107033Y124200D01*
X106700Y124283D01*
X106408Y124533D01*
X106200Y124908D01*
X106117Y125283D01*
Y125742D01*
X106200Y126117D01*
X106408Y126450D01*
X106658Y126617D01*
X106950Y126700D01*
X107283Y126617D01*
X107533Y126450D01*
X107700Y126200D01*
X107783Y125867D01*
X107700Y125575D01*
X107492Y125283D01*
X107242Y125117D01*
X106950Y125075D01*
X106617Y125158D01*
X106367Y125367D01*
X106117Y125742D01*
G01X103850Y126700D02*
Y124200D01*
G01X104808Y126700D02*
X102892D01*
G01X100750Y124200D02*
X100458Y124242D01*
X100125Y124367D01*
X99917Y124575D01*
X99833Y124867D01*
X99917Y125158D01*
X100167Y125408D01*
X100542Y125533D01*
X100958D01*
X101208Y125617D01*
X101417Y125825D01*
X101500Y126117D01*
X101375Y126408D01*
X101083Y126617D01*
X100750Y126700D01*
X100417Y126617D01*
X100125Y126408D01*
X100000Y126117D01*
X100083Y125825D01*
X100292Y125617D01*
X100542Y125533D01*
X100958D01*
X101333Y125408D01*
X101583Y125158D01*
X101667Y124867D01*
X101583Y124575D01*
X101375Y124367D01*
X101042Y124242D01*
X100750Y124200D01*
G01X107675Y108075D02*
X110175D01*
Y109116D01*
X110050Y109450D01*
X109883Y109658D01*
X109550Y109741D01*
X109217Y109658D01*
X109008Y109408D01*
X108883Y109116D01*
Y108075D01*
G01Y109116D02*
X107675Y109741D01*
G01X107967Y111300D02*
X107758Y111591D01*
X107675Y111925D01*
X107758Y112258D01*
X108008Y112550D01*
X108383Y112758D01*
X108758Y112841D01*
X109217D01*
X109592Y112758D01*
X109925Y112550D01*
X110092Y112300D01*
X110175Y112008D01*
X110092Y111675D01*
X109925Y111425D01*
X109675Y111258D01*
X109342Y111175D01*
X109050Y111258D01*
X108758Y111466D01*
X108592Y111716D01*
X108550Y112008D01*
X108633Y112341D01*
X108842Y112591D01*
X109217Y112841D01*
G01X110175Y115108D02*
X107675D01*
G01X110175Y114150D02*
Y116066D01*
G01X107967Y117500D02*
X107758Y117791D01*
X107675Y118125D01*
X107758Y118458D01*
X108008Y118750D01*
X108383Y118958D01*
X108758Y119041D01*
X109217D01*
X109592Y118958D01*
X109925Y118750D01*
X110092Y118500D01*
X110175Y118208D01*
X110092Y117875D01*
X109925Y117625D01*
X109675Y117458D01*
X109342Y117375D01*
X109050Y117458D01*
X108758Y117666D01*
X108592Y117916D01*
X108550Y118208D01*
X108633Y118541D01*
X108842Y118791D01*
X109217Y119041D01*
G01X94283Y132100D02*
Y134600D01*
X93242D01*
X92908Y134475D01*
X92700Y134308D01*
X92617Y133975D01*
X92700Y133642D01*
X92950Y133433D01*
X93242Y133308D01*
X94283D01*
G01X93242D02*
X92617Y132100D01*
G01X91058Y132392D02*
X90767Y132183D01*
X90433Y132100D01*
X90100Y132183D01*
X89808Y132433D01*
X89600Y132808D01*
X89517Y133183D01*
Y133642D01*
X89600Y134017D01*
X89808Y134350D01*
X90058Y134517D01*
X90350Y134600D01*
X90683Y134517D01*
X90933Y134350D01*
X91100Y134100D01*
X91183Y133767D01*
X91100Y133475D01*
X90892Y133183D01*
X90642Y133017D01*
X90350Y132975D01*
X90017Y133058D01*
X89767Y133267D01*
X89517Y133642D01*
G01X87250Y134600D02*
Y132100D01*
G01X88208Y134600D02*
X86292D01*
G01X85067Y132600D02*
X84817Y132308D01*
X84483Y132142D01*
X84108Y132100D01*
X83775Y132142D01*
X83442Y132350D01*
X83233Y132600D01*
X83192Y132850D01*
X83275Y133142D01*
X83567Y133350D01*
X83858Y133433D01*
X84233D01*
G01X83858D02*
X83608Y133558D01*
X83400Y133767D01*
X83317Y134017D01*
X83400Y134267D01*
X83608Y134475D01*
X83983Y134600D01*
X84358Y134558D01*
X84733Y134392D01*
G01X102197Y113588D02*
Y116088D01*
X101156D01*
X100822Y115963D01*
X100614Y115796D01*
X100531Y115463D01*
X100614Y115130D01*
X100864Y114921D01*
X101156Y114796D01*
X102197D01*
G01X101156D02*
X100531Y113588D01*
G01X98972Y113880D02*
X98681Y113671D01*
X98347Y113588D01*
X98014Y113671D01*
X97722Y113921D01*
X97514Y114296D01*
X97431Y114671D01*
Y115130D01*
X97514Y115505D01*
X97722Y115838D01*
X97972Y116005D01*
X98264Y116088D01*
X98597Y116005D01*
X98847Y115838D01*
X99014Y115588D01*
X99097Y115255D01*
X99014Y114963D01*
X98806Y114671D01*
X98556Y114505D01*
X98264Y114463D01*
X97931Y114546D01*
X97681Y114755D01*
X97431Y115130D01*
G01X95164Y116088D02*
Y113588D01*
G01X96122Y116088D02*
X94206D01*
G01X92856Y114630D02*
X92564Y114921D01*
X92314Y115088D01*
X91981Y115171D01*
X91689Y115088D01*
X91481Y114921D01*
X91314Y114671D01*
X91272Y114380D01*
X91314Y114130D01*
X91481Y113880D01*
X91731Y113671D01*
X92022Y113588D01*
X92356Y113671D01*
X92647Y113921D01*
X92814Y114296D01*
X92856Y114713D01*
X92772Y115255D01*
X92647Y115546D01*
X92439Y115838D01*
X92147Y116046D01*
X91856Y116088D01*
X91564Y116005D01*
X91356Y115796D01*
G01X108970Y96383D02*
X108918Y96115D01*
X108763Y95808D01*
X108505Y95616D01*
X108143Y95540D01*
X107782Y95616D01*
X107472Y95846D01*
X107317Y96191D01*
Y96575D01*
X107213Y96805D01*
X106955Y96996D01*
X106593Y97073D01*
X106232Y96958D01*
X105973Y96690D01*
X105870Y96383D01*
X105973Y96076D01*
X106232Y95808D01*
X106593Y95693D01*
X106955Y95770D01*
X107213Y95961D01*
X107317Y96191D01*
Y96575D01*
X107472Y96920D01*
X107782Y97150D01*
X108143Y97226D01*
X108505Y97150D01*
X108763Y96958D01*
X108918Y96651D01*
X108970Y96383D01*
G01X90302Y128285D02*
X90635Y128327D01*
X90927Y128493D01*
X91177Y128743D01*
X91344Y129035D01*
X91427Y129368D01*
Y129702D01*
X91344Y130035D01*
X91177Y130327D01*
X90927Y130577D01*
X90635Y130743D01*
X90302Y130785D01*
X89969Y130743D01*
X89677Y130577D01*
X89427Y130327D01*
X89260Y130035D01*
X89177Y129702D01*
Y129368D01*
X89260Y129035D01*
X89427Y128743D01*
X89677Y128493D01*
X89969Y128327D01*
X90302Y128285D01*
G01X89969Y128952D02*
X89469Y128285D01*
G01X87910Y128577D02*
X87619Y128368D01*
X87285Y128285D01*
X86952Y128368D01*
X86660Y128618D01*
X86452Y128993D01*
X86369Y129368D01*
Y129827D01*
X86452Y130202D01*
X86660Y130535D01*
X86910Y130702D01*
X87202Y130785D01*
X87535Y130702D01*
X87785Y130535D01*
X87952Y130285D01*
X88035Y129952D01*
X87952Y129660D01*
X87744Y129368D01*
X87494Y129202D01*
X87202Y129160D01*
X86869Y129243D01*
X86619Y129452D01*
X86369Y129827D01*
G01X84102Y130785D02*
Y128285D01*
G01X85060Y130785D02*
X83144D01*
G01X81002Y128285D02*
Y130785D01*
X81502Y130285D01*
G01Y128285D02*
X80502D01*
G01X91350Y120950D02*
Y117700D01*
X87850D01*
G01X79350Y120950D02*
Y117700D01*
X82850D01*
G01X84100Y123200D02*
X86600D01*
G01X117383Y219842D02*
X117633Y219967D01*
X117925Y220050D01*
X118258D01*
X118633Y219925D01*
X118925Y219717D01*
X119133Y219467D01*
X119300Y219050D01*
X119342Y218675D01*
X119258Y218300D01*
X119133Y218050D01*
X118883Y217800D01*
X118592Y217633D01*
X118300Y217550D01*
X118008D01*
X117717Y217633D01*
X117467Y217758D01*
X117258Y217925D01*
G01X115908Y217842D02*
X115617Y217633D01*
X115283Y217550D01*
X114950Y217633D01*
X114658Y217883D01*
X114450Y218258D01*
X114367Y218633D01*
Y219092D01*
X114450Y219467D01*
X114658Y219800D01*
X114908Y219967D01*
X115200Y220050D01*
X115533Y219967D01*
X115783Y219800D01*
X115950Y219550D01*
X116033Y219217D01*
X115950Y218925D01*
X115742Y218633D01*
X115492Y218467D01*
X115200Y218425D01*
X114867Y218508D01*
X114617Y218717D01*
X114367Y219092D01*
G01X112933Y217550D02*
Y220050D01*
X111892D01*
X111558Y219925D01*
X111350Y219758D01*
X111267Y219425D01*
X111350Y219092D01*
X111600Y218883D01*
X111892Y218758D01*
X112933D01*
G01X111892D02*
X111267Y217550D01*
G01X109000D02*
Y220050D01*
X109500Y219550D01*
G01Y217550D02*
X108500D01*
G01X105900D02*
Y220050D01*
X106400Y219550D01*
G01Y217550D02*
X105400D01*
G01X79283Y217958D02*
X79533Y218083D01*
X79825Y218166D01*
X80158D01*
X80533Y218041D01*
X80825Y217833D01*
X81033Y217583D01*
X81200Y217166D01*
X81242Y216791D01*
X81158Y216416D01*
X81033Y216166D01*
X80783Y215916D01*
X80492Y215749D01*
X80200Y215666D01*
X79908D01*
X79617Y215749D01*
X79367Y215874D01*
X79158Y216041D01*
G01X77100Y215666D02*
Y218166D01*
X77600Y217666D01*
G01Y215666D02*
X76600D01*
G01X73167D02*
X74833D01*
Y218166D01*
X73167D01*
G01X73833Y216958D02*
X74833D01*
G01X70900Y215666D02*
Y218166D01*
X71400Y217666D01*
G01Y215666D02*
X70400D01*
G01X68717Y216041D02*
X68467Y215833D01*
X68175Y215708D01*
X67800Y215666D01*
X67425Y215749D01*
X67133Y215916D01*
X66925Y216208D01*
X66883Y216541D01*
X66967Y216874D01*
X67175Y217083D01*
X67467Y217249D01*
X67758Y217291D01*
X68050Y217249D01*
X68425Y217083D01*
X68300Y218166D01*
X67175D01*
G01X63783Y187600D02*
Y190100D01*
X62742D01*
X62408Y189975D01*
X62200Y189808D01*
X62117Y189475D01*
X62200Y189142D01*
X62450Y188933D01*
X62742Y188808D01*
X63783D01*
G01X62742D02*
X62117Y187600D01*
G01X60558Y187892D02*
X60267Y187683D01*
X59933Y187600D01*
X59600Y187683D01*
X59308Y187933D01*
X59100Y188308D01*
X59017Y188683D01*
Y189142D01*
X59100Y189517D01*
X59308Y189850D01*
X59558Y190017D01*
X59850Y190100D01*
X60183Y190017D01*
X60433Y189850D01*
X60600Y189600D01*
X60683Y189267D01*
X60600Y188975D01*
X60392Y188683D01*
X60142Y188517D01*
X59850Y188475D01*
X59517Y188558D01*
X59267Y188767D01*
X59017Y189142D01*
G01X57583Y187600D02*
Y190100D01*
X56542D01*
X56208Y189975D01*
X56000Y189808D01*
X55917Y189475D01*
X56000Y189142D01*
X56250Y188933D01*
X56542Y188808D01*
X57583D01*
G01X56542D02*
X55917Y187600D01*
G01X54442Y188642D02*
X54150Y188933D01*
X53900Y189100D01*
X53567Y189183D01*
X53275Y189100D01*
X53067Y188933D01*
X52900Y188683D01*
X52858Y188392D01*
X52900Y188142D01*
X53067Y187892D01*
X53317Y187683D01*
X53608Y187600D01*
X53942Y187683D01*
X54233Y187933D01*
X54400Y188308D01*
X54442Y188725D01*
X54358Y189267D01*
X54233Y189558D01*
X54025Y189850D01*
X53733Y190058D01*
X53442Y190100D01*
X53150Y190017D01*
X52942Y189808D01*
G01X66733Y193100D02*
Y195600D01*
X65692D01*
X65358Y195475D01*
X65150Y195308D01*
X65067Y194975D01*
X65150Y194642D01*
X65400Y194433D01*
X65692Y194308D01*
X66733D01*
G01X65692D02*
X65067Y193100D01*
G01X63508Y193392D02*
X63217Y193183D01*
X62883Y193100D01*
X62550Y193183D01*
X62258Y193433D01*
X62050Y193808D01*
X61967Y194183D01*
Y194642D01*
X62050Y195017D01*
X62258Y195350D01*
X62508Y195517D01*
X62800Y195600D01*
X63133Y195517D01*
X63383Y195350D01*
X63550Y195100D01*
X63633Y194767D01*
X63550Y194475D01*
X63342Y194183D01*
X63092Y194017D01*
X62800Y193975D01*
X62467Y194058D01*
X62217Y194267D01*
X61967Y194642D01*
G01X60533Y193100D02*
Y195600D01*
X59492D01*
X59158Y195475D01*
X58950Y195308D01*
X58867Y194975D01*
X58950Y194642D01*
X59200Y194433D01*
X59492Y194308D01*
X60533D01*
G01X59492D02*
X58867Y193100D01*
G01X57517Y193475D02*
X57267Y193267D01*
X56975Y193142D01*
X56600Y193100D01*
X56225Y193183D01*
X55933Y193350D01*
X55725Y193642D01*
X55683Y193975D01*
X55767Y194308D01*
X55975Y194517D01*
X56267Y194683D01*
X56558Y194725D01*
X56850Y194683D01*
X57225Y194517D01*
X57100Y195600D01*
X55975D01*
G01X75533Y168950D02*
Y171450D01*
X74492D01*
X74158Y171325D01*
X73950Y171158D01*
X73867Y170825D01*
X73950Y170492D01*
X74200Y170283D01*
X74492Y170158D01*
X75533D01*
G01X74492D02*
X73867Y168950D01*
G01X72308Y169242D02*
X72017Y169033D01*
X71683Y168950D01*
X71350Y169033D01*
X71058Y169283D01*
X70850Y169658D01*
X70767Y170033D01*
Y170492D01*
X70850Y170867D01*
X71058Y171200D01*
X71308Y171367D01*
X71600Y171450D01*
X71933Y171367D01*
X72183Y171200D01*
X72350Y170950D01*
X72433Y170617D01*
X72350Y170325D01*
X72142Y170033D01*
X71892Y169867D01*
X71600Y169825D01*
X71267Y169908D01*
X71017Y170117D01*
X70767Y170492D01*
G01X69333Y168950D02*
Y171450D01*
X68292D01*
X67958Y171325D01*
X67750Y171158D01*
X67667Y170825D01*
X67750Y170492D01*
X68000Y170283D01*
X68292Y170158D01*
X69333D01*
G01X68292D02*
X67667Y168950D01*
G01X65400D02*
Y171450D01*
X65900Y170950D01*
G01Y168950D02*
X64900D01*
G01X63092Y171033D02*
X62842Y171283D01*
X62550Y171408D01*
X62217Y171450D01*
X61800Y171367D01*
X61508Y171158D01*
X61425Y170908D01*
X61467Y170658D01*
X61633Y170450D01*
X62467Y170033D01*
X62842Y169742D01*
X63092Y169325D01*
X63175Y168950D01*
X61425D01*
G01X67707Y158968D02*
Y161468D01*
X66666D01*
X66332Y161343D01*
X66124Y161176D01*
X66041Y160843D01*
X66124Y160510D01*
X66374Y160301D01*
X66666Y160176D01*
X67707D01*
G01X66666D02*
X66041Y158968D01*
G01X64482Y159260D02*
X64191Y159051D01*
X63857Y158968D01*
X63524Y159051D01*
X63232Y159301D01*
X63024Y159676D01*
X62941Y160051D01*
Y160510D01*
X63024Y160885D01*
X63232Y161218D01*
X63482Y161385D01*
X63774Y161468D01*
X64107Y161385D01*
X64357Y161218D01*
X64524Y160968D01*
X64607Y160635D01*
X64524Y160343D01*
X64316Y160051D01*
X64066Y159885D01*
X63774Y159843D01*
X63441Y159926D01*
X63191Y160135D01*
X62941Y160510D01*
G01X60674Y161468D02*
Y158968D01*
G01X61632Y161468D02*
X59716D01*
G01X57574Y158968D02*
Y161468D01*
X58074Y160968D01*
G01Y158968D02*
X57074D01*
G01X104833Y212950D02*
Y215450D01*
X103792D01*
X103458Y215325D01*
X103250Y215158D01*
X103167Y214825D01*
X103250Y214492D01*
X103500Y214283D01*
X103792Y214158D01*
X104833D01*
G01X103792D02*
X103167Y212950D01*
G01X101608Y213242D02*
X101317Y213033D01*
X100983Y212950D01*
X100650Y213033D01*
X100358Y213283D01*
X100150Y213658D01*
X100067Y214033D01*
Y214492D01*
X100150Y214867D01*
X100358Y215200D01*
X100608Y215367D01*
X100900Y215450D01*
X101233Y215367D01*
X101483Y215200D01*
X101650Y214950D01*
X101733Y214617D01*
X101650Y214325D01*
X101442Y214033D01*
X101192Y213867D01*
X100900Y213825D01*
X100567Y213908D01*
X100317Y214117D01*
X100067Y214492D01*
G01X98633Y212950D02*
Y215450D01*
X97592D01*
X97258Y215325D01*
X97050Y215158D01*
X96967Y214825D01*
X97050Y214492D01*
X97300Y214283D01*
X97592Y214158D01*
X98633D01*
G01X97592D02*
X96967Y212950D01*
G01X94200D02*
Y215450D01*
X95742Y213658D01*
X93658D01*
G01X80716Y174172D02*
X80841Y173922D01*
X80924Y173630D01*
Y173297D01*
X80799Y172922D01*
X80591Y172630D01*
X80341Y172422D01*
X79924Y172255D01*
X79549Y172213D01*
X79174Y172297D01*
X78924Y172422D01*
X78674Y172672D01*
X78507Y172963D01*
X78424Y173255D01*
Y173547D01*
X78507Y173838D01*
X78632Y174088D01*
X78799Y174297D01*
G01X78716Y175647D02*
X78507Y175938D01*
X78424Y176272D01*
X78507Y176605D01*
X78757Y176897D01*
X79132Y177105D01*
X79507Y177188D01*
X79966D01*
X80341Y177105D01*
X80674Y176897D01*
X80841Y176647D01*
X80924Y176355D01*
X80841Y176022D01*
X80674Y175772D01*
X80424Y175605D01*
X80091Y175522D01*
X79799Y175605D01*
X79507Y175813D01*
X79341Y176063D01*
X79299Y176355D01*
X79382Y176688D01*
X79591Y176938D01*
X79966Y177188D01*
G01X78424Y178622D02*
X80924D01*
Y179663D01*
X80799Y179997D01*
X80632Y180205D01*
X80299Y180288D01*
X79966Y180205D01*
X79757Y179955D01*
X79632Y179663D01*
Y178622D01*
G01Y179663D02*
X78424Y180288D01*
G01Y182555D02*
X80924D01*
X80424Y182055D01*
G01X78424D02*
Y183055D01*
G01Y186155D02*
X80924D01*
X79132Y184613D01*
Y186697D01*
G01X84716Y174172D02*
X84841Y173922D01*
X84924Y173630D01*
Y173297D01*
X84799Y172922D01*
X84591Y172630D01*
X84341Y172422D01*
X83924Y172255D01*
X83549Y172213D01*
X83174Y172297D01*
X82924Y172422D01*
X82674Y172672D01*
X82507Y172963D01*
X82424Y173255D01*
Y173547D01*
X82507Y173838D01*
X82632Y174088D01*
X82799Y174297D01*
G01X82716Y175647D02*
X82507Y175938D01*
X82424Y176272D01*
X82507Y176605D01*
X82757Y176897D01*
X83132Y177105D01*
X83507Y177188D01*
X83966D01*
X84341Y177105D01*
X84674Y176897D01*
X84841Y176647D01*
X84924Y176355D01*
X84841Y176022D01*
X84674Y175772D01*
X84424Y175605D01*
X84091Y175522D01*
X83799Y175605D01*
X83507Y175813D01*
X83341Y176063D01*
X83299Y176355D01*
X83382Y176688D01*
X83591Y176938D01*
X83966Y177188D01*
G01X82424Y178622D02*
X84924D01*
Y179663D01*
X84799Y179997D01*
X84632Y180205D01*
X84299Y180288D01*
X83966Y180205D01*
X83757Y179955D01*
X83632Y179663D01*
Y178622D01*
G01Y179663D02*
X82424Y180288D01*
G01Y182555D02*
X84924D01*
X84424Y182055D01*
G01X82424D02*
Y183055D01*
G01X82924Y184738D02*
X82632Y184988D01*
X82466Y185322D01*
X82424Y185697D01*
X82466Y186030D01*
X82674Y186363D01*
X82924Y186572D01*
X83174Y186613D01*
X83466Y186530D01*
X83674Y186238D01*
X83757Y185947D01*
Y185572D01*
G01Y185947D02*
X83882Y186197D01*
X84091Y186405D01*
X84341Y186488D01*
X84591Y186405D01*
X84799Y186197D01*
X84924Y185822D01*
X84882Y185447D01*
X84716Y185072D01*
G01X116633Y268192D02*
X116883Y268317D01*
X117175Y268400D01*
X117508D01*
X117883Y268275D01*
X118175Y268067D01*
X118383Y267817D01*
X118550Y267400D01*
X118592Y267025D01*
X118508Y266650D01*
X118383Y266400D01*
X118133Y266150D01*
X117842Y265983D01*
X117550Y265900D01*
X117258D01*
X116967Y265983D01*
X116717Y266108D01*
X116508Y266275D01*
G01X115158Y266192D02*
X114867Y265983D01*
X114533Y265900D01*
X114200Y265983D01*
X113908Y266233D01*
X113700Y266608D01*
X113617Y266983D01*
Y267442D01*
X113700Y267817D01*
X113908Y268150D01*
X114158Y268317D01*
X114450Y268400D01*
X114783Y268317D01*
X115033Y268150D01*
X115200Y267900D01*
X115283Y267567D01*
X115200Y267275D01*
X114992Y266983D01*
X114742Y266817D01*
X114450Y266775D01*
X114117Y266858D01*
X113867Y267067D01*
X113617Y267442D01*
G01X112183Y265900D02*
Y268400D01*
X111183D01*
X110850Y268275D01*
X110600Y267983D01*
X110517Y267650D01*
X110600Y267317D01*
X110808Y267067D01*
X111183Y266942D01*
X112183D01*
G01X108333Y265900D02*
X108250Y266442D01*
X108125Y266900D01*
X107958Y267317D01*
X107750Y267775D01*
X107417Y268400D01*
X109083D01*
G01X116433Y271692D02*
X116683Y271817D01*
X116975Y271900D01*
X117308D01*
X117683Y271775D01*
X117975Y271567D01*
X118183Y271317D01*
X118350Y270900D01*
X118392Y270525D01*
X118308Y270150D01*
X118183Y269900D01*
X117933Y269650D01*
X117642Y269483D01*
X117350Y269400D01*
X117058D01*
X116767Y269483D01*
X116517Y269608D01*
X116308Y269775D01*
G01X114958Y269692D02*
X114667Y269483D01*
X114333Y269400D01*
X114000Y269483D01*
X113708Y269733D01*
X113500Y270108D01*
X113417Y270483D01*
Y270942D01*
X113500Y271317D01*
X113708Y271650D01*
X113958Y271817D01*
X114250Y271900D01*
X114583Y271817D01*
X114833Y271650D01*
X115000Y271400D01*
X115083Y271067D01*
X115000Y270775D01*
X114792Y270483D01*
X114542Y270317D01*
X114250Y270275D01*
X113917Y270358D01*
X113667Y270567D01*
X113417Y270942D01*
G01X111983Y269400D02*
Y271900D01*
X110983D01*
X110650Y271775D01*
X110400Y271483D01*
X110317Y271150D01*
X110400Y270817D01*
X110608Y270567D01*
X110983Y270442D01*
X111983D01*
G01X107550Y269400D02*
Y271900D01*
X109092Y270108D01*
X107008D01*
G01X116133Y275492D02*
X116383Y275617D01*
X116675Y275700D01*
X117008D01*
X117383Y275575D01*
X117675Y275367D01*
X117883Y275117D01*
X118050Y274700D01*
X118092Y274325D01*
X118008Y273950D01*
X117883Y273700D01*
X117633Y273450D01*
X117342Y273283D01*
X117050Y273200D01*
X116758D01*
X116467Y273283D01*
X116217Y273408D01*
X116008Y273575D01*
G01X114658Y273492D02*
X114367Y273283D01*
X114033Y273200D01*
X113700Y273283D01*
X113408Y273533D01*
X113200Y273908D01*
X113117Y274283D01*
Y274742D01*
X113200Y275117D01*
X113408Y275450D01*
X113658Y275617D01*
X113950Y275700D01*
X114283Y275617D01*
X114533Y275450D01*
X114700Y275200D01*
X114783Y274867D01*
X114700Y274575D01*
X114492Y274283D01*
X114242Y274117D01*
X113950Y274075D01*
X113617Y274158D01*
X113367Y274367D01*
X113117Y274742D01*
G01X111683Y273200D02*
Y275700D01*
X110683D01*
X110350Y275575D01*
X110100Y275283D01*
X110017Y274950D01*
X110100Y274617D01*
X110308Y274367D01*
X110683Y274242D01*
X111683D01*
G01X108458Y273492D02*
X108167Y273283D01*
X107833Y273200D01*
X107500Y273283D01*
X107208Y273533D01*
X107000Y273908D01*
X106917Y274283D01*
Y274742D01*
X107000Y275117D01*
X107208Y275450D01*
X107458Y275617D01*
X107750Y275700D01*
X108083Y275617D01*
X108333Y275450D01*
X108500Y275200D01*
X108583Y274867D01*
X108500Y274575D01*
X108292Y274283D01*
X108042Y274117D01*
X107750Y274075D01*
X107417Y274158D01*
X107167Y274367D01*
X106917Y274742D01*
G01X117483Y253792D02*
X117733Y253917D01*
X118025Y254000D01*
X118358D01*
X118733Y253875D01*
X119025Y253667D01*
X119233Y253417D01*
X119400Y253000D01*
X119442Y252625D01*
X119358Y252250D01*
X119233Y252000D01*
X118983Y251750D01*
X118692Y251583D01*
X118400Y251500D01*
X118108D01*
X117817Y251583D01*
X117567Y251708D01*
X117358Y251875D01*
G01X116008Y251792D02*
X115717Y251583D01*
X115383Y251500D01*
X115050Y251583D01*
X114758Y251833D01*
X114550Y252208D01*
X114467Y252583D01*
Y253042D01*
X114550Y253417D01*
X114758Y253750D01*
X115008Y253917D01*
X115300Y254000D01*
X115633Y253917D01*
X115883Y253750D01*
X116050Y253500D01*
X116133Y253167D01*
X116050Y252875D01*
X115842Y252583D01*
X115592Y252417D01*
X115300Y252375D01*
X114967Y252458D01*
X114717Y252667D01*
X114467Y253042D01*
G01X113033Y251500D02*
Y254000D01*
X112033D01*
X111700Y253875D01*
X111450Y253583D01*
X111367Y253250D01*
X111450Y252917D01*
X111658Y252667D01*
X112033Y252542D01*
X113033D01*
G01X109892Y253583D02*
X109642Y253833D01*
X109350Y253958D01*
X109017Y254000D01*
X108600Y253917D01*
X108308Y253708D01*
X108225Y253458D01*
X108267Y253208D01*
X108433Y253000D01*
X109267Y252583D01*
X109642Y252292D01*
X109892Y251875D01*
X109975Y251500D01*
X108225D01*
G01X106917Y251875D02*
X106667Y251667D01*
X106375Y251542D01*
X106000Y251500D01*
X105625Y251583D01*
X105333Y251750D01*
X105125Y252042D01*
X105083Y252375D01*
X105167Y252708D01*
X105375Y252917D01*
X105667Y253083D01*
X105958Y253125D01*
X106250Y253083D01*
X106625Y252917D01*
X106500Y254000D01*
X105375D01*
G01X117583Y257692D02*
X117833Y257817D01*
X118125Y257900D01*
X118458D01*
X118833Y257775D01*
X119125Y257567D01*
X119333Y257317D01*
X119500Y256900D01*
X119542Y256525D01*
X119458Y256150D01*
X119333Y255900D01*
X119083Y255650D01*
X118792Y255483D01*
X118500Y255400D01*
X118208D01*
X117917Y255483D01*
X117667Y255608D01*
X117458Y255775D01*
G01X116108Y255692D02*
X115817Y255483D01*
X115483Y255400D01*
X115150Y255483D01*
X114858Y255733D01*
X114650Y256108D01*
X114567Y256483D01*
Y256942D01*
X114650Y257317D01*
X114858Y257650D01*
X115108Y257817D01*
X115400Y257900D01*
X115733Y257817D01*
X115983Y257650D01*
X116150Y257400D01*
X116233Y257067D01*
X116150Y256775D01*
X115942Y256483D01*
X115692Y256317D01*
X115400Y256275D01*
X115067Y256358D01*
X114817Y256567D01*
X114567Y256942D01*
G01X113133Y255400D02*
Y257900D01*
X112133D01*
X111800Y257775D01*
X111550Y257483D01*
X111467Y257150D01*
X111550Y256817D01*
X111758Y256567D01*
X112133Y256442D01*
X113133D01*
G01X109992Y257483D02*
X109742Y257733D01*
X109450Y257858D01*
X109117Y257900D01*
X108700Y257817D01*
X108408Y257608D01*
X108325Y257358D01*
X108367Y257108D01*
X108533Y256900D01*
X109367Y256483D01*
X109742Y256192D01*
X109992Y255775D01*
X110075Y255400D01*
X108325D01*
G01X106892Y257483D02*
X106642Y257733D01*
X106350Y257858D01*
X106017Y257900D01*
X105600Y257817D01*
X105308Y257608D01*
X105225Y257358D01*
X105267Y257108D01*
X105433Y256900D01*
X106267Y256483D01*
X106642Y256192D01*
X106892Y255775D01*
X106975Y255400D01*
X105225D01*
G01X114783Y249292D02*
X115033Y249417D01*
X115325Y249500D01*
X115658D01*
X116033Y249375D01*
X116325Y249167D01*
X116533Y248917D01*
X116700Y248500D01*
X116742Y248125D01*
X116658Y247750D01*
X116533Y247500D01*
X116283Y247250D01*
X115992Y247083D01*
X115700Y247000D01*
X115408D01*
X115117Y247083D01*
X114867Y247208D01*
X114658Y247375D01*
G01X113308Y247292D02*
X113017Y247083D01*
X112683Y247000D01*
X112350Y247083D01*
X112058Y247333D01*
X111850Y247708D01*
X111767Y248083D01*
Y248542D01*
X111850Y248917D01*
X112058Y249250D01*
X112308Y249417D01*
X112600Y249500D01*
X112933Y249417D01*
X113183Y249250D01*
X113350Y249000D01*
X113433Y248667D01*
X113350Y248375D01*
X113142Y248083D01*
X112892Y247917D01*
X112600Y247875D01*
X112267Y247958D01*
X112017Y248167D01*
X111767Y248542D01*
G01X110333Y247000D02*
Y249500D01*
X109333D01*
X109000Y249375D01*
X108750Y249083D01*
X108667Y248750D01*
X108750Y248417D01*
X108958Y248167D01*
X109333Y248042D01*
X110333D01*
G01X107192Y249083D02*
X106942Y249333D01*
X106650Y249458D01*
X106317Y249500D01*
X105900Y249417D01*
X105608Y249208D01*
X105525Y248958D01*
X105567Y248708D01*
X105733Y248500D01*
X106567Y248083D01*
X106942Y247792D01*
X107192Y247375D01*
X107275Y247000D01*
X105525D01*
G01X104092Y248042D02*
X103800Y248333D01*
X103550Y248500D01*
X103217Y248583D01*
X102925Y248500D01*
X102717Y248333D01*
X102550Y248083D01*
X102508Y247792D01*
X102550Y247542D01*
X102717Y247292D01*
X102967Y247083D01*
X103258Y247000D01*
X103592Y247083D01*
X103883Y247333D01*
X104050Y247708D01*
X104092Y248125D01*
X104008Y248667D01*
X103883Y248958D01*
X103675Y249250D01*
X103383Y249458D01*
X103092Y249500D01*
X102800Y249417D01*
X102592Y249208D01*
G01X117683Y226492D02*
X117933Y226617D01*
X118225Y226700D01*
X118558D01*
X118933Y226575D01*
X119225Y226367D01*
X119433Y226117D01*
X119600Y225700D01*
X119642Y225325D01*
X119558Y224950D01*
X119433Y224700D01*
X119183Y224450D01*
X118892Y224283D01*
X118600Y224200D01*
X118308D01*
X118017Y224283D01*
X117767Y224408D01*
X117558Y224575D01*
G01X116208Y224492D02*
X115917Y224283D01*
X115583Y224200D01*
X115250Y224283D01*
X114958Y224533D01*
X114750Y224908D01*
X114667Y225283D01*
Y225742D01*
X114750Y226117D01*
X114958Y226450D01*
X115208Y226617D01*
X115500Y226700D01*
X115833Y226617D01*
X116083Y226450D01*
X116250Y226200D01*
X116333Y225867D01*
X116250Y225575D01*
X116042Y225283D01*
X115792Y225117D01*
X115500Y225075D01*
X115167Y225158D01*
X114917Y225367D01*
X114667Y225742D01*
G01X113233Y224200D02*
Y226700D01*
X112192D01*
X111858Y226575D01*
X111650Y226408D01*
X111567Y226075D01*
X111650Y225742D01*
X111900Y225533D01*
X112192Y225408D01*
X113233D01*
G01X112192D02*
X111567Y224200D01*
G01X109300D02*
Y226700D01*
X109800Y226200D01*
G01Y224200D02*
X108800D01*
G01X106200Y226700D02*
X106533Y226617D01*
X106783Y226408D01*
X106950Y226158D01*
X107075Y225825D01*
X107117Y225450D01*
X107075Y225075D01*
X106950Y224742D01*
X106783Y224492D01*
X106533Y224283D01*
X106200Y224200D01*
X105867Y224283D01*
X105617Y224492D01*
X105450Y224742D01*
X105325Y225075D01*
X105283Y225450D01*
X105325Y225825D01*
X105450Y226158D01*
X105617Y226408D01*
X105867Y226617D01*
X106200Y226700D01*
G01X117404Y262711D02*
Y265211D01*
X116363D01*
X116029Y265086D01*
X115821Y264919D01*
X115738Y264586D01*
X115821Y264253D01*
X116071Y264044D01*
X116363Y263919D01*
X117404D01*
G01X116363D02*
X115738Y262711D01*
G01X114179Y263003D02*
X113888Y262794D01*
X113554Y262711D01*
X113221Y262794D01*
X112929Y263044D01*
X112721Y263419D01*
X112638Y263794D01*
Y264253D01*
X112721Y264628D01*
X112929Y264961D01*
X113179Y265128D01*
X113471Y265211D01*
X113804Y265128D01*
X114054Y264961D01*
X114221Y264711D01*
X114304Y264378D01*
X114221Y264086D01*
X114013Y263794D01*
X113763Y263628D01*
X113471Y263586D01*
X113138Y263669D01*
X112888Y263878D01*
X112638Y264253D01*
G01X111204Y262711D02*
Y265211D01*
X110204D01*
X109871Y265086D01*
X109621Y264794D01*
X109538Y264461D01*
X109621Y264128D01*
X109829Y263878D01*
X110204Y263753D01*
X111204D01*
G01X108063Y264794D02*
X107813Y265044D01*
X107521Y265169D01*
X107188Y265211D01*
X106771Y265128D01*
X106479Y264919D01*
X106396Y264669D01*
X106438Y264419D01*
X106604Y264211D01*
X107438Y263794D01*
X107813Y263503D01*
X108063Y263086D01*
X108146Y262711D01*
X106396D01*
G01X104963Y264794D02*
X104713Y265044D01*
X104421Y265169D01*
X104088Y265211D01*
X103671Y265128D01*
X103379Y264919D01*
X103296Y264669D01*
X103338Y264419D01*
X103504Y264211D01*
X104338Y263794D01*
X104713Y263503D01*
X104963Y263086D01*
X105046Y262711D01*
X103296D01*
G01X113597Y242456D02*
Y244956D01*
X112556D01*
X112222Y244831D01*
X112014Y244664D01*
X111931Y244331D01*
X112014Y243998D01*
X112264Y243789D01*
X112556Y243664D01*
X113597D01*
G01X112556D02*
X111931Y242456D01*
G01X110372Y242748D02*
X110081Y242539D01*
X109747Y242456D01*
X109414Y242539D01*
X109122Y242789D01*
X108914Y243164D01*
X108831Y243539D01*
Y243998D01*
X108914Y244373D01*
X109122Y244706D01*
X109372Y244873D01*
X109664Y244956D01*
X109997Y244873D01*
X110247Y244706D01*
X110414Y244456D01*
X110497Y244123D01*
X110414Y243831D01*
X110206Y243539D01*
X109956Y243373D01*
X109664Y243331D01*
X109331Y243414D01*
X109081Y243623D01*
X108831Y243998D01*
G01X107397Y242456D02*
Y244956D01*
X106356D01*
X106022Y244831D01*
X105814Y244664D01*
X105731Y244331D01*
X105814Y243998D01*
X106064Y243789D01*
X106356Y243664D01*
X107397D01*
G01X106356D02*
X105731Y242456D01*
G01X103464D02*
Y244956D01*
X103964Y244456D01*
G01Y242456D02*
X102964D01*
G01X100364D02*
Y244956D01*
X100864Y244456D01*
G01Y242456D02*
X99864D01*
G01X84600Y256967D02*
X87100D01*
Y258008D01*
X86975Y258342D01*
X86808Y258550D01*
X86475Y258633D01*
X86142Y258550D01*
X85933Y258300D01*
X85808Y258008D01*
Y256967D01*
G01Y258008D02*
X84600Y258633D01*
G01X84892Y260192D02*
X84683Y260483D01*
X84600Y260817D01*
X84683Y261150D01*
X84933Y261442D01*
X85308Y261650D01*
X85683Y261733D01*
X86142D01*
X86517Y261650D01*
X86850Y261442D01*
X87017Y261192D01*
X87100Y260900D01*
X87017Y260567D01*
X86850Y260317D01*
X86600Y260150D01*
X86267Y260067D01*
X85975Y260150D01*
X85683Y260358D01*
X85517Y260608D01*
X85475Y260900D01*
X85558Y261233D01*
X85767Y261483D01*
X86142Y261733D01*
G01X84600Y263167D02*
X87100D01*
Y264167D01*
X86975Y264500D01*
X86683Y264750D01*
X86350Y264833D01*
X86017Y264750D01*
X85767Y264542D01*
X85642Y264167D01*
Y263167D01*
G01X86683Y266308D02*
X86933Y266558D01*
X87058Y266850D01*
X87100Y267183D01*
X87017Y267600D01*
X86808Y267892D01*
X86558Y267975D01*
X86308Y267933D01*
X86100Y267767D01*
X85683Y266933D01*
X85392Y266558D01*
X84975Y266308D01*
X84600Y266225D01*
Y267975D01*
G01Y270200D02*
X84642Y270492D01*
X84767Y270825D01*
X84975Y271033D01*
X85267Y271117D01*
X85558Y271033D01*
X85808Y270783D01*
X85933Y270408D01*
Y269992D01*
X86017Y269742D01*
X86225Y269533D01*
X86517Y269450D01*
X86808Y269575D01*
X87017Y269867D01*
X87100Y270200D01*
X87017Y270533D01*
X86808Y270825D01*
X86517Y270950D01*
X86225Y270867D01*
X86017Y270658D01*
X85933Y270408D01*
Y269992D01*
X85808Y269617D01*
X85558Y269367D01*
X85267Y269283D01*
X84975Y269367D01*
X84767Y269575D01*
X84642Y269908D01*
X84600Y270200D01*
G01X79100Y256967D02*
X81600D01*
Y258008D01*
X81475Y258342D01*
X81308Y258550D01*
X80975Y258633D01*
X80642Y258550D01*
X80433Y258300D01*
X80308Y258008D01*
Y256967D01*
G01Y258008D02*
X79100Y258633D01*
G01X79392Y260192D02*
X79183Y260483D01*
X79100Y260817D01*
X79183Y261150D01*
X79433Y261442D01*
X79808Y261650D01*
X80183Y261733D01*
X80642D01*
X81017Y261650D01*
X81350Y261442D01*
X81517Y261192D01*
X81600Y260900D01*
X81517Y260567D01*
X81350Y260317D01*
X81100Y260150D01*
X80767Y260067D01*
X80475Y260150D01*
X80183Y260358D01*
X80017Y260608D01*
X79975Y260900D01*
X80058Y261233D01*
X80267Y261483D01*
X80642Y261733D01*
G01X79100Y263167D02*
X81600D01*
Y264167D01*
X81475Y264500D01*
X81183Y264750D01*
X80850Y264833D01*
X80517Y264750D01*
X80267Y264542D01*
X80142Y264167D01*
Y263167D01*
G01X81183Y266308D02*
X81433Y266558D01*
X81558Y266850D01*
X81600Y267183D01*
X81517Y267600D01*
X81308Y267892D01*
X81058Y267975D01*
X80808Y267933D01*
X80600Y267767D01*
X80183Y266933D01*
X79892Y266558D01*
X79475Y266308D01*
X79100Y266225D01*
Y267975D01*
G01X79392Y269492D02*
X79183Y269783D01*
X79100Y270117D01*
X79183Y270450D01*
X79433Y270742D01*
X79808Y270950D01*
X80183Y271033D01*
X80642D01*
X81017Y270950D01*
X81350Y270742D01*
X81517Y270492D01*
X81600Y270200D01*
X81517Y269867D01*
X81350Y269617D01*
X81100Y269450D01*
X80767Y269367D01*
X80475Y269450D01*
X80183Y269658D01*
X80017Y269908D01*
X79975Y270200D01*
X80058Y270533D01*
X80267Y270783D01*
X80642Y271033D01*
G01X75600Y256967D02*
X78100D01*
Y258008D01*
X77975Y258342D01*
X77808Y258550D01*
X77475Y258633D01*
X77142Y258550D01*
X76933Y258300D01*
X76808Y258008D01*
Y256967D01*
G01Y258008D02*
X75600Y258633D01*
G01X75892Y260192D02*
X75683Y260483D01*
X75600Y260817D01*
X75683Y261150D01*
X75933Y261442D01*
X76308Y261650D01*
X76683Y261733D01*
X77142D01*
X77517Y261650D01*
X77850Y261442D01*
X78017Y261192D01*
X78100Y260900D01*
X78017Y260567D01*
X77850Y260317D01*
X77600Y260150D01*
X77267Y260067D01*
X76975Y260150D01*
X76683Y260358D01*
X76517Y260608D01*
X76475Y260900D01*
X76558Y261233D01*
X76767Y261483D01*
X77142Y261733D01*
G01X75600Y263167D02*
X78100D01*
Y264167D01*
X77975Y264500D01*
X77683Y264750D01*
X77350Y264833D01*
X77017Y264750D01*
X76767Y264542D01*
X76642Y264167D01*
Y263167D01*
G01X76100Y266183D02*
X75808Y266433D01*
X75642Y266767D01*
X75600Y267142D01*
X75642Y267475D01*
X75850Y267808D01*
X76100Y268017D01*
X76350Y268058D01*
X76642Y267975D01*
X76850Y267683D01*
X76933Y267392D01*
Y267017D01*
G01Y267392D02*
X77058Y267642D01*
X77267Y267850D01*
X77517Y267933D01*
X77767Y267850D01*
X77975Y267642D01*
X78100Y267267D01*
X78058Y266892D01*
X77892Y266517D01*
G01X78100Y270200D02*
X78017Y269867D01*
X77808Y269617D01*
X77558Y269450D01*
X77225Y269325D01*
X76850Y269283D01*
X76475Y269325D01*
X76142Y269450D01*
X75892Y269617D01*
X75683Y269867D01*
X75600Y270200D01*
X75683Y270533D01*
X75892Y270783D01*
X76142Y270950D01*
X76475Y271075D01*
X76850Y271117D01*
X77225Y271075D01*
X77558Y270950D01*
X77808Y270783D01*
X78017Y270533D01*
X78100Y270200D01*
G01X102449Y253286D02*
X102574Y253036D01*
X102657Y252744D01*
Y252411D01*
X102532Y252036D01*
X102324Y251744D01*
X102074Y251536D01*
X101657Y251369D01*
X101282Y251327D01*
X100907Y251411D01*
X100657Y251536D01*
X100407Y251786D01*
X100240Y252077D01*
X100157Y252369D01*
Y252661D01*
X100240Y252952D01*
X100365Y253202D01*
X100532Y253411D01*
G01X102657Y255469D02*
X100157D01*
G01X102657Y254511D02*
Y256427D01*
G01X102240Y257777D02*
X102490Y258027D01*
X102615Y258319D01*
X102657Y258652D01*
X102574Y259069D01*
X102365Y259361D01*
X102115Y259444D01*
X101865Y259402D01*
X101657Y259236D01*
X101240Y258402D01*
X100949Y258027D01*
X100532Y257777D01*
X100157Y257694D01*
Y259444D01*
G01X101199Y260877D02*
X101490Y261169D01*
X101657Y261419D01*
X101740Y261752D01*
X101657Y262044D01*
X101490Y262252D01*
X101240Y262419D01*
X100949Y262461D01*
X100699Y262419D01*
X100449Y262252D01*
X100240Y262002D01*
X100157Y261711D01*
X100240Y261377D01*
X100490Y261086D01*
X100865Y260919D01*
X101282Y260877D01*
X101824Y260961D01*
X102115Y261086D01*
X102407Y261294D01*
X102615Y261586D01*
X102657Y261877D01*
X102574Y262169D01*
X102365Y262377D01*
G01X103642Y222667D02*
X103767Y222417D01*
X103850Y222125D01*
Y221792D01*
X103725Y221417D01*
X103517Y221125D01*
X103267Y220917D01*
X102850Y220750D01*
X102475Y220708D01*
X102100Y220792D01*
X101850Y220917D01*
X101600Y221167D01*
X101433Y221458D01*
X101350Y221750D01*
Y222042D01*
X101433Y222333D01*
X101558Y222583D01*
X101725Y222792D01*
G01X103850Y224850D02*
X101350D01*
G01X103850Y223892D02*
Y225808D01*
G01X103433Y227158D02*
X103683Y227408D01*
X103808Y227700D01*
X103850Y228033D01*
X103767Y228450D01*
X103558Y228742D01*
X103308Y228825D01*
X103058Y228783D01*
X102850Y228617D01*
X102433Y227783D01*
X102142Y227408D01*
X101725Y227158D01*
X101350Y227075D01*
Y228825D01*
G01X103433Y230258D02*
X103683Y230508D01*
X103808Y230800D01*
X103850Y231133D01*
X103767Y231550D01*
X103558Y231842D01*
X103308Y231925D01*
X103058Y231883D01*
X102850Y231717D01*
X102433Y230883D01*
X102142Y230508D01*
X101725Y230258D01*
X101350Y230175D01*
Y231925D01*
G01X52676Y280572D02*
X52801Y280322D01*
X52884Y280030D01*
Y279697D01*
X52759Y279322D01*
X52551Y279030D01*
X52301Y278822D01*
X51884Y278655D01*
X51509Y278613D01*
X51134Y278697D01*
X50884Y278822D01*
X50634Y279072D01*
X50467Y279363D01*
X50384Y279655D01*
Y279947D01*
X50467Y280238D01*
X50592Y280488D01*
X50759Y280697D01*
G01X50676Y282047D02*
X50467Y282338D01*
X50384Y282672D01*
X50467Y283005D01*
X50717Y283297D01*
X51092Y283505D01*
X51467Y283588D01*
X51926D01*
X52301Y283505D01*
X52634Y283297D01*
X52801Y283047D01*
X52884Y282755D01*
X52801Y282422D01*
X52634Y282172D01*
X52384Y282005D01*
X52051Y281922D01*
X51759Y282005D01*
X51467Y282213D01*
X51301Y282463D01*
X51259Y282755D01*
X51342Y283088D01*
X51551Y283338D01*
X51926Y283588D01*
G01X50384Y285022D02*
X52884D01*
Y286022D01*
X52759Y286355D01*
X52467Y286605D01*
X52134Y286688D01*
X51801Y286605D01*
X51551Y286397D01*
X51426Y286022D01*
Y285022D01*
G01X50384Y288955D02*
X52884D01*
X52384Y288455D01*
G01X50384D02*
Y289455D01*
G01Y291972D02*
X50926Y292055D01*
X51384Y292180D01*
X51801Y292347D01*
X52259Y292555D01*
X52884Y292888D01*
Y291222D01*
G01X105883Y279392D02*
X106133Y279517D01*
X106425Y279600D01*
X106758D01*
X107133Y279475D01*
X107425Y279267D01*
X107633Y279017D01*
X107800Y278600D01*
X107842Y278225D01*
X107758Y277850D01*
X107633Y277600D01*
X107383Y277350D01*
X107092Y277183D01*
X106800Y277100D01*
X106508D01*
X106217Y277183D01*
X105967Y277308D01*
X105758Y277475D01*
G01X104408Y277392D02*
X104117Y277183D01*
X103783Y277100D01*
X103450Y277183D01*
X103158Y277433D01*
X102950Y277808D01*
X102867Y278183D01*
Y278642D01*
X102950Y279017D01*
X103158Y279350D01*
X103408Y279517D01*
X103700Y279600D01*
X104033Y279517D01*
X104283Y279350D01*
X104450Y279100D01*
X104533Y278767D01*
X104450Y278475D01*
X104242Y278183D01*
X103992Y278017D01*
X103700Y277975D01*
X103367Y278058D01*
X103117Y278267D01*
X102867Y278642D01*
G01X101433Y277100D02*
Y279600D01*
X100433D01*
X100100Y279475D01*
X99850Y279183D01*
X99767Y278850D01*
X99850Y278517D01*
X100058Y278267D01*
X100433Y278142D01*
X101433D01*
G01X97500Y277100D02*
Y279600D01*
X98000Y279100D01*
G01Y277100D02*
X97000D01*
G01X95317Y277475D02*
X95067Y277267D01*
X94775Y277142D01*
X94400Y277100D01*
X94025Y277183D01*
X93733Y277350D01*
X93525Y277642D01*
X93483Y277975D01*
X93567Y278308D01*
X93775Y278517D01*
X94067Y278683D01*
X94358Y278725D01*
X94650Y278683D01*
X95025Y278517D01*
X94900Y279600D01*
X93775D01*
G01X56843Y280472D02*
X56968Y280222D01*
X57051Y279930D01*
Y279597D01*
X56926Y279222D01*
X56718Y278930D01*
X56468Y278722D01*
X56051Y278555D01*
X55676Y278513D01*
X55301Y278597D01*
X55051Y278722D01*
X54801Y278972D01*
X54634Y279263D01*
X54551Y279555D01*
Y279847D01*
X54634Y280138D01*
X54759Y280388D01*
X54926Y280597D01*
G01X54843Y281947D02*
X54634Y282238D01*
X54551Y282572D01*
X54634Y282905D01*
X54884Y283197D01*
X55259Y283405D01*
X55634Y283488D01*
X56093D01*
X56468Y283405D01*
X56801Y283197D01*
X56968Y282947D01*
X57051Y282655D01*
X56968Y282322D01*
X56801Y282072D01*
X56551Y281905D01*
X56218Y281822D01*
X55926Y281905D01*
X55634Y282113D01*
X55468Y282363D01*
X55426Y282655D01*
X55509Y282988D01*
X55718Y283238D01*
X56093Y283488D01*
G01X54551Y284922D02*
X57051D01*
Y285922D01*
X56926Y286255D01*
X56634Y286505D01*
X56301Y286588D01*
X55968Y286505D01*
X55718Y286297D01*
X55593Y285922D01*
Y284922D01*
G01X54551Y288855D02*
X57051D01*
X56551Y288355D01*
G01X54551D02*
Y289355D01*
G01X55593Y291163D02*
X55884Y291455D01*
X56051Y291705D01*
X56134Y292038D01*
X56051Y292330D01*
X55884Y292538D01*
X55634Y292705D01*
X55343Y292747D01*
X55093Y292705D01*
X54843Y292538D01*
X54634Y292288D01*
X54551Y291997D01*
X54634Y291663D01*
X54884Y291372D01*
X55259Y291205D01*
X55676Y291163D01*
X56218Y291247D01*
X56509Y291372D01*
X56801Y291580D01*
X57009Y291872D01*
X57051Y292163D01*
X56968Y292455D01*
X56759Y292663D01*
G01X78267Y245550D02*
X79933D01*
Y248050D01*
X78267D01*
G01X78933Y246842D02*
X79933D01*
G01X76917Y248050D02*
Y246258D01*
X76750Y245883D01*
X76417Y245633D01*
X76000Y245550D01*
X75583Y245633D01*
X75250Y245883D01*
X75083Y246258D01*
Y248050D01*
G01X73608Y245842D02*
X73317Y245633D01*
X72983Y245550D01*
X72650Y245633D01*
X72358Y245883D01*
X72150Y246258D01*
X72067Y246633D01*
Y247092D01*
X72150Y247467D01*
X72358Y247800D01*
X72608Y247967D01*
X72900Y248050D01*
X73233Y247967D01*
X73483Y247800D01*
X73650Y247550D01*
X73733Y247217D01*
X73650Y246925D01*
X73442Y246633D01*
X73192Y246467D01*
X72900Y246425D01*
X72567Y246508D01*
X72317Y246717D01*
X72067Y247092D01*
G01X70633Y245550D02*
Y248050D01*
X69592D01*
X69258Y247925D01*
X69050Y247758D01*
X68967Y247425D01*
X69050Y247092D01*
X69300Y246883D01*
X69592Y246758D01*
X70633D01*
G01X69592D02*
X68967Y245550D01*
G01X66700D02*
Y248050D01*
X67200Y247550D01*
G01Y245550D02*
X66200D01*
G01X81900Y222299D02*
Y221850D01*
X64600D01*
Y222299D01*
G01X81900Y242301D02*
Y242750D01*
X64600D01*
Y242301D01*
G01X118008Y234500D02*
X118258Y234625D01*
X118550Y234708D01*
X118883D01*
X119258Y234583D01*
X119550Y234375D01*
X119758Y234125D01*
X119925Y233708D01*
X119967Y233333D01*
X119883Y232958D01*
X119758Y232708D01*
X119508Y232458D01*
X119217Y232291D01*
X118925Y232208D01*
X118633D01*
X118342Y232291D01*
X118092Y232416D01*
X117883Y232583D01*
G01X115825Y232208D02*
Y234708D01*
X116325Y234208D01*
G01Y232208D02*
X115325D01*
G01X111892D02*
X113558D01*
Y234708D01*
X111892D01*
G01X112558Y233500D02*
X113558D01*
G01X110417Y234291D02*
X110167Y234541D01*
X109875Y234666D01*
X109542Y234708D01*
X109125Y234625D01*
X108833Y234416D01*
X108750Y234166D01*
X108792Y233916D01*
X108958Y233708D01*
X109792Y233291D01*
X110167Y233000D01*
X110417Y232583D01*
X110500Y232208D01*
X108750D01*
G01X107442Y232708D02*
X107192Y232416D01*
X106858Y232250D01*
X106483Y232208D01*
X106150Y232250D01*
X105817Y232458D01*
X105608Y232708D01*
X105567Y232958D01*
X105650Y233250D01*
X105942Y233458D01*
X106233Y233541D01*
X106608D01*
G01X106233D02*
X105983Y233666D01*
X105775Y233875D01*
X105692Y234125D01*
X105775Y234375D01*
X105983Y234583D01*
X106358Y234708D01*
X106733Y234666D01*
X107108Y234500D01*
G01X115574Y261683D02*
X115824Y261808D01*
X116116Y261891D01*
X116449D01*
X116824Y261766D01*
X117116Y261558D01*
X117324Y261308D01*
X117491Y260891D01*
X117533Y260516D01*
X117449Y260141D01*
X117324Y259891D01*
X117074Y259641D01*
X116783Y259474D01*
X116491Y259391D01*
X116199D01*
X115908Y259474D01*
X115658Y259599D01*
X115449Y259766D01*
G01X113391Y259391D02*
Y261891D01*
X113891Y261391D01*
G01Y259391D02*
X112891D01*
G01X111208D02*
Y261891D01*
X110374D01*
X110041Y261766D01*
X109791Y261599D01*
X109583Y261349D01*
X109416Y261058D01*
X109374Y260641D01*
X109416Y260224D01*
X109583Y259933D01*
X109791Y259683D01*
X110041Y259516D01*
X110374Y259391D01*
X111208D01*
G01X107191D02*
Y261891D01*
X107691Y261391D01*
G01Y259391D02*
X106691D01*
G01X105008Y259766D02*
X104758Y259558D01*
X104466Y259433D01*
X104091Y259391D01*
X103716Y259474D01*
X103424Y259641D01*
X103216Y259933D01*
X103174Y260266D01*
X103258Y260599D01*
X103466Y260808D01*
X103758Y260974D01*
X104049Y261016D01*
X104341Y260974D01*
X104716Y260808D01*
X104591Y261891D01*
X103466D01*
G01X71100Y319300D02*
Y336600D01*
X88600D01*
Y357177D01*
X104800D01*
Y354900D01*
X107600D01*
Y352800D01*
G01X92500Y311300D02*
X86000D01*
Y314800D01*
X71100D01*
Y315414D01*
G01X107500Y342300D02*
Y330103D01*
G01X105003Y326700D02*
X101600D01*
Y320700D01*
X97500D01*
G01X93100Y318400D02*
Y311800D01*
G01X79167Y290967D02*
X81667D01*
Y292008D01*
X81542Y292342D01*
X81375Y292550D01*
X81042Y292633D01*
X80709Y292550D01*
X80500Y292300D01*
X80375Y292008D01*
Y290967D01*
G01Y292008D02*
X79167Y292633D01*
G01X79459Y294192D02*
X79250Y294483D01*
X79167Y294817D01*
X79250Y295150D01*
X79500Y295442D01*
X79875Y295650D01*
X80250Y295733D01*
X80709D01*
X81084Y295650D01*
X81417Y295442D01*
X81584Y295192D01*
X81667Y294900D01*
X81584Y294567D01*
X81417Y294317D01*
X81167Y294150D01*
X80834Y294067D01*
X80542Y294150D01*
X80250Y294358D01*
X80084Y294608D01*
X80042Y294900D01*
X80125Y295233D01*
X80334Y295483D01*
X80709Y295733D01*
G01X79167Y297167D02*
X81667D01*
Y298167D01*
X81542Y298500D01*
X81250Y298750D01*
X80917Y298833D01*
X80584Y298750D01*
X80334Y298542D01*
X80209Y298167D01*
Y297167D01*
G01X79167Y301100D02*
X81667D01*
X81167Y300600D01*
G01X79167D02*
Y301600D01*
G01X80209Y303408D02*
X80500Y303700D01*
X80667Y303950D01*
X80750Y304283D01*
X80667Y304575D01*
X80500Y304783D01*
X80250Y304950D01*
X79959Y304992D01*
X79709Y304950D01*
X79459Y304783D01*
X79250Y304533D01*
X79167Y304242D01*
X79250Y303908D01*
X79500Y303617D01*
X79875Y303450D01*
X80292Y303408D01*
X80834Y303492D01*
X81125Y303617D01*
X81417Y303825D01*
X81625Y304117D01*
X81667Y304408D01*
X81584Y304700D01*
X81375Y304908D01*
G01X100900Y286767D02*
X103400D01*
Y287808D01*
X103275Y288142D01*
X103108Y288350D01*
X102775Y288433D01*
X102442Y288350D01*
X102233Y288100D01*
X102108Y287808D01*
Y286767D01*
G01Y287808D02*
X100900Y288433D01*
G01X101192Y289992D02*
X100983Y290283D01*
X100900Y290617D01*
X100983Y290950D01*
X101233Y291242D01*
X101608Y291450D01*
X101983Y291533D01*
X102442D01*
X102817Y291450D01*
X103150Y291242D01*
X103317Y290992D01*
X103400Y290700D01*
X103317Y290367D01*
X103150Y290117D01*
X102900Y289950D01*
X102567Y289867D01*
X102275Y289950D01*
X101983Y290158D01*
X101817Y290408D01*
X101775Y290700D01*
X101858Y291033D01*
X102067Y291283D01*
X102442Y291533D01*
G01X100900Y292967D02*
X103400D01*
Y293967D01*
X103275Y294300D01*
X102983Y294550D01*
X102650Y294633D01*
X102317Y294550D01*
X102067Y294342D01*
X101942Y293967D01*
Y292967D01*
G01X102983Y296108D02*
X103233Y296358D01*
X103358Y296650D01*
X103400Y296983D01*
X103317Y297400D01*
X103108Y297692D01*
X102858Y297775D01*
X102608Y297733D01*
X102400Y297567D01*
X101983Y296733D01*
X101692Y296358D01*
X101275Y296108D01*
X100900Y296025D01*
Y297775D01*
G01Y300000D02*
X103400D01*
X102900Y299500D01*
G01X100900D02*
Y300500D01*
G01X104400Y286667D02*
X106900D01*
Y287708D01*
X106775Y288042D01*
X106608Y288250D01*
X106275Y288333D01*
X105942Y288250D01*
X105733Y288000D01*
X105608Y287708D01*
Y286667D01*
G01Y287708D02*
X104400Y288333D01*
G01X104692Y289892D02*
X104483Y290183D01*
X104400Y290517D01*
X104483Y290850D01*
X104733Y291142D01*
X105108Y291350D01*
X105483Y291433D01*
X105942D01*
X106317Y291350D01*
X106650Y291142D01*
X106817Y290892D01*
X106900Y290600D01*
X106817Y290267D01*
X106650Y290017D01*
X106400Y289850D01*
X106067Y289767D01*
X105775Y289850D01*
X105483Y290058D01*
X105317Y290308D01*
X105275Y290600D01*
X105358Y290933D01*
X105567Y291183D01*
X105942Y291433D01*
G01X104400Y292867D02*
X106900D01*
Y293867D01*
X106775Y294200D01*
X106483Y294450D01*
X106150Y294533D01*
X105817Y294450D01*
X105567Y294242D01*
X105442Y293867D01*
Y292867D01*
G01X104400Y296800D02*
X106900D01*
X106400Y296300D01*
G01X104400D02*
Y297300D01*
G01X104692Y299192D02*
X104483Y299483D01*
X104400Y299817D01*
X104483Y300150D01*
X104733Y300442D01*
X105108Y300650D01*
X105483Y300733D01*
X105942D01*
X106317Y300650D01*
X106650Y300442D01*
X106817Y300192D01*
X106900Y299900D01*
X106817Y299567D01*
X106650Y299317D01*
X106400Y299150D01*
X106067Y299067D01*
X105775Y299150D01*
X105483Y299358D01*
X105317Y299608D01*
X105275Y299900D01*
X105358Y300233D01*
X105567Y300483D01*
X105942Y300733D01*
G01X97400Y286767D02*
X99900D01*
Y287808D01*
X99775Y288142D01*
X99608Y288350D01*
X99275Y288433D01*
X98942Y288350D01*
X98733Y288100D01*
X98608Y287808D01*
Y286767D01*
G01Y287808D02*
X97400Y288433D01*
G01X97692Y289992D02*
X97483Y290283D01*
X97400Y290617D01*
X97483Y290950D01*
X97733Y291242D01*
X98108Y291450D01*
X98483Y291533D01*
X98942D01*
X99317Y291450D01*
X99650Y291242D01*
X99817Y290992D01*
X99900Y290700D01*
X99817Y290367D01*
X99650Y290117D01*
X99400Y289950D01*
X99067Y289867D01*
X98775Y289950D01*
X98483Y290158D01*
X98317Y290408D01*
X98275Y290700D01*
X98358Y291033D01*
X98567Y291283D01*
X98942Y291533D01*
G01X97400Y292967D02*
X99900D01*
Y293967D01*
X99775Y294300D01*
X99483Y294550D01*
X99150Y294633D01*
X98817Y294550D01*
X98567Y294342D01*
X98442Y293967D01*
Y292967D01*
G01X97400Y296900D02*
X99900D01*
X99400Y296400D01*
G01X97400D02*
Y297400D01*
G01Y299917D02*
X97942Y300000D01*
X98400Y300125D01*
X98817Y300292D01*
X99275Y300500D01*
X99900Y300833D01*
Y299167D01*
G01X105883Y282892D02*
X106133Y283017D01*
X106425Y283100D01*
X106758D01*
X107133Y282975D01*
X107425Y282767D01*
X107633Y282517D01*
X107800Y282100D01*
X107842Y281725D01*
X107758Y281350D01*
X107633Y281100D01*
X107383Y280850D01*
X107092Y280683D01*
X106800Y280600D01*
X106508D01*
X106217Y280683D01*
X105967Y280808D01*
X105758Y280975D01*
G01X104408Y280892D02*
X104117Y280683D01*
X103783Y280600D01*
X103450Y280683D01*
X103158Y280933D01*
X102950Y281308D01*
X102867Y281683D01*
Y282142D01*
X102950Y282517D01*
X103158Y282850D01*
X103408Y283017D01*
X103700Y283100D01*
X104033Y283017D01*
X104283Y282850D01*
X104450Y282600D01*
X104533Y282267D01*
X104450Y281975D01*
X104242Y281683D01*
X103992Y281517D01*
X103700Y281475D01*
X103367Y281558D01*
X103117Y281767D01*
X102867Y282142D01*
G01X101433Y280600D02*
Y283100D01*
X100433D01*
X100100Y282975D01*
X99850Y282683D01*
X99767Y282350D01*
X99850Y282017D01*
X100058Y281767D01*
X100433Y281642D01*
X101433D01*
G01X97500Y280600D02*
Y283100D01*
X98000Y282600D01*
G01Y280600D02*
X97000D01*
G01X93900D02*
Y283100D01*
X95442Y281308D01*
X93358D01*
G01X110192Y288417D02*
X110317Y288167D01*
X110400Y287875D01*
Y287542D01*
X110275Y287167D01*
X110067Y286875D01*
X109817Y286667D01*
X109400Y286500D01*
X109025Y286458D01*
X108650Y286542D01*
X108400Y286667D01*
X108150Y286917D01*
X107983Y287208D01*
X107900Y287500D01*
Y287792D01*
X107983Y288083D01*
X108108Y288333D01*
X108275Y288542D01*
G01X108192Y289892D02*
X107983Y290183D01*
X107900Y290517D01*
X107983Y290850D01*
X108233Y291142D01*
X108608Y291350D01*
X108983Y291433D01*
X109442D01*
X109817Y291350D01*
X110150Y291142D01*
X110317Y290892D01*
X110400Y290600D01*
X110317Y290267D01*
X110150Y290017D01*
X109900Y289850D01*
X109567Y289767D01*
X109275Y289850D01*
X108983Y290058D01*
X108817Y290308D01*
X108775Y290600D01*
X108858Y290933D01*
X109067Y291183D01*
X109442Y291433D01*
G01X107900Y292867D02*
X110400D01*
Y293867D01*
X110275Y294200D01*
X109983Y294450D01*
X109650Y294533D01*
X109317Y294450D01*
X109067Y294242D01*
X108942Y293867D01*
Y292867D01*
G01X107900Y296800D02*
X110400D01*
X109900Y296300D01*
G01X107900D02*
Y297300D01*
G01Y299900D02*
X110400D01*
X109900Y299400D01*
G01X107900D02*
Y300400D01*
G01X117231Y320127D02*
X117481Y320252D01*
X117773Y320335D01*
X118106D01*
X118481Y320210D01*
X118773Y320002D01*
X118981Y319752D01*
X119148Y319335D01*
X119190Y318960D01*
X119106Y318585D01*
X118981Y318335D01*
X118731Y318085D01*
X118440Y317918D01*
X118148Y317835D01*
X117856D01*
X117565Y317918D01*
X117315Y318043D01*
X117106Y318210D01*
G01X115048Y320335D02*
Y317835D01*
G01X116006Y320335D02*
X114090D01*
G01X111948Y317835D02*
Y320335D01*
X112448Y319835D01*
G01Y317835D02*
X111448D01*
G01X109556Y318127D02*
X109265Y317918D01*
X108931Y317835D01*
X108598Y317918D01*
X108306Y318168D01*
X108098Y318543D01*
X108015Y318918D01*
Y319377D01*
X108098Y319752D01*
X108306Y320085D01*
X108556Y320252D01*
X108848Y320335D01*
X109181Y320252D01*
X109431Y320085D01*
X109598Y319835D01*
X109681Y319502D01*
X109598Y319210D01*
X109390Y318918D01*
X109140Y318752D01*
X108848Y318710D01*
X108515Y318793D01*
X108265Y319002D01*
X108015Y319377D01*
G01X104802Y330347D02*
X101213D01*
Y332240D01*
X97934Y330347D01*
X101213Y328454D01*
Y330347D01*
G01X97934Y328454D02*
Y332240D01*
G01X93511Y330347D02*
X97934D01*
G01X103992Y341317D02*
X100403D01*
Y343210D01*
X97124Y341317D01*
X100403Y339424D01*
Y341317D01*
G01X97124Y339424D02*
Y343210D01*
G01X92701Y341317D02*
X97124D01*
G01X107150Y314133D02*
X105358D01*
X104983Y314300D01*
X104733Y314633D01*
X104650Y315050D01*
X104733Y315467D01*
X104983Y315800D01*
X105358Y315967D01*
X107150D01*
G01X104942Y317442D02*
X104733Y317733D01*
X104650Y318067D01*
X104733Y318400D01*
X104983Y318692D01*
X105358Y318900D01*
X105733Y318983D01*
X106192D01*
X106567Y318900D01*
X106900Y318692D01*
X107067Y318442D01*
X107150Y318150D01*
X107067Y317817D01*
X106900Y317567D01*
X106650Y317400D01*
X106317Y317317D01*
X106025Y317400D01*
X105733Y317608D01*
X105567Y317858D01*
X105525Y318150D01*
X105608Y318483D01*
X105817Y318733D01*
X106192Y318983D01*
G01X104650Y320417D02*
X107150D01*
Y321417D01*
X107025Y321750D01*
X106733Y322000D01*
X106400Y322083D01*
X106067Y322000D01*
X105817Y321792D01*
X105692Y321417D01*
Y320417D01*
G01X106733Y323558D02*
X106983Y323808D01*
X107108Y324100D01*
X107150Y324433D01*
X107067Y324850D01*
X106858Y325142D01*
X106608Y325225D01*
X106358Y325183D01*
X106150Y325017D01*
X105733Y324183D01*
X105442Y323808D01*
X105025Y323558D01*
X104650Y323475D01*
Y325225D01*
G01X55911Y327145D02*
X55953Y326812D01*
X56119Y326520D01*
X56369Y326270D01*
X56661Y326103D01*
X56994Y326020D01*
X57328D01*
X57661Y326103D01*
X57953Y326270D01*
X58203Y326520D01*
X58369Y326812D01*
X58411Y327145D01*
X58369Y327478D01*
X58203Y327770D01*
X57953Y328020D01*
X57661Y328187D01*
X57328Y328270D01*
X56994D01*
X56661Y328187D01*
X56369Y328020D01*
X56119Y327770D01*
X55953Y327478D01*
X55911Y327145D01*
G01X56578Y327478D02*
X55911Y327978D01*
G01X56203Y329537D02*
X55994Y329828D01*
X55911Y330162D01*
X55994Y330495D01*
X56244Y330787D01*
X56619Y330995D01*
X56994Y331078D01*
X57453D01*
X57828Y330995D01*
X58161Y330787D01*
X58328Y330537D01*
X58411Y330245D01*
X58328Y329912D01*
X58161Y329662D01*
X57911Y329495D01*
X57578Y329412D01*
X57286Y329495D01*
X56994Y329703D01*
X56828Y329953D01*
X56786Y330245D01*
X56869Y330578D01*
X57078Y330828D01*
X57453Y331078D01*
G01X55911Y332512D02*
X58411D01*
Y333512D01*
X58286Y333845D01*
X57994Y334095D01*
X57661Y334178D01*
X57328Y334095D01*
X57078Y333887D01*
X56953Y333512D01*
Y332512D01*
G01X55911Y336445D02*
X58411D01*
X57911Y335945D01*
G01X55911D02*
Y336945D01*
G01X55372Y315550D02*
Y313050D01*
G01X53122Y320300D02*
X49872D01*
Y316800D01*
G01X53122Y308300D02*
X49872D01*
Y311800D01*
G01X85939Y322948D02*
Y318948D01*
X78539D01*
G01X95733Y347300D02*
Y354300D01*
X93067D01*
X92000Y353950D01*
X91200Y353483D01*
X90533Y352783D01*
X90000Y351967D01*
X89867Y350800D01*
X90000Y349633D01*
X90533Y348817D01*
X91200Y348116D01*
X92000Y347650D01*
X93067Y347300D01*
X95733D01*
G01X119529Y367682D02*
X119779Y367807D01*
X120071Y367890D01*
X120404D01*
X120779Y367765D01*
X121071Y367557D01*
X121279Y367307D01*
X121446Y366890D01*
X121488Y366515D01*
X121404Y366140D01*
X121279Y365890D01*
X121029Y365640D01*
X120738Y365473D01*
X120446Y365390D01*
X120154D01*
X119863Y365473D01*
X119613Y365598D01*
X119404Y365765D01*
G01X118054Y365682D02*
X117763Y365473D01*
X117429Y365390D01*
X117096Y365473D01*
X116804Y365723D01*
X116596Y366098D01*
X116513Y366473D01*
Y366932D01*
X116596Y367307D01*
X116804Y367640D01*
X117054Y367807D01*
X117346Y367890D01*
X117679Y367807D01*
X117929Y367640D01*
X118096Y367390D01*
X118179Y367057D01*
X118096Y366765D01*
X117888Y366473D01*
X117638Y366307D01*
X117346Y366265D01*
X117013Y366348D01*
X116763Y366557D01*
X116513Y366932D01*
G01X115204Y365390D02*
Y367890D01*
X113288Y365390D01*
Y367890D01*
G01X111938Y367473D02*
X111688Y367723D01*
X111396Y367848D01*
X111063Y367890D01*
X110646Y367807D01*
X110354Y367598D01*
X110271Y367348D01*
X110313Y367098D01*
X110479Y366890D01*
X111313Y366473D01*
X111688Y366182D01*
X111938Y365765D01*
X112021Y365390D01*
X110271D01*
G01X108963Y365765D02*
X108713Y365557D01*
X108421Y365432D01*
X108046Y365390D01*
X107671Y365473D01*
X107379Y365640D01*
X107171Y365932D01*
X107129Y366265D01*
X107213Y366598D01*
X107421Y366807D01*
X107713Y366973D01*
X108004Y367015D01*
X108296Y366973D01*
X108671Y366807D01*
X108546Y367890D01*
X107421D01*
G01X119529Y364182D02*
X119779Y364307D01*
X120071Y364390D01*
X120404D01*
X120779Y364265D01*
X121071Y364057D01*
X121279Y363807D01*
X121446Y363390D01*
X121488Y363015D01*
X121404Y362640D01*
X121279Y362390D01*
X121029Y362140D01*
X120738Y361973D01*
X120446Y361890D01*
X120154D01*
X119863Y361973D01*
X119613Y362098D01*
X119404Y362265D01*
G01X118054Y362182D02*
X117763Y361973D01*
X117429Y361890D01*
X117096Y361973D01*
X116804Y362223D01*
X116596Y362598D01*
X116513Y362973D01*
Y363432D01*
X116596Y363807D01*
X116804Y364140D01*
X117054Y364307D01*
X117346Y364390D01*
X117679Y364307D01*
X117929Y364140D01*
X118096Y363890D01*
X118179Y363557D01*
X118096Y363265D01*
X117888Y362973D01*
X117638Y362807D01*
X117346Y362765D01*
X117013Y362848D01*
X116763Y363057D01*
X116513Y363432D01*
G01X115204Y361890D02*
Y364390D01*
X113288Y361890D01*
Y364390D01*
G01X111938Y363973D02*
X111688Y364223D01*
X111396Y364348D01*
X111063Y364390D01*
X110646Y364307D01*
X110354Y364098D01*
X110271Y363848D01*
X110313Y363598D01*
X110479Y363390D01*
X111313Y362973D01*
X111688Y362682D01*
X111938Y362265D01*
X112021Y361890D01*
X110271D01*
G01X108838Y362932D02*
X108546Y363223D01*
X108296Y363390D01*
X107963Y363473D01*
X107671Y363390D01*
X107463Y363223D01*
X107296Y362973D01*
X107254Y362682D01*
X107296Y362432D01*
X107463Y362182D01*
X107713Y361973D01*
X108004Y361890D01*
X108338Y361973D01*
X108629Y362223D01*
X108796Y362598D01*
X108838Y363015D01*
X108754Y363557D01*
X108629Y363848D01*
X108421Y364140D01*
X108129Y364348D01*
X107838Y364390D01*
X107546Y364307D01*
X107338Y364098D01*
G01X119233Y345500D02*
Y348000D01*
X118192D01*
X117858Y347875D01*
X117650Y347708D01*
X117567Y347375D01*
X117650Y347042D01*
X117900Y346833D01*
X118192Y346708D01*
X119233D01*
G01X118192D02*
X117567Y345500D01*
G01X116008Y345792D02*
X115717Y345583D01*
X115383Y345500D01*
X115050Y345583D01*
X114758Y345833D01*
X114550Y346208D01*
X114467Y346583D01*
Y347042D01*
X114550Y347417D01*
X114758Y347750D01*
X115008Y347917D01*
X115300Y348000D01*
X115633Y347917D01*
X115883Y347750D01*
X116050Y347500D01*
X116133Y347167D01*
X116050Y346875D01*
X115842Y346583D01*
X115592Y346417D01*
X115300Y346375D01*
X114967Y346458D01*
X114717Y346667D01*
X114467Y347042D01*
G01X113033Y345500D02*
Y348000D01*
X112033D01*
X111700Y347875D01*
X111450Y347583D01*
X111367Y347250D01*
X111450Y346917D01*
X111658Y346667D01*
X112033Y346542D01*
X113033D01*
G01X110017Y346000D02*
X109767Y345708D01*
X109433Y345542D01*
X109058Y345500D01*
X108725Y345542D01*
X108392Y345750D01*
X108183Y346000D01*
X108142Y346250D01*
X108225Y346542D01*
X108517Y346750D01*
X108808Y346833D01*
X109183D01*
G01X108808D02*
X108558Y346958D01*
X108350Y347167D01*
X108267Y347417D01*
X108350Y347667D01*
X108558Y347875D01*
X108933Y348000D01*
X109308Y347958D01*
X109683Y347792D01*
G01X106792Y347583D02*
X106542Y347833D01*
X106250Y347958D01*
X105917Y348000D01*
X105500Y347917D01*
X105208Y347708D01*
X105125Y347458D01*
X105167Y347208D01*
X105333Y347000D01*
X106167Y346583D01*
X106542Y346292D01*
X106792Y345875D01*
X106875Y345500D01*
X105125D01*
G01X70650Y370017D02*
X73150D01*
Y371058D01*
X73025Y371392D01*
X72858Y371600D01*
X72525Y371683D01*
X72192Y371600D01*
X71983Y371350D01*
X71858Y371058D01*
Y370017D01*
G01Y371058D02*
X70650Y371683D01*
G01X70942Y373242D02*
X70733Y373533D01*
X70650Y373867D01*
X70733Y374200D01*
X70983Y374492D01*
X71358Y374700D01*
X71733Y374783D01*
X72192D01*
X72567Y374700D01*
X72900Y374492D01*
X73067Y374242D01*
X73150Y373950D01*
X73067Y373617D01*
X72900Y373367D01*
X72650Y373200D01*
X72317Y373117D01*
X72025Y373200D01*
X71733Y373408D01*
X71567Y373658D01*
X71525Y373950D01*
X71608Y374283D01*
X71817Y374533D01*
X72192Y374783D01*
G01X70650Y376092D02*
X73150D01*
X70650Y378008D01*
X73150D01*
G01X70650Y380150D02*
X70692Y380442D01*
X70817Y380775D01*
X71025Y380983D01*
X71317Y381067D01*
X71608Y380983D01*
X71858Y380733D01*
X71983Y380358D01*
Y379942D01*
X72067Y379692D01*
X72275Y379483D01*
X72567Y379400D01*
X72858Y379525D01*
X73067Y379817D01*
X73150Y380150D01*
X73067Y380483D01*
X72858Y380775D01*
X72567Y380900D01*
X72275Y380817D01*
X72067Y380608D01*
X71983Y380358D01*
Y379942D01*
X71858Y379567D01*
X71608Y379317D01*
X71317Y379233D01*
X71025Y379317D01*
X70817Y379525D01*
X70692Y379858D01*
X70650Y380150D01*
G01X83850Y367717D02*
X86350D01*
Y368758D01*
X86225Y369092D01*
X86058Y369300D01*
X85725Y369383D01*
X85392Y369300D01*
X85183Y369050D01*
X85058Y368758D01*
Y367717D01*
G01Y368758D02*
X83850Y369383D01*
G01X84142Y370942D02*
X83933Y371233D01*
X83850Y371567D01*
X83933Y371900D01*
X84183Y372192D01*
X84558Y372400D01*
X84933Y372483D01*
X85392D01*
X85767Y372400D01*
X86100Y372192D01*
X86267Y371942D01*
X86350Y371650D01*
X86267Y371317D01*
X86100Y371067D01*
X85850Y370900D01*
X85517Y370817D01*
X85225Y370900D01*
X84933Y371108D01*
X84767Y371358D01*
X84725Y371650D01*
X84808Y371983D01*
X85017Y372233D01*
X85392Y372483D01*
G01X83850Y373792D02*
X86350D01*
X83850Y375708D01*
X86350D01*
G01X83850Y377767D02*
X84392Y377850D01*
X84850Y377975D01*
X85267Y378142D01*
X85725Y378350D01*
X86350Y378683D01*
Y377017D01*
G01X112633Y351392D02*
X112883Y351517D01*
X113175Y351600D01*
X113508D01*
X113883Y351475D01*
X114175Y351267D01*
X114383Y351017D01*
X114550Y350600D01*
X114592Y350225D01*
X114508Y349850D01*
X114383Y349600D01*
X114133Y349350D01*
X113842Y349183D01*
X113550Y349100D01*
X113258D01*
X112967Y349183D01*
X112717Y349308D01*
X112508Y349475D01*
G01X110450Y351600D02*
Y349100D01*
G01X111408Y351600D02*
X109492D01*
G01X107350Y349100D02*
Y351600D01*
X107850Y351100D01*
G01Y349100D02*
X106850D01*
G01X105167Y349475D02*
X104917Y349267D01*
X104625Y349142D01*
X104250Y349100D01*
X103875Y349183D01*
X103583Y349350D01*
X103375Y349642D01*
X103333Y349975D01*
X103417Y350308D01*
X103625Y350517D01*
X103917Y350683D01*
X104208Y350725D01*
X104500Y350683D01*
X104875Y350517D01*
X104750Y351600D01*
X103625D01*
G01X88463Y395672D02*
X88713Y395797D01*
X89005Y395880D01*
X89338D01*
X89713Y395755D01*
X90005Y395547D01*
X90213Y395297D01*
X90380Y394880D01*
X90422Y394505D01*
X90338Y394130D01*
X90213Y393880D01*
X89963Y393630D01*
X89672Y393463D01*
X89380Y393380D01*
X89088D01*
X88797Y393463D01*
X88547Y393588D01*
X88338Y393755D01*
G01X86988Y393672D02*
X86697Y393463D01*
X86363Y393380D01*
X86030Y393463D01*
X85738Y393713D01*
X85530Y394088D01*
X85447Y394463D01*
Y394922D01*
X85530Y395297D01*
X85738Y395630D01*
X85988Y395797D01*
X86280Y395880D01*
X86613Y395797D01*
X86863Y395630D01*
X87030Y395380D01*
X87113Y395047D01*
X87030Y394755D01*
X86822Y394463D01*
X86572Y394297D01*
X86280Y394255D01*
X85947Y394338D01*
X85697Y394547D01*
X85447Y394922D01*
G01X84138Y393380D02*
Y395880D01*
X82222Y393380D01*
Y395880D01*
G01X80080Y393380D02*
Y395880D01*
X80580Y395380D01*
G01Y393380D02*
X79580D01*
G01X77772Y395463D02*
X77522Y395713D01*
X77230Y395838D01*
X76897Y395880D01*
X76480Y395797D01*
X76188Y395588D01*
X76105Y395338D01*
X76147Y395088D01*
X76313Y394880D01*
X77147Y394463D01*
X77522Y394172D01*
X77772Y393755D01*
X77855Y393380D01*
X76105D01*
G01X84663Y388572D02*
X84913Y388697D01*
X85205Y388780D01*
X85538D01*
X85913Y388655D01*
X86205Y388447D01*
X86413Y388197D01*
X86580Y387780D01*
X86622Y387405D01*
X86538Y387030D01*
X86413Y386780D01*
X86163Y386530D01*
X85872Y386363D01*
X85580Y386280D01*
X85288D01*
X84997Y386363D01*
X84747Y386488D01*
X84538Y386655D01*
G01X83188Y386572D02*
X82897Y386363D01*
X82563Y386280D01*
X82230Y386363D01*
X81938Y386613D01*
X81730Y386988D01*
X81647Y387363D01*
Y387822D01*
X81730Y388197D01*
X81938Y388530D01*
X82188Y388697D01*
X82480Y388780D01*
X82813Y388697D01*
X83063Y388530D01*
X83230Y388280D01*
X83313Y387947D01*
X83230Y387655D01*
X83022Y387363D01*
X82772Y387197D01*
X82480Y387155D01*
X82147Y387238D01*
X81897Y387447D01*
X81647Y387822D01*
G01X80338Y386280D02*
Y388780D01*
X78422Y386280D01*
Y388780D01*
G01X76280Y386280D02*
Y388780D01*
X76780Y388280D01*
G01Y386280D02*
X75780D01*
G01X74097Y386655D02*
X73847Y386447D01*
X73555Y386322D01*
X73180Y386280D01*
X72805Y386363D01*
X72513Y386530D01*
X72305Y386822D01*
X72263Y387155D01*
X72347Y387488D01*
X72555Y387697D01*
X72847Y387863D01*
X73138Y387905D01*
X73430Y387863D01*
X73805Y387697D01*
X73680Y388780D01*
X72555D01*
G01X85613Y406072D02*
X85863Y406197D01*
X86155Y406280D01*
X86488D01*
X86863Y406155D01*
X87155Y405947D01*
X87363Y405697D01*
X87530Y405280D01*
X87572Y404905D01*
X87488Y404530D01*
X87363Y404280D01*
X87113Y404030D01*
X86822Y403863D01*
X86530Y403780D01*
X86238D01*
X85947Y403863D01*
X85697Y403988D01*
X85488Y404155D01*
G01X84138Y404072D02*
X83847Y403863D01*
X83513Y403780D01*
X83180Y403863D01*
X82888Y404113D01*
X82680Y404488D01*
X82597Y404863D01*
Y405322D01*
X82680Y405697D01*
X82888Y406030D01*
X83138Y406197D01*
X83430Y406280D01*
X83763Y406197D01*
X84013Y406030D01*
X84180Y405780D01*
X84263Y405447D01*
X84180Y405155D01*
X83972Y404863D01*
X83722Y404697D01*
X83430Y404655D01*
X83097Y404738D01*
X82847Y404947D01*
X82597Y405322D01*
G01X81288Y403780D02*
Y406280D01*
X79372Y403780D01*
Y406280D01*
G01X77313Y403780D02*
X77230Y404322D01*
X77105Y404780D01*
X76938Y405197D01*
X76730Y405655D01*
X76397Y406280D01*
X78063D01*
G01X85613Y402572D02*
X85863Y402697D01*
X86155Y402780D01*
X86488D01*
X86863Y402655D01*
X87155Y402447D01*
X87363Y402197D01*
X87530Y401780D01*
X87572Y401405D01*
X87488Y401030D01*
X87363Y400780D01*
X87113Y400530D01*
X86822Y400363D01*
X86530Y400280D01*
X86238D01*
X85947Y400363D01*
X85697Y400488D01*
X85488Y400655D01*
G01X84138Y400572D02*
X83847Y400363D01*
X83513Y400280D01*
X83180Y400363D01*
X82888Y400613D01*
X82680Y400988D01*
X82597Y401363D01*
Y401822D01*
X82680Y402197D01*
X82888Y402530D01*
X83138Y402697D01*
X83430Y402780D01*
X83763Y402697D01*
X84013Y402530D01*
X84180Y402280D01*
X84263Y401947D01*
X84180Y401655D01*
X83972Y401363D01*
X83722Y401197D01*
X83430Y401155D01*
X83097Y401238D01*
X82847Y401447D01*
X82597Y401822D01*
G01X81288Y400280D02*
Y402780D01*
X79372Y400280D01*
Y402780D01*
G01X77938Y400572D02*
X77647Y400363D01*
X77313Y400280D01*
X76980Y400363D01*
X76688Y400613D01*
X76480Y400988D01*
X76397Y401363D01*
Y401822D01*
X76480Y402197D01*
X76688Y402530D01*
X76938Y402697D01*
X77230Y402780D01*
X77563Y402697D01*
X77813Y402530D01*
X77980Y402280D01*
X78063Y401947D01*
X77980Y401655D01*
X77772Y401363D01*
X77522Y401197D01*
X77230Y401155D01*
X76897Y401238D01*
X76647Y401447D01*
X76397Y401822D01*
G01X115317Y380802D02*
X115567Y380927D01*
X115859Y381010D01*
X116192D01*
X116567Y380885D01*
X116859Y380677D01*
X117067Y380427D01*
X117234Y380010D01*
X117276Y379635D01*
X117192Y379260D01*
X117067Y379010D01*
X116817Y378760D01*
X116526Y378593D01*
X116234Y378510D01*
X115942D01*
X115651Y378593D01*
X115401Y378718D01*
X115192Y378885D01*
G01X113134Y381010D02*
Y378510D01*
G01X114092Y381010D02*
X112176D01*
G01X110951Y378885D02*
X110701Y378677D01*
X110409Y378552D01*
X110034Y378510D01*
X109659Y378593D01*
X109367Y378760D01*
X109159Y379052D01*
X109117Y379385D01*
X109201Y379718D01*
X109409Y379927D01*
X109701Y380093D01*
X109992Y380135D01*
X110284Y380093D01*
X110659Y379927D01*
X110534Y381010D01*
X109409D01*
G01X107851Y378885D02*
X107601Y378677D01*
X107309Y378552D01*
X106934Y378510D01*
X106559Y378593D01*
X106267Y378760D01*
X106059Y379052D01*
X106017Y379385D01*
X106101Y379718D01*
X106309Y379927D01*
X106601Y380093D01*
X106892Y380135D01*
X107184Y380093D01*
X107559Y379927D01*
X107434Y381010D01*
X106309D01*
G01X93450Y359467D02*
X93783Y359509D01*
X94075Y359675D01*
X94325Y359925D01*
X94492Y360217D01*
X94575Y360550D01*
Y360884D01*
X94492Y361217D01*
X94325Y361509D01*
X94075Y361759D01*
X93783Y361925D01*
X93450Y361967D01*
X93117Y361925D01*
X92825Y361759D01*
X92575Y361509D01*
X92408Y361217D01*
X92325Y360884D01*
Y360550D01*
X92408Y360217D01*
X92575Y359925D01*
X92825Y359675D01*
X93117Y359509D01*
X93450Y359467D01*
G01X93117Y360134D02*
X92617Y359467D01*
G01X91142Y360509D02*
X90850Y360800D01*
X90600Y360967D01*
X90267Y361050D01*
X89975Y360967D01*
X89767Y360800D01*
X89600Y360550D01*
X89558Y360259D01*
X89600Y360009D01*
X89767Y359759D01*
X90017Y359550D01*
X90308Y359467D01*
X90642Y359550D01*
X90933Y359800D01*
X91100Y360175D01*
X91142Y360592D01*
X91058Y361134D01*
X90933Y361425D01*
X90725Y361717D01*
X90433Y361925D01*
X90142Y361967D01*
X89850Y361884D01*
X89642Y361675D01*
G01X88500Y361967D02*
X87917Y359467D01*
X87250Y361967D01*
X86583Y359467D01*
X86000Y361967D01*
G01X84150Y359467D02*
Y361967D01*
X84650Y361467D01*
G01Y359467D02*
X83650D01*
G01X70500Y358500D02*
Y361750D01*
X74000D01*
G01X82500Y358500D02*
Y361750D01*
X79000D01*
G01X77750Y356250D02*
X75250D01*
G01X71200Y366500D02*
Y362500D01*
X63800D01*
G01X52292Y366367D02*
X52417Y366117D01*
X52500Y365825D01*
Y365492D01*
X52375Y365117D01*
X52167Y364825D01*
X51917Y364617D01*
X51500Y364450D01*
X51125Y364408D01*
X50750Y364492D01*
X50500Y364617D01*
X50250Y364867D01*
X50083Y365158D01*
X50000Y365450D01*
Y365742D01*
X50083Y366033D01*
X50208Y366283D01*
X50375Y366492D01*
G01X50292Y367842D02*
X50083Y368133D01*
X50000Y368467D01*
X50083Y368800D01*
X50333Y369092D01*
X50708Y369300D01*
X51083Y369383D01*
X51542D01*
X51917Y369300D01*
X52250Y369092D01*
X52417Y368842D01*
X52500Y368550D01*
X52417Y368217D01*
X52250Y367967D01*
X52000Y367800D01*
X51667Y367717D01*
X51375Y367800D01*
X51083Y368008D01*
X50917Y368258D01*
X50875Y368550D01*
X50958Y368883D01*
X51167Y369133D01*
X51542Y369383D01*
G01X52500Y370400D02*
X50000Y370983D01*
X52500Y371650D01*
X50000Y372317D01*
X52500Y372900D01*
G01X50000Y374750D02*
X52500D01*
X52000Y374250D01*
G01X50000D02*
Y375250D01*
G01X77995Y459514D02*
X78120Y459264D01*
X78203Y458972D01*
Y458639D01*
X78078Y458264D01*
X77870Y457972D01*
X77620Y457764D01*
X77203Y457597D01*
X76828Y457555D01*
X76453Y457639D01*
X76203Y457764D01*
X75953Y458014D01*
X75786Y458305D01*
X75703Y458597D01*
Y458889D01*
X75786Y459180D01*
X75911Y459430D01*
X76078Y459639D01*
G01X75703Y461697D02*
X78203D01*
X77703Y461197D01*
G01X75703D02*
Y462197D01*
G01X78203Y464797D02*
X78120Y464464D01*
X77911Y464214D01*
X77661Y464047D01*
X77328Y463922D01*
X76953Y463880D01*
X76578Y463922D01*
X76245Y464047D01*
X75995Y464214D01*
X75786Y464464D01*
X75703Y464797D01*
X75786Y465130D01*
X75995Y465380D01*
X76245Y465547D01*
X76578Y465672D01*
X76953Y465714D01*
X77328Y465672D01*
X77661Y465547D01*
X77911Y465380D01*
X78120Y465130D01*
X78203Y464797D01*
G01Y466647D02*
X75703Y467230D01*
X78203Y467897D01*
X75703Y468564D01*
X78203Y469147D01*
G01X75703Y470997D02*
X78203D01*
X77703Y470497D01*
G01X75703D02*
Y471497D01*
G01X68231Y459611D02*
X70731D01*
Y460652D01*
X70606Y460986D01*
X70439Y461194D01*
X70106Y461277D01*
X69773Y461194D01*
X69564Y460944D01*
X69439Y460652D01*
Y459611D01*
G01Y460652D02*
X68231Y461277D01*
G01Y463544D02*
X70731D01*
X70231Y463044D01*
G01X68231D02*
Y464044D01*
G01X70314Y465852D02*
X70564Y466102D01*
X70689Y466394D01*
X70731Y466727D01*
X70648Y467144D01*
X70439Y467436D01*
X70189Y467519D01*
X69939Y467477D01*
X69731Y467311D01*
X69314Y466477D01*
X69023Y466102D01*
X68606Y465852D01*
X68231Y465769D01*
Y467519D01*
G01X70731Y468494D02*
X68231Y469077D01*
X70731Y469744D01*
X68231Y470411D01*
X70731Y470994D01*
G01X68231Y472844D02*
X70731D01*
X70231Y472344D01*
G01X68231D02*
Y473344D01*
G01X68523Y475236D02*
X68314Y475527D01*
X68231Y475861D01*
X68314Y476194D01*
X68564Y476486D01*
X68939Y476694D01*
X69314Y476777D01*
X69773D01*
X70148Y476694D01*
X70481Y476486D01*
X70648Y476236D01*
X70731Y475944D01*
X70648Y475611D01*
X70481Y475361D01*
X70231Y475194D01*
X69898Y475111D01*
X69606Y475194D01*
X69314Y475402D01*
X69148Y475652D01*
X69106Y475944D01*
X69189Y476277D01*
X69398Y476527D01*
X69773Y476777D01*
G01X86313Y415172D02*
X86563Y415297D01*
X86855Y415380D01*
X87188D01*
X87563Y415255D01*
X87855Y415047D01*
X88063Y414797D01*
X88230Y414380D01*
X88272Y414005D01*
X88188Y413630D01*
X88063Y413380D01*
X87813Y413130D01*
X87522Y412963D01*
X87230Y412880D01*
X86938D01*
X86647Y412963D01*
X86397Y413088D01*
X86188Y413255D01*
G01X84838Y413172D02*
X84547Y412963D01*
X84213Y412880D01*
X83880Y412963D01*
X83588Y413213D01*
X83380Y413588D01*
X83297Y413963D01*
Y414422D01*
X83380Y414797D01*
X83588Y415130D01*
X83838Y415297D01*
X84130Y415380D01*
X84463Y415297D01*
X84713Y415130D01*
X84880Y414880D01*
X84963Y414547D01*
X84880Y414255D01*
X84672Y413963D01*
X84422Y413797D01*
X84130Y413755D01*
X83797Y413838D01*
X83547Y414047D01*
X83297Y414422D01*
G01X81988Y412880D02*
Y415380D01*
X80072Y412880D01*
Y415380D01*
G01X78722Y413922D02*
X78430Y414213D01*
X78180Y414380D01*
X77847Y414463D01*
X77555Y414380D01*
X77347Y414213D01*
X77180Y413963D01*
X77138Y413672D01*
X77180Y413422D01*
X77347Y413172D01*
X77597Y412963D01*
X77888Y412880D01*
X78222Y412963D01*
X78513Y413213D01*
X78680Y413588D01*
X78722Y414005D01*
X78638Y414547D01*
X78513Y414838D01*
X78305Y415130D01*
X78013Y415338D01*
X77722Y415380D01*
X77430Y415297D01*
X77222Y415088D01*
G01X86313Y418672D02*
X86563Y418797D01*
X86855Y418880D01*
X87188D01*
X87563Y418755D01*
X87855Y418547D01*
X88063Y418297D01*
X88230Y417880D01*
X88272Y417505D01*
X88188Y417130D01*
X88063Y416880D01*
X87813Y416630D01*
X87522Y416463D01*
X87230Y416380D01*
X86938D01*
X86647Y416463D01*
X86397Y416588D01*
X86188Y416755D01*
G01X84838Y416672D02*
X84547Y416463D01*
X84213Y416380D01*
X83880Y416463D01*
X83588Y416713D01*
X83380Y417088D01*
X83297Y417463D01*
Y417922D01*
X83380Y418297D01*
X83588Y418630D01*
X83838Y418797D01*
X84130Y418880D01*
X84463Y418797D01*
X84713Y418630D01*
X84880Y418380D01*
X84963Y418047D01*
X84880Y417755D01*
X84672Y417463D01*
X84422Y417297D01*
X84130Y417255D01*
X83797Y417338D01*
X83547Y417547D01*
X83297Y417922D01*
G01X81988Y416380D02*
Y418880D01*
X80072Y416380D01*
Y418880D01*
G01X78847Y416755D02*
X78597Y416547D01*
X78305Y416422D01*
X77930Y416380D01*
X77555Y416463D01*
X77263Y416630D01*
X77055Y416922D01*
X77013Y417255D01*
X77097Y417588D01*
X77305Y417797D01*
X77597Y417963D01*
X77888Y418005D01*
X78180Y417963D01*
X78555Y417797D01*
X78430Y418880D01*
X77305D01*
G01X57173Y431562D02*
X57423Y431687D01*
X57715Y431770D01*
X58048D01*
X58423Y431645D01*
X58715Y431437D01*
X58923Y431187D01*
X59090Y430770D01*
X59132Y430395D01*
X59048Y430020D01*
X58923Y429770D01*
X58673Y429520D01*
X58382Y429353D01*
X58090Y429270D01*
X57798D01*
X57507Y429353D01*
X57257Y429478D01*
X57048Y429645D01*
G01X55698Y429562D02*
X55407Y429353D01*
X55073Y429270D01*
X54740Y429353D01*
X54448Y429603D01*
X54240Y429978D01*
X54157Y430353D01*
Y430812D01*
X54240Y431187D01*
X54448Y431520D01*
X54698Y431687D01*
X54990Y431770D01*
X55323Y431687D01*
X55573Y431520D01*
X55740Y431270D01*
X55823Y430937D01*
X55740Y430645D01*
X55532Y430353D01*
X55282Y430187D01*
X54990Y430145D01*
X54657Y430228D01*
X54407Y430437D01*
X54157Y430812D01*
G01X52848Y429270D02*
Y431770D01*
X50932Y429270D01*
Y431770D01*
G01X49707Y429770D02*
X49457Y429478D01*
X49123Y429312D01*
X48748Y429270D01*
X48415Y429312D01*
X48082Y429520D01*
X47873Y429770D01*
X47832Y430020D01*
X47915Y430312D01*
X48207Y430520D01*
X48498Y430603D01*
X48873D01*
G01X48498D02*
X48248Y430728D01*
X48040Y430937D01*
X47957Y431187D01*
X48040Y431437D01*
X48248Y431645D01*
X48623Y431770D01*
X48998Y431728D01*
X49373Y431562D01*
G01X57173Y428062D02*
X57423Y428187D01*
X57715Y428270D01*
X58048D01*
X58423Y428145D01*
X58715Y427937D01*
X58923Y427687D01*
X59090Y427270D01*
X59132Y426895D01*
X59048Y426520D01*
X58923Y426270D01*
X58673Y426020D01*
X58382Y425853D01*
X58090Y425770D01*
X57798D01*
X57507Y425853D01*
X57257Y425978D01*
X57048Y426145D01*
G01X55698Y426062D02*
X55407Y425853D01*
X55073Y425770D01*
X54740Y425853D01*
X54448Y426103D01*
X54240Y426478D01*
X54157Y426853D01*
Y427312D01*
X54240Y427687D01*
X54448Y428020D01*
X54698Y428187D01*
X54990Y428270D01*
X55323Y428187D01*
X55573Y428020D01*
X55740Y427770D01*
X55823Y427437D01*
X55740Y427145D01*
X55532Y426853D01*
X55282Y426687D01*
X54990Y426645D01*
X54657Y426728D01*
X54407Y426937D01*
X54157Y427312D01*
G01X52848Y425770D02*
Y428270D01*
X50932Y425770D01*
Y428270D01*
G01X48290Y425770D02*
Y428270D01*
X49832Y426478D01*
X47748D01*
G01X74363Y432672D02*
X74613Y432797D01*
X74905Y432880D01*
X75238D01*
X75613Y432755D01*
X75905Y432547D01*
X76113Y432297D01*
X76280Y431880D01*
X76322Y431505D01*
X76238Y431130D01*
X76113Y430880D01*
X75863Y430630D01*
X75572Y430463D01*
X75280Y430380D01*
X74988D01*
X74697Y430463D01*
X74447Y430588D01*
X74238Y430755D01*
G01X72888Y430672D02*
X72597Y430463D01*
X72263Y430380D01*
X71930Y430463D01*
X71638Y430713D01*
X71430Y431088D01*
X71347Y431463D01*
Y431922D01*
X71430Y432297D01*
X71638Y432630D01*
X71888Y432797D01*
X72180Y432880D01*
X72513Y432797D01*
X72763Y432630D01*
X72930Y432380D01*
X73013Y432047D01*
X72930Y431755D01*
X72722Y431463D01*
X72472Y431297D01*
X72180Y431255D01*
X71847Y431338D01*
X71597Y431547D01*
X71347Y431922D01*
G01X70038Y430380D02*
Y432880D01*
X68122Y430380D01*
Y432880D01*
G01X66772Y432463D02*
X66522Y432713D01*
X66230Y432838D01*
X65897Y432880D01*
X65480Y432797D01*
X65188Y432588D01*
X65105Y432338D01*
X65147Y432088D01*
X65313Y431880D01*
X66147Y431463D01*
X66522Y431172D01*
X66772Y430755D01*
X66855Y430380D01*
X65105D01*
G01X74363Y436172D02*
X74613Y436297D01*
X74905Y436380D01*
X75238D01*
X75613Y436255D01*
X75905Y436047D01*
X76113Y435797D01*
X76280Y435380D01*
X76322Y435005D01*
X76238Y434630D01*
X76113Y434380D01*
X75863Y434130D01*
X75572Y433963D01*
X75280Y433880D01*
X74988D01*
X74697Y433963D01*
X74447Y434088D01*
X74238Y434255D01*
G01X72888Y434172D02*
X72597Y433963D01*
X72263Y433880D01*
X71930Y433963D01*
X71638Y434213D01*
X71430Y434588D01*
X71347Y434963D01*
Y435422D01*
X71430Y435797D01*
X71638Y436130D01*
X71888Y436297D01*
X72180Y436380D01*
X72513Y436297D01*
X72763Y436130D01*
X72930Y435880D01*
X73013Y435547D01*
X72930Y435255D01*
X72722Y434963D01*
X72472Y434797D01*
X72180Y434755D01*
X71847Y434838D01*
X71597Y435047D01*
X71347Y435422D01*
G01X70038Y433880D02*
Y436380D01*
X68122Y433880D01*
Y436380D01*
G01X65980Y433880D02*
Y436380D01*
X66480Y435880D01*
G01Y433880D02*
X65480D01*
G01X74160Y459423D02*
X74285Y459173D01*
X74368Y458881D01*
Y458548D01*
X74243Y458173D01*
X74035Y457881D01*
X73785Y457673D01*
X73368Y457506D01*
X72993Y457464D01*
X72618Y457548D01*
X72368Y457673D01*
X72118Y457923D01*
X71951Y458214D01*
X71868Y458506D01*
Y458798D01*
X71951Y459089D01*
X72076Y459339D01*
X72243Y459548D01*
G01X71868Y461606D02*
X74368D01*
X73868Y461106D01*
G01X71868D02*
Y462106D01*
G01X74368Y464706D02*
X74285Y464373D01*
X74076Y464123D01*
X73826Y463956D01*
X73493Y463831D01*
X73118Y463789D01*
X72743Y463831D01*
X72410Y463956D01*
X72160Y464123D01*
X71951Y464373D01*
X71868Y464706D01*
X71951Y465039D01*
X72160Y465289D01*
X72410Y465456D01*
X72743Y465581D01*
X73118Y465623D01*
X73493Y465581D01*
X73826Y465456D01*
X74076Y465289D01*
X74285Y465039D01*
X74368Y464706D01*
G01Y466556D02*
X71868Y467139D01*
X74368Y467806D01*
X71868Y468473D01*
X74368Y469056D01*
G01X73951Y470114D02*
X74201Y470364D01*
X74326Y470656D01*
X74368Y470989D01*
X74285Y471406D01*
X74076Y471698D01*
X73826Y471781D01*
X73576Y471739D01*
X73368Y471573D01*
X72951Y470739D01*
X72660Y470364D01*
X72243Y470114D01*
X71868Y470031D01*
Y471781D01*
G01X87617Y480120D02*
X87425Y479810D01*
X87195Y479603D01*
X86927Y479500D01*
X86620Y479603D01*
X86390Y479810D01*
X86160Y480120D01*
X86083Y480533D01*
Y482600D01*
G01X84248Y480533D02*
X83252D01*
G01X80190Y479500D02*
Y482600D01*
X81608Y480378D01*
X79692D01*
G01X72733Y482842D02*
X72983Y482967D01*
X73275Y483050D01*
X73608D01*
X73983Y482925D01*
X74275Y482717D01*
X74483Y482467D01*
X74650Y482050D01*
X74692Y481675D01*
X74608Y481300D01*
X74483Y481050D01*
X74233Y480800D01*
X73942Y480633D01*
X73650Y480550D01*
X73358D01*
X73067Y480633D01*
X72817Y480758D01*
X72608Y480925D01*
G01X71258Y480842D02*
X70967Y480633D01*
X70633Y480550D01*
X70300Y480633D01*
X70008Y480883D01*
X69800Y481258D01*
X69717Y481633D01*
Y482092D01*
X69800Y482467D01*
X70008Y482800D01*
X70258Y482967D01*
X70550Y483050D01*
X70883Y482967D01*
X71133Y482800D01*
X71300Y482550D01*
X71383Y482217D01*
X71300Y481925D01*
X71092Y481633D01*
X70842Y481467D01*
X70550Y481425D01*
X70217Y481508D01*
X69967Y481717D01*
X69717Y482092D01*
G01X68533Y480550D02*
Y483050D01*
X67450Y480967D01*
X66367Y483050D01*
Y480550D01*
G01X65267Y481050D02*
X65017Y480758D01*
X64683Y480592D01*
X64308Y480550D01*
X63975Y480592D01*
X63642Y480800D01*
X63433Y481050D01*
X63392Y481300D01*
X63475Y481592D01*
X63767Y481800D01*
X64058Y481883D01*
X64433D01*
G01X64058D02*
X63808Y482008D01*
X63600Y482217D01*
X63517Y482467D01*
X63600Y482717D01*
X63808Y482925D01*
X64183Y483050D01*
X64558Y483008D01*
X64933Y482842D01*
G01X82350Y519400D02*
Y496825D01*
G01X64350Y519400D02*
Y496828D01*
G01Y519400D02*
X67045D01*
G01X82350D02*
X79652D01*
G01X79650Y484036D02*
X83212D01*
Y496832D01*
X79650D01*
G01X67050Y484036D02*
X63259D01*
Y496832D01*
X67050D01*
G01X83850Y508517D02*
X83600Y508725D01*
X83433Y508975D01*
X83350Y509267D01*
X83433Y509600D01*
X83600Y509850D01*
X83850Y510100D01*
X84183Y510183D01*
X85850D01*
G01X83642Y511742D02*
X83433Y512033D01*
X83350Y512367D01*
X83433Y512700D01*
X83683Y512992D01*
X84058Y513200D01*
X84433Y513283D01*
X84892D01*
X85267Y513200D01*
X85600Y512992D01*
X85767Y512742D01*
X85850Y512450D01*
X85767Y512117D01*
X85600Y511867D01*
X85350Y511700D01*
X85017Y511617D01*
X84725Y511700D01*
X84433Y511908D01*
X84267Y512158D01*
X84225Y512450D01*
X84308Y512783D01*
X84517Y513033D01*
X84892Y513283D01*
G01X83350Y514467D02*
X85850D01*
X83767Y515550D01*
X85850Y516633D01*
X83350D01*
G01Y518650D02*
X85850D01*
X85350Y518150D01*
G01X83350D02*
Y519150D01*
G01X111100Y526874D02*
X86710D01*
Y501284D01*
X111100D01*
G01X61268Y533272D02*
Y535772D01*
X60227D01*
X59893Y535647D01*
X59685Y535480D01*
X59602Y535147D01*
X59685Y534814D01*
X59935Y534605D01*
X60227Y534480D01*
X61268D01*
G01X60227D02*
X59602Y533272D01*
G01X58043Y533564D02*
X57752Y533355D01*
X57418Y533272D01*
X57085Y533355D01*
X56793Y533605D01*
X56585Y533980D01*
X56502Y534355D01*
Y534814D01*
X56585Y535189D01*
X56793Y535522D01*
X57043Y535689D01*
X57335Y535772D01*
X57668Y535689D01*
X57918Y535522D01*
X58085Y535272D01*
X58168Y534939D01*
X58085Y534647D01*
X57877Y534355D01*
X57627Y534189D01*
X57335Y534147D01*
X57002Y534230D01*
X56752Y534439D01*
X56502Y534814D01*
G01X55318Y533272D02*
Y535772D01*
X54235Y533689D01*
X53152Y535772D01*
Y533272D01*
G01X51927Y535355D02*
X51677Y535605D01*
X51385Y535730D01*
X51052Y535772D01*
X50635Y535689D01*
X50343Y535480D01*
X50260Y535230D01*
X50302Y534980D01*
X50468Y534772D01*
X51302Y534355D01*
X51677Y534064D01*
X51927Y533647D01*
X52010Y533272D01*
X50260D01*
G01X48035Y535772D02*
X48368Y535689D01*
X48618Y535480D01*
X48785Y535230D01*
X48910Y534897D01*
X48952Y534522D01*
X48910Y534147D01*
X48785Y533814D01*
X48618Y533564D01*
X48368Y533355D01*
X48035Y533272D01*
X47702Y533355D01*
X47452Y533564D01*
X47285Y533814D01*
X47160Y534147D01*
X47118Y534522D01*
X47160Y534897D01*
X47285Y535230D01*
X47452Y535480D01*
X47702Y535689D01*
X48035Y535772D01*
G01X61212Y529564D02*
Y532064D01*
X60171D01*
X59837Y531939D01*
X59629Y531772D01*
X59546Y531439D01*
X59629Y531106D01*
X59879Y530897D01*
X60171Y530772D01*
X61212D01*
G01X60171D02*
X59546Y529564D01*
G01X57987Y529856D02*
X57696Y529647D01*
X57362Y529564D01*
X57029Y529647D01*
X56737Y529897D01*
X56529Y530272D01*
X56446Y530647D01*
Y531106D01*
X56529Y531481D01*
X56737Y531814D01*
X56987Y531981D01*
X57279Y532064D01*
X57612Y531981D01*
X57862Y531814D01*
X58029Y531564D01*
X58112Y531231D01*
X58029Y530939D01*
X57821Y530647D01*
X57571Y530481D01*
X57279Y530439D01*
X56946Y530522D01*
X56696Y530731D01*
X56446Y531106D01*
G01X55262Y529564D02*
Y532064D01*
X54179Y529981D01*
X53096Y532064D01*
Y529564D01*
G01X51871Y531647D02*
X51621Y531897D01*
X51329Y532022D01*
X50996Y532064D01*
X50579Y531981D01*
X50287Y531772D01*
X50204Y531522D01*
X50246Y531272D01*
X50412Y531064D01*
X51246Y530647D01*
X51621Y530356D01*
X51871Y529939D01*
X51954Y529564D01*
X50204D01*
G01X47979D02*
Y532064D01*
X48479Y531564D01*
G01Y529564D02*
X47479D01*
G01X81142Y564767D02*
X81267Y564517D01*
X81350Y564225D01*
Y563892D01*
X81225Y563517D01*
X81017Y563225D01*
X80767Y563017D01*
X80350Y562850D01*
X79975Y562808D01*
X79600Y562892D01*
X79350Y563017D01*
X79100Y563267D01*
X78933Y563558D01*
X78850Y563850D01*
Y564142D01*
X78933Y564433D01*
X79058Y564683D01*
X79225Y564892D01*
G01X79142Y566242D02*
X78933Y566533D01*
X78850Y566867D01*
X78933Y567200D01*
X79183Y567492D01*
X79558Y567700D01*
X79933Y567783D01*
X80392D01*
X80767Y567700D01*
X81100Y567492D01*
X81267Y567242D01*
X81350Y566950D01*
X81267Y566617D01*
X81100Y566367D01*
X80850Y566200D01*
X80517Y566117D01*
X80225Y566200D01*
X79933Y566408D01*
X79767Y566658D01*
X79725Y566950D01*
X79808Y567283D01*
X80017Y567533D01*
X80392Y567783D01*
G01X81350Y569217D02*
X78850D01*
Y570883D01*
G01X79142Y572442D02*
X78933Y572733D01*
X78850Y573067D01*
X78933Y573400D01*
X79183Y573692D01*
X79558Y573900D01*
X79933Y573983D01*
X80392D01*
X80767Y573900D01*
X81100Y573692D01*
X81267Y573442D01*
X81350Y573150D01*
X81267Y572817D01*
X81100Y572567D01*
X80850Y572400D01*
X80517Y572317D01*
X80225Y572400D01*
X79933Y572608D01*
X79767Y572858D01*
X79725Y573150D01*
X79808Y573483D01*
X80017Y573733D01*
X80392Y573983D01*
G01X77464Y561800D02*
Y558009D01*
X64668D01*
Y561800D01*
G01X77464Y574400D02*
Y577962D01*
X64668D01*
Y574400D01*
G01X81272Y541442D02*
X81397Y541192D01*
X81480Y540900D01*
Y540567D01*
X81355Y540192D01*
X81147Y539900D01*
X80897Y539692D01*
X80480Y539525D01*
X80105Y539483D01*
X79730Y539567D01*
X79480Y539692D01*
X79230Y539942D01*
X79063Y540233D01*
X78980Y540525D01*
Y540817D01*
X79063Y541108D01*
X79188Y541358D01*
X79355Y541567D01*
G01X79272Y542917D02*
X79063Y543208D01*
X78980Y543542D01*
X79063Y543875D01*
X79313Y544167D01*
X79688Y544375D01*
X80063Y544458D01*
X80522D01*
X80897Y544375D01*
X81230Y544167D01*
X81397Y543917D01*
X81480Y543625D01*
X81397Y543292D01*
X81230Y543042D01*
X80980Y542875D01*
X80647Y542792D01*
X80355Y542875D01*
X80063Y543083D01*
X79897Y543333D01*
X79855Y543625D01*
X79938Y543958D01*
X80147Y544208D01*
X80522Y544458D01*
G01X81480Y545892D02*
X78980D01*
Y547558D01*
G01Y549825D02*
X81480D01*
X80980Y549325D01*
G01X78980D02*
Y550325D01*
G01X81063Y552133D02*
X81313Y552383D01*
X81438Y552675D01*
X81480Y553008D01*
X81397Y553425D01*
X81188Y553717D01*
X80938Y553800D01*
X80688Y553758D01*
X80480Y553592D01*
X80063Y552758D01*
X79772Y552383D01*
X79355Y552133D01*
X78980Y552050D01*
Y553800D01*
G01X77264Y554200D02*
Y557762D01*
X64468D01*
Y554200D01*
G01X77264Y541600D02*
Y537809D01*
X64468D01*
Y541600D01*
G01X81242Y585467D02*
X81367Y585217D01*
X81450Y584925D01*
Y584592D01*
X81325Y584217D01*
X81117Y583925D01*
X80867Y583717D01*
X80450Y583550D01*
X80075Y583508D01*
X79700Y583592D01*
X79450Y583717D01*
X79200Y583967D01*
X79033Y584258D01*
X78950Y584550D01*
Y584842D01*
X79033Y585133D01*
X79158Y585383D01*
X79325Y585592D01*
G01X79242Y586942D02*
X79033Y587233D01*
X78950Y587567D01*
X79033Y587900D01*
X79283Y588192D01*
X79658Y588400D01*
X80033Y588483D01*
X80492D01*
X80867Y588400D01*
X81200Y588192D01*
X81367Y587942D01*
X81450Y587650D01*
X81367Y587317D01*
X81200Y587067D01*
X80950Y586900D01*
X80617Y586817D01*
X80325Y586900D01*
X80033Y587108D01*
X79867Y587358D01*
X79825Y587650D01*
X79908Y587983D01*
X80117Y588233D01*
X80492Y588483D01*
G01X81450Y589917D02*
X78950D01*
Y591583D01*
G01Y594350D02*
X81450D01*
X79658Y592808D01*
Y594892D01*
G01X77464Y582300D02*
Y578509D01*
X64668D01*
Y582300D01*
G01X83650Y583817D02*
X83400Y584025D01*
X83233Y584275D01*
X83150Y584567D01*
X83233Y584900D01*
X83400Y585150D01*
X83650Y585400D01*
X83983Y585483D01*
X85650D01*
G01X83442Y587042D02*
X83233Y587333D01*
X83150Y587667D01*
X83233Y588000D01*
X83483Y588292D01*
X83858Y588500D01*
X84233Y588583D01*
X84692D01*
X85067Y588500D01*
X85400Y588292D01*
X85567Y588042D01*
X85650Y587750D01*
X85567Y587417D01*
X85400Y587167D01*
X85150Y587000D01*
X84817Y586917D01*
X84525Y587000D01*
X84233Y587208D01*
X84067Y587458D01*
X84025Y587750D01*
X84108Y588083D01*
X84317Y588333D01*
X84692Y588583D01*
G01X85650Y590017D02*
X83150D01*
Y591683D01*
G01Y593950D02*
X85650D01*
X85150Y593450D01*
G01X83150D02*
Y594450D01*
G01X111100Y602474D02*
X86710D01*
Y576884D01*
X111100D01*
G01X83750Y545617D02*
X83500Y545825D01*
X83333Y546075D01*
X83250Y546367D01*
X83333Y546700D01*
X83500Y546950D01*
X83750Y547200D01*
X84083Y547283D01*
X85750D01*
G01X83542Y548842D02*
X83333Y549133D01*
X83250Y549467D01*
X83333Y549800D01*
X83583Y550092D01*
X83958Y550300D01*
X84333Y550383D01*
X84792D01*
X85167Y550300D01*
X85500Y550092D01*
X85667Y549842D01*
X85750Y549550D01*
X85667Y549217D01*
X85500Y548967D01*
X85250Y548800D01*
X84917Y548717D01*
X84625Y548800D01*
X84333Y549008D01*
X84167Y549258D01*
X84125Y549550D01*
X84208Y549883D01*
X84417Y550133D01*
X84792Y550383D01*
G01X85750Y551817D02*
X83250D01*
Y553483D01*
G01X85333Y554958D02*
X85583Y555208D01*
X85708Y555500D01*
X85750Y555833D01*
X85667Y556250D01*
X85458Y556542D01*
X85208Y556625D01*
X84958Y556583D01*
X84750Y556417D01*
X84333Y555583D01*
X84042Y555208D01*
X83625Y554958D01*
X83250Y554875D01*
Y556625D01*
G01X111100Y564674D02*
X86710D01*
Y539084D01*
X111100D01*
G01X116633Y618292D02*
X116883Y618417D01*
X117175Y618500D01*
X117508D01*
X117883Y618375D01*
X118175Y618167D01*
X118383Y617917D01*
X118550Y617500D01*
X118592Y617125D01*
X118508Y616750D01*
X118383Y616500D01*
X118133Y616250D01*
X117842Y616083D01*
X117550Y616000D01*
X117258D01*
X116967Y616083D01*
X116717Y616208D01*
X116508Y616375D01*
G01X115158Y616292D02*
X114867Y616083D01*
X114533Y616000D01*
X114200Y616083D01*
X113908Y616333D01*
X113700Y616708D01*
X113617Y617083D01*
Y617542D01*
X113700Y617917D01*
X113908Y618250D01*
X114158Y618417D01*
X114450Y618500D01*
X114783Y618417D01*
X115033Y618250D01*
X115200Y618000D01*
X115283Y617667D01*
X115200Y617375D01*
X114992Y617083D01*
X114742Y616917D01*
X114450Y616875D01*
X114117Y616958D01*
X113867Y617167D01*
X113617Y617542D01*
G01X112183Y618500D02*
Y616000D01*
X110517D01*
G01X109167Y616500D02*
X108917Y616208D01*
X108583Y616042D01*
X108208Y616000D01*
X107875Y616042D01*
X107542Y616250D01*
X107333Y616500D01*
X107292Y616750D01*
X107375Y617042D01*
X107667Y617250D01*
X107958Y617333D01*
X108333D01*
G01X107958D02*
X107708Y617458D01*
X107500Y617667D01*
X107417Y617917D01*
X107500Y618167D01*
X107708Y618375D01*
X108083Y618500D01*
X108458Y618458D01*
X108833Y618292D01*
G01X60633Y621442D02*
X60883Y621567D01*
X61175Y621650D01*
X61508D01*
X61883Y621525D01*
X62175Y621317D01*
X62383Y621067D01*
X62550Y620650D01*
X62592Y620275D01*
X62508Y619900D01*
X62383Y619650D01*
X62133Y619400D01*
X61842Y619233D01*
X61550Y619150D01*
X61258D01*
X60967Y619233D01*
X60717Y619358D01*
X60508Y619525D01*
G01X59158Y619442D02*
X58867Y619233D01*
X58533Y619150D01*
X58200Y619233D01*
X57908Y619483D01*
X57700Y619858D01*
X57617Y620233D01*
Y620692D01*
X57700Y621067D01*
X57908Y621400D01*
X58158Y621567D01*
X58450Y621650D01*
X58783Y621567D01*
X59033Y621400D01*
X59200Y621150D01*
X59283Y620817D01*
X59200Y620525D01*
X58992Y620233D01*
X58742Y620067D01*
X58450Y620025D01*
X58117Y620108D01*
X57867Y620317D01*
X57617Y620692D01*
G01X56183Y621650D02*
Y619150D01*
X54517D01*
G01X53042Y621233D02*
X52792Y621483D01*
X52500Y621608D01*
X52167Y621650D01*
X51750Y621567D01*
X51458Y621358D01*
X51375Y621108D01*
X51417Y620858D01*
X51583Y620650D01*
X52417Y620233D01*
X52792Y619942D01*
X53042Y619525D01*
X53125Y619150D01*
X51375D01*
G01X77464Y602300D02*
Y598509D01*
X64668D01*
Y602300D01*
G01X77464Y614900D02*
Y618462D01*
X64668D01*
Y614900D01*
G01X77464Y594900D02*
Y598462D01*
X64668D01*
Y594900D01*
G01X159612Y658868D02*
Y661868D01*
X158612D01*
X158212Y661718D01*
X157912Y661518D01*
X157662Y661218D01*
X157462Y660868D01*
X157412Y660368D01*
X157462Y659868D01*
X157662Y659518D01*
X157912Y659218D01*
X158212Y659018D01*
X158612Y658868D01*
X159612D01*
G01X155662Y660218D02*
X154062D01*
X154212Y660568D01*
X154462Y660768D01*
X154812Y660868D01*
X155162Y660818D01*
X155462Y660668D01*
X155662Y660318D01*
X155762Y660018D01*
Y659718D01*
X155662Y659418D01*
X155412Y659118D01*
X155112Y658918D01*
X154762Y658868D01*
X154412Y658968D01*
X154062Y659268D01*
G01X151312Y658868D02*
Y661868D01*
G01X147712D02*
Y658868D01*
G01X148412Y660868D02*
X147012D01*
G01X143212Y658868D02*
Y660868D01*
G01Y660518D02*
X143412Y660718D01*
X143712Y660818D01*
X144062Y660868D01*
X144412Y660768D01*
X144712Y660568D01*
X144912Y660268D01*
X145012Y659868D01*
X144912Y659468D01*
X144712Y659168D01*
X144412Y658968D01*
X144062Y658868D01*
X143712Y658918D01*
X143412Y659068D01*
X143212Y659268D01*
G01X142012Y657868D02*
X139012D01*
G01X137912Y661868D02*
Y658868D01*
X135912D01*
G01X133312D02*
Y661868D01*
X133912Y661268D01*
G01Y658868D02*
X132712D01*
G01X129112D02*
Y661868D01*
X130962Y659718D01*
X128462D01*
G01X127612Y657868D02*
X124612D01*
G01X123612Y659318D02*
X123312Y659068D01*
X122962Y658918D01*
X122512Y658868D01*
X122062Y658968D01*
X121712Y659168D01*
X121462Y659518D01*
X121412Y659918D01*
X121512Y660318D01*
X121762Y660568D01*
X122112Y660768D01*
X122462Y660818D01*
X122812Y660768D01*
X123262Y660568D01*
X123112Y661868D01*
X121762D01*
G01X118912Y660868D02*
Y658868D01*
G01Y661668D02*
X119012Y661718D01*
Y661818D01*
X118912Y661868D01*
X118812Y661818D01*
Y661718D01*
X118912Y661668D01*
G01X116162Y658868D02*
Y660868D01*
G01Y660368D02*
X115962Y660618D01*
X115662Y660818D01*
X115262Y660868D01*
X114912Y660818D01*
X114612Y660618D01*
X114462Y660268D01*
Y658868D01*
G01X110912Y660618D02*
X111262Y660818D01*
X111562Y660868D01*
X111962Y660768D01*
X112262Y660568D01*
X112462Y660218D01*
X112512Y659868D01*
X112462Y659518D01*
X112262Y659218D01*
X111962Y658968D01*
X111562Y658868D01*
X111212Y658968D01*
X110912Y659168D01*
G01X108962Y658868D02*
Y661868D01*
G01Y660418D02*
X108712Y660668D01*
X108462Y660818D01*
X108062Y660868D01*
X107762Y660818D01*
X107412Y660618D01*
X107262Y660318D01*
Y658868D01*
G01X136633Y31692D02*
X136883Y31817D01*
X137175Y31900D01*
X137508D01*
X137883Y31775D01*
X138175Y31567D01*
X138383Y31317D01*
X138550Y30900D01*
X138592Y30525D01*
X138508Y30150D01*
X138383Y29900D01*
X138133Y29650D01*
X137842Y29483D01*
X137550Y29400D01*
X137258D01*
X136967Y29483D01*
X136717Y29608D01*
X136508Y29775D01*
G01X135158Y29692D02*
X134867Y29483D01*
X134533Y29400D01*
X134200Y29483D01*
X133908Y29733D01*
X133700Y30108D01*
X133617Y30483D01*
Y30942D01*
X133700Y31317D01*
X133908Y31650D01*
X134158Y31817D01*
X134450Y31900D01*
X134783Y31817D01*
X135033Y31650D01*
X135200Y31400D01*
X135283Y31067D01*
X135200Y30775D01*
X134992Y30483D01*
X134742Y30317D01*
X134450Y30275D01*
X134117Y30358D01*
X133867Y30567D01*
X133617Y30942D01*
G01X132267Y31900D02*
Y30108D01*
X132100Y29733D01*
X131767Y29483D01*
X131350Y29400D01*
X130933Y29483D01*
X130600Y29733D01*
X130433Y30108D01*
Y31900D01*
G01X128250Y29400D02*
X127958Y29442D01*
X127625Y29567D01*
X127417Y29775D01*
X127333Y30067D01*
X127417Y30358D01*
X127667Y30608D01*
X128042Y30733D01*
X128458D01*
X128708Y30817D01*
X128917Y31025D01*
X129000Y31317D01*
X128875Y31608D01*
X128583Y31817D01*
X128250Y31900D01*
X127917Y31817D01*
X127625Y31608D01*
X127500Y31317D01*
X127583Y31025D01*
X127792Y30817D01*
X128042Y30733D01*
X128458D01*
X128833Y30608D01*
X129083Y30358D01*
X129167Y30067D01*
X129083Y29775D01*
X128875Y29567D01*
X128542Y29442D01*
X128250Y29400D01*
G01X152333Y33192D02*
X152583Y33317D01*
X152875Y33400D01*
X153208D01*
X153583Y33275D01*
X153875Y33067D01*
X154083Y32817D01*
X154250Y32400D01*
X154292Y32025D01*
X154208Y31650D01*
X154083Y31400D01*
X153833Y31150D01*
X153542Y30983D01*
X153250Y30900D01*
X152958D01*
X152667Y30983D01*
X152417Y31108D01*
X152208Y31275D01*
G01X150858Y31192D02*
X150567Y30983D01*
X150233Y30900D01*
X149900Y30983D01*
X149608Y31233D01*
X149400Y31608D01*
X149317Y31983D01*
Y32442D01*
X149400Y32817D01*
X149608Y33150D01*
X149858Y33317D01*
X150150Y33400D01*
X150483Y33317D01*
X150733Y33150D01*
X150900Y32900D01*
X150983Y32567D01*
X150900Y32275D01*
X150692Y31983D01*
X150442Y31817D01*
X150150Y31775D01*
X149817Y31858D01*
X149567Y32067D01*
X149317Y32442D01*
G01X147967Y33400D02*
Y31608D01*
X147800Y31233D01*
X147467Y30983D01*
X147050Y30900D01*
X146633Y30983D01*
X146300Y31233D01*
X146133Y31608D01*
Y33400D01*
G01X144033Y30900D02*
X143950Y31442D01*
X143825Y31900D01*
X143658Y32317D01*
X143450Y32775D01*
X143117Y33400D01*
X144783D01*
G01X127083Y-11708D02*
X127333Y-11583D01*
X127625Y-11500D01*
X127958D01*
X128333Y-11625D01*
X128625Y-11833D01*
X128833Y-12083D01*
X129000Y-12500D01*
X129042Y-12875D01*
X128958Y-13250D01*
X128833Y-13500D01*
X128583Y-13750D01*
X128292Y-13917D01*
X128000Y-14000D01*
X127708D01*
X127417Y-13917D01*
X127167Y-13792D01*
X126958Y-13625D01*
G01X125608Y-13708D02*
X125317Y-13917D01*
X124983Y-14000D01*
X124650Y-13917D01*
X124358Y-13667D01*
X124150Y-13292D01*
X124067Y-12917D01*
Y-12458D01*
X124150Y-12083D01*
X124358Y-11750D01*
X124608Y-11583D01*
X124900Y-11500D01*
X125233Y-11583D01*
X125483Y-11750D01*
X125650Y-12000D01*
X125733Y-12333D01*
X125650Y-12625D01*
X125442Y-12917D01*
X125192Y-13083D01*
X124900Y-13125D01*
X124567Y-13042D01*
X124317Y-12833D01*
X124067Y-12458D01*
G01X122717Y-11500D02*
Y-13292D01*
X122550Y-13667D01*
X122217Y-13917D01*
X121800Y-14000D01*
X121383Y-13917D01*
X121050Y-13667D01*
X120883Y-13292D01*
Y-11500D01*
G01X118700Y-14000D02*
Y-11500D01*
X119200Y-12000D01*
G01Y-14000D02*
X118200D01*
G01X115600Y-11500D02*
X115933Y-11583D01*
X116183Y-11792D01*
X116350Y-12042D01*
X116475Y-12375D01*
X116517Y-12750D01*
X116475Y-13125D01*
X116350Y-13458D01*
X116183Y-13708D01*
X115933Y-13917D01*
X115600Y-14000D01*
X115267Y-13917D01*
X115017Y-13708D01*
X114850Y-13458D01*
X114725Y-13125D01*
X114683Y-12750D01*
X114725Y-12375D01*
X114850Y-12042D01*
X115017Y-11792D01*
X115267Y-11583D01*
X115600Y-11500D01*
G01X118071Y-3570D02*
Y-470D01*
X118531Y-1090D01*
G01Y-3570D02*
X117611D01*
G01X114511D02*
Y-470D01*
X115929Y-2692D01*
X114013D01*
G01X112714Y-3105D02*
X112484Y-3363D01*
X112216Y-3518D01*
X111871Y-3570D01*
X111526Y-3467D01*
X111258Y-3260D01*
X111066Y-2898D01*
X111028Y-2485D01*
X111104Y-2072D01*
X111296Y-1813D01*
X111564Y-1607D01*
X111833Y-1555D01*
X112101Y-1607D01*
X112446Y-1813D01*
X112331Y-470D01*
X111296D01*
G01X172052Y30786D02*
X171844Y30536D01*
X171594Y30369D01*
X171302Y30286D01*
X170969Y30369D01*
X170719Y30536D01*
X170469Y30786D01*
X170386Y31119D01*
Y32786D01*
G01X168827Y30578D02*
X168536Y30369D01*
X168202Y30286D01*
X167869Y30369D01*
X167577Y30619D01*
X167369Y30994D01*
X167286Y31369D01*
Y31828D01*
X167369Y32203D01*
X167577Y32536D01*
X167827Y32703D01*
X168119Y32786D01*
X168452Y32703D01*
X168702Y32536D01*
X168869Y32286D01*
X168952Y31953D01*
X168869Y31661D01*
X168661Y31369D01*
X168411Y31203D01*
X168119Y31161D01*
X167786Y31244D01*
X167536Y31453D01*
X167286Y31828D01*
G01X165936Y32786D02*
Y30994D01*
X165769Y30619D01*
X165436Y30369D01*
X165019Y30286D01*
X164602Y30369D01*
X164269Y30619D01*
X164102Y30994D01*
Y32786D01*
G01X162711Y32369D02*
X162461Y32619D01*
X162169Y32744D01*
X161836Y32786D01*
X161419Y32703D01*
X161127Y32494D01*
X161044Y32244D01*
X161086Y31994D01*
X161252Y31786D01*
X162086Y31369D01*
X162461Y31078D01*
X162711Y30661D01*
X162794Y30286D01*
X161044D01*
G01X137233Y69692D02*
X137483Y69817D01*
X137775Y69900D01*
X138108D01*
X138483Y69775D01*
X138775Y69567D01*
X138983Y69317D01*
X139150Y68900D01*
X139192Y68525D01*
X139108Y68150D01*
X138983Y67900D01*
X138733Y67650D01*
X138442Y67483D01*
X138150Y67400D01*
X137858D01*
X137567Y67483D01*
X137317Y67608D01*
X137108Y67775D01*
G01X135758Y67692D02*
X135467Y67483D01*
X135133Y67400D01*
X134800Y67483D01*
X134508Y67733D01*
X134300Y68108D01*
X134217Y68483D01*
Y68942D01*
X134300Y69317D01*
X134508Y69650D01*
X134758Y69817D01*
X135050Y69900D01*
X135383Y69817D01*
X135633Y69650D01*
X135800Y69400D01*
X135883Y69067D01*
X135800Y68775D01*
X135592Y68483D01*
X135342Y68317D01*
X135050Y68275D01*
X134717Y68358D01*
X134467Y68567D01*
X134217Y68942D01*
G01X131950Y69900D02*
Y67400D01*
G01X132908Y69900D02*
X130992D01*
G01X128850Y67400D02*
X128558Y67442D01*
X128225Y67567D01*
X128017Y67775D01*
X127933Y68067D01*
X128017Y68358D01*
X128267Y68608D01*
X128642Y68733D01*
X129058D01*
X129308Y68817D01*
X129517Y69025D01*
X129600Y69317D01*
X129475Y69608D01*
X129183Y69817D01*
X128850Y69900D01*
X128517Y69817D01*
X128225Y69608D01*
X128100Y69317D01*
X128183Y69025D01*
X128392Y68817D01*
X128642Y68733D01*
X129058D01*
X129433Y68608D01*
X129683Y68358D01*
X129767Y68067D01*
X129683Y67775D01*
X129475Y67567D01*
X129142Y67442D01*
X128850Y67400D01*
G01X153933Y70692D02*
X154183Y70817D01*
X154475Y70900D01*
X154808D01*
X155183Y70775D01*
X155475Y70567D01*
X155683Y70317D01*
X155850Y69900D01*
X155892Y69525D01*
X155808Y69150D01*
X155683Y68900D01*
X155433Y68650D01*
X155142Y68483D01*
X154850Y68400D01*
X154558D01*
X154267Y68483D01*
X154017Y68608D01*
X153808Y68775D01*
G01X152458Y68692D02*
X152167Y68483D01*
X151833Y68400D01*
X151500Y68483D01*
X151208Y68733D01*
X151000Y69108D01*
X150917Y69483D01*
Y69942D01*
X151000Y70317D01*
X151208Y70650D01*
X151458Y70817D01*
X151750Y70900D01*
X152083Y70817D01*
X152333Y70650D01*
X152500Y70400D01*
X152583Y70067D01*
X152500Y69775D01*
X152292Y69483D01*
X152042Y69317D01*
X151750Y69275D01*
X151417Y69358D01*
X151167Y69567D01*
X150917Y69942D01*
G01X148650Y70900D02*
Y68400D01*
G01X149608Y70900D02*
X147692D01*
G01X145633Y68400D02*
X145550Y68942D01*
X145425Y69400D01*
X145258Y69817D01*
X145050Y70275D01*
X144717Y70900D01*
X146383D01*
G01X120850Y34500D02*
Y37600D01*
X121310Y36980D01*
G01Y34500D02*
X120390D01*
G01X117290D02*
Y37600D01*
X118708Y35378D01*
X116792D01*
G01X115493Y34965D02*
X115263Y34707D01*
X114995Y34552D01*
X114650Y34500D01*
X114305Y34603D01*
X114037Y34810D01*
X113845Y35172D01*
X113807Y35585D01*
X113883Y35998D01*
X114075Y36257D01*
X114343Y36463D01*
X114612Y36515D01*
X114880Y36463D01*
X115225Y36257D01*
X115110Y37600D01*
X114075D01*
G01X120850Y72000D02*
Y75100D01*
X121310Y74480D01*
G01Y72000D02*
X120390D01*
G01X117290D02*
Y75100D01*
X118708Y72878D01*
X116792D01*
G01X115493Y72465D02*
X115263Y72207D01*
X114995Y72052D01*
X114650Y72000D01*
X114305Y72103D01*
X114037Y72310D01*
X113845Y72672D01*
X113807Y73085D01*
X113883Y73498D01*
X114075Y73757D01*
X114343Y73963D01*
X114612Y74015D01*
X114880Y73963D01*
X115225Y73757D01*
X115110Y75100D01*
X114075D01*
G01X142358Y150655D02*
X142483Y150405D01*
X142566Y150113D01*
Y149780D01*
X142441Y149405D01*
X142233Y149113D01*
X141983Y148905D01*
X141566Y148738D01*
X141191Y148696D01*
X140816Y148780D01*
X140566Y148905D01*
X140316Y149155D01*
X140149Y149446D01*
X140066Y149738D01*
Y150030D01*
X140149Y150321D01*
X140274Y150571D01*
X140441Y150780D01*
G01X140358Y152130D02*
X140149Y152421D01*
X140066Y152755D01*
X140149Y153088D01*
X140399Y153380D01*
X140774Y153588D01*
X141149Y153671D01*
X141608D01*
X141983Y153588D01*
X142316Y153380D01*
X142483Y153130D01*
X142566Y152838D01*
X142483Y152505D01*
X142316Y152255D01*
X142066Y152088D01*
X141733Y152005D01*
X141441Y152088D01*
X141149Y152296D01*
X140983Y152546D01*
X140941Y152838D01*
X141024Y153171D01*
X141233Y153421D01*
X141608Y153671D01*
G01X142566Y155938D02*
X140066D01*
G01X142566Y154980D02*
Y156896D01*
G01X140566Y158121D02*
X140274Y158371D01*
X140108Y158705D01*
X140066Y159080D01*
X140108Y159413D01*
X140316Y159746D01*
X140566Y159955D01*
X140816Y159996D01*
X141108Y159913D01*
X141316Y159621D01*
X141399Y159330D01*
Y158955D01*
G01Y159330D02*
X141524Y159580D01*
X141733Y159788D01*
X141983Y159871D01*
X142233Y159788D01*
X142441Y159580D01*
X142566Y159205D01*
X142524Y158830D01*
X142358Y158455D01*
G01X147366Y134024D02*
X143575D01*
Y146820D01*
X147366D01*
G01X159966Y134024D02*
X163528D01*
Y146820D01*
X159966D01*
G01X144666Y169388D02*
Y146816D01*
G01X162666Y169388D02*
Y146813D01*
G01X134591Y120767D02*
Y123267D01*
X133550D01*
X133216Y123142D01*
X133008Y122975D01*
X132925Y122642D01*
X133008Y122309D01*
X133258Y122100D01*
X133550Y121975D01*
X134591D01*
G01X133550D02*
X132925Y120767D01*
G01X130658D02*
Y123267D01*
X131158Y122767D01*
G01Y120767D02*
X130158D01*
G01X128350Y122850D02*
X128100Y123100D01*
X127808Y123225D01*
X127475Y123267D01*
X127058Y123184D01*
X126766Y122975D01*
X126683Y122725D01*
X126725Y122475D01*
X126891Y122267D01*
X127725Y121850D01*
X128100Y121559D01*
X128350Y121142D01*
X128433Y120767D01*
X126683D01*
G01X125708Y123267D02*
X125125Y120767D01*
X124458Y123267D01*
X123791Y120767D01*
X123208Y123267D01*
G01X121358Y120767D02*
Y123267D01*
X121858Y122767D01*
G01Y120767D02*
X120858D01*
G01X119175Y121267D02*
X118925Y120975D01*
X118591Y120809D01*
X118216Y120767D01*
X117883Y120809D01*
X117550Y121017D01*
X117341Y121267D01*
X117300Y121517D01*
X117383Y121809D01*
X117675Y122017D01*
X117966Y122100D01*
X118341D01*
G01X117966D02*
X117716Y122225D01*
X117508Y122434D01*
X117425Y122684D01*
X117508Y122934D01*
X117716Y123142D01*
X118091Y123267D01*
X118466Y123225D01*
X118841Y123059D01*
G01X116158Y124310D02*
Y120310D01*
X108758D01*
G01X155457Y212740D02*
Y209640D01*
X153923D01*
G01X152088Y210673D02*
X151092D01*
G01X149257Y212740D02*
Y209640D01*
X147723D01*
G01X146233Y210105D02*
X146003Y209847D01*
X145735Y209692D01*
X145390Y209640D01*
X145045Y209743D01*
X144777Y209950D01*
X144585Y210312D01*
X144547Y210725D01*
X144623Y211138D01*
X144815Y211397D01*
X145083Y211603D01*
X145352Y211655D01*
X145620Y211603D01*
X145965Y211397D01*
X145850Y212740D01*
X144815D01*
G01X123283Y209500D02*
Y212000D01*
X122242D01*
X121908Y211875D01*
X121700Y211708D01*
X121617Y211375D01*
X121700Y211042D01*
X121950Y210833D01*
X122242Y210708D01*
X123283D01*
G01X122242D02*
X121617Y209500D01*
G01X120058Y209792D02*
X119767Y209583D01*
X119433Y209500D01*
X119100Y209583D01*
X118808Y209833D01*
X118600Y210208D01*
X118517Y210583D01*
Y211042D01*
X118600Y211417D01*
X118808Y211750D01*
X119058Y211917D01*
X119350Y212000D01*
X119683Y211917D01*
X119933Y211750D01*
X120100Y211500D01*
X120183Y211167D01*
X120100Y210875D01*
X119892Y210583D01*
X119642Y210417D01*
X119350Y210375D01*
X119017Y210458D01*
X118767Y210667D01*
X118517Y211042D01*
G01X117083Y209500D02*
Y212000D01*
X116042D01*
X115708Y211875D01*
X115500Y211708D01*
X115417Y211375D01*
X115500Y211042D01*
X115750Y210833D01*
X116042Y210708D01*
X117083D01*
G01X116042D02*
X115417Y209500D01*
G01X113942Y211583D02*
X113692Y211833D01*
X113400Y211958D01*
X113067Y212000D01*
X112650Y211917D01*
X112358Y211708D01*
X112275Y211458D01*
X112317Y211208D01*
X112483Y211000D01*
X113317Y210583D01*
X113692Y210292D01*
X113942Y209875D01*
X114025Y209500D01*
X112275D01*
G01X162666Y169388D02*
X159968D01*
G01X144666D02*
X147361D01*
G01X176550Y209177D02*
X176800Y209302D01*
X177092Y209385D01*
X177425D01*
X177800Y209260D01*
X178092Y209052D01*
X178300Y208802D01*
X178467Y208385D01*
X178509Y208010D01*
X178425Y207635D01*
X178300Y207385D01*
X178050Y207135D01*
X177759Y206968D01*
X177467Y206885D01*
X177175D01*
X176884Y206968D01*
X176634Y207093D01*
X176425Y207260D01*
G01X175075Y207177D02*
X174784Y206968D01*
X174450Y206885D01*
X174117Y206968D01*
X173825Y207218D01*
X173617Y207593D01*
X173534Y207968D01*
Y208427D01*
X173617Y208802D01*
X173825Y209135D01*
X174075Y209302D01*
X174367Y209385D01*
X174700Y209302D01*
X174950Y209135D01*
X175117Y208885D01*
X175200Y208552D01*
X175117Y208260D01*
X174909Y207968D01*
X174659Y207802D01*
X174367Y207760D01*
X174034Y207843D01*
X173784Y208052D01*
X173534Y208427D01*
G01X172100Y206885D02*
Y209385D01*
X171059D01*
X170725Y209260D01*
X170517Y209093D01*
X170434Y208760D01*
X170517Y208427D01*
X170767Y208218D01*
X171059Y208093D01*
X172100D01*
G01X171059D02*
X170434Y206885D01*
G01X168875Y207177D02*
X168584Y206968D01*
X168250Y206885D01*
X167917Y206968D01*
X167625Y207218D01*
X167417Y207593D01*
X167334Y207968D01*
Y208427D01*
X167417Y208802D01*
X167625Y209135D01*
X167875Y209302D01*
X168167Y209385D01*
X168500Y209302D01*
X168750Y209135D01*
X168917Y208885D01*
X169000Y208552D01*
X168917Y208260D01*
X168709Y207968D01*
X168459Y207802D01*
X168167Y207760D01*
X167834Y207843D01*
X167584Y208052D01*
X167334Y208427D01*
G01X149000Y215500D02*
Y218195D01*
G01Y215500D02*
X171572D01*
G01X125933Y208292D02*
X126183Y208417D01*
X126475Y208500D01*
X126808D01*
X127183Y208375D01*
X127475Y208167D01*
X127683Y207917D01*
X127850Y207500D01*
X127892Y207125D01*
X127808Y206750D01*
X127683Y206500D01*
X127433Y206250D01*
X127142Y206083D01*
X126850Y206000D01*
X126558D01*
X126267Y206083D01*
X126017Y206208D01*
X125808Y206375D01*
G01X123750Y206000D02*
Y208500D01*
X124250Y208000D01*
G01Y206000D02*
X123250D01*
G01X119817D02*
X121483D01*
Y208500D01*
X119817D01*
G01X120483Y207292D02*
X121483D01*
G01X118342Y207042D02*
X118050Y207333D01*
X117800Y207500D01*
X117467Y207583D01*
X117175Y207500D01*
X116967Y207333D01*
X116800Y207083D01*
X116758Y206792D01*
X116800Y206542D01*
X116967Y206292D01*
X117217Y206083D01*
X117508Y206000D01*
X117842Y206083D01*
X118133Y206333D01*
X118300Y206708D01*
X118342Y207125D01*
X118258Y207667D01*
X118133Y207958D01*
X117925Y208250D01*
X117633Y208458D01*
X117342Y208500D01*
X117050Y208417D01*
X116842Y208208D01*
G01X117983Y230692D02*
X118233Y230817D01*
X118525Y230900D01*
X118858D01*
X119233Y230775D01*
X119525Y230567D01*
X119733Y230317D01*
X119900Y229900D01*
X119942Y229525D01*
X119858Y229150D01*
X119733Y228900D01*
X119483Y228650D01*
X119192Y228483D01*
X118900Y228400D01*
X118608D01*
X118317Y228483D01*
X118067Y228608D01*
X117858Y228775D01*
G01X116508Y228692D02*
X116217Y228483D01*
X115883Y228400D01*
X115550Y228483D01*
X115258Y228733D01*
X115050Y229108D01*
X114967Y229483D01*
Y229942D01*
X115050Y230317D01*
X115258Y230650D01*
X115508Y230817D01*
X115800Y230900D01*
X116133Y230817D01*
X116383Y230650D01*
X116550Y230400D01*
X116633Y230067D01*
X116550Y229775D01*
X116342Y229483D01*
X116092Y229317D01*
X115800Y229275D01*
X115467Y229358D01*
X115217Y229567D01*
X114967Y229942D01*
G01X113533Y228400D02*
Y230900D01*
X112492D01*
X112158Y230775D01*
X111950Y230608D01*
X111867Y230275D01*
X111950Y229942D01*
X112200Y229733D01*
X112492Y229608D01*
X113533D01*
G01X112492D02*
X111867Y228400D01*
G01X109683D02*
X109600Y228942D01*
X109475Y229400D01*
X109308Y229817D01*
X109100Y230275D01*
X108767Y230900D01*
X110433D01*
G01X149000Y279500D02*
Y282195D01*
G01Y279500D02*
X171572D01*
G01X149000Y276500D02*
Y273802D01*
G01Y258500D02*
Y261195D01*
G01Y258500D02*
X171572D01*
G01X149000Y276500D02*
X171575D01*
G01X149000Y255500D02*
Y252802D01*
G01Y237500D02*
Y240195D01*
G01Y237500D02*
X171572D01*
G01X149000Y255500D02*
X171575D01*
G01X149000Y233500D02*
Y230802D01*
G01Y233500D02*
X171575D01*
G01X119847Y332937D02*
X120097Y333062D01*
X120389Y333145D01*
X120722D01*
X121097Y333020D01*
X121389Y332812D01*
X121597Y332562D01*
X121764Y332145D01*
X121806Y331770D01*
X121722Y331395D01*
X121597Y331145D01*
X121347Y330895D01*
X121056Y330728D01*
X120764Y330645D01*
X120472D01*
X120181Y330728D01*
X119931Y330853D01*
X119722Y331020D01*
G01X118372Y330937D02*
X118081Y330728D01*
X117747Y330645D01*
X117414Y330728D01*
X117122Y330978D01*
X116914Y331353D01*
X116831Y331728D01*
Y332187D01*
X116914Y332562D01*
X117122Y332895D01*
X117372Y333062D01*
X117664Y333145D01*
X117997Y333062D01*
X118247Y332895D01*
X118414Y332645D01*
X118497Y332312D01*
X118414Y332020D01*
X118206Y331728D01*
X117956Y331562D01*
X117664Y331520D01*
X117331Y331603D01*
X117081Y331812D01*
X116831Y332187D01*
G01X115397Y330645D02*
Y333145D01*
X114397D01*
X114064Y333020D01*
X113814Y332728D01*
X113731Y332395D01*
X113814Y332062D01*
X114022Y331812D01*
X114397Y331687D01*
X115397D01*
G01X112256Y332728D02*
X112006Y332978D01*
X111714Y333103D01*
X111381Y333145D01*
X110964Y333062D01*
X110672Y332853D01*
X110589Y332603D01*
X110631Y332353D01*
X110797Y332145D01*
X111631Y331728D01*
X112006Y331437D01*
X112256Y331020D01*
X112339Y330645D01*
X110589D01*
G01X121783Y329392D02*
X122033Y329517D01*
X122325Y329600D01*
X122658D01*
X123033Y329475D01*
X123325Y329267D01*
X123533Y329017D01*
X123700Y328600D01*
X123742Y328225D01*
X123658Y327850D01*
X123533Y327600D01*
X123283Y327350D01*
X122992Y327183D01*
X122700Y327100D01*
X122408D01*
X122117Y327183D01*
X121867Y327308D01*
X121658Y327475D01*
G01X120308Y327392D02*
X120017Y327183D01*
X119683Y327100D01*
X119350Y327183D01*
X119058Y327433D01*
X118850Y327808D01*
X118767Y328183D01*
Y328642D01*
X118850Y329017D01*
X119058Y329350D01*
X119308Y329517D01*
X119600Y329600D01*
X119933Y329517D01*
X120183Y329350D01*
X120350Y329100D01*
X120433Y328767D01*
X120350Y328475D01*
X120142Y328183D01*
X119892Y328017D01*
X119600Y327975D01*
X119267Y328058D01*
X119017Y328267D01*
X118767Y328642D01*
G01X117333Y327100D02*
Y329600D01*
X116333D01*
X116000Y329475D01*
X115750Y329183D01*
X115667Y328850D01*
X115750Y328517D01*
X115958Y328267D01*
X116333Y328142D01*
X117333D01*
G01X113400Y327100D02*
Y329600D01*
X113900Y329100D01*
G01Y327100D02*
X112900D01*
G01X121783Y325892D02*
X122033Y326017D01*
X122325Y326100D01*
X122658D01*
X123033Y325975D01*
X123325Y325767D01*
X123533Y325517D01*
X123700Y325100D01*
X123742Y324725D01*
X123658Y324350D01*
X123533Y324100D01*
X123283Y323850D01*
X122992Y323683D01*
X122700Y323600D01*
X122408D01*
X122117Y323683D01*
X121867Y323808D01*
X121658Y323975D01*
G01X120308Y323892D02*
X120017Y323683D01*
X119683Y323600D01*
X119350Y323683D01*
X119058Y323933D01*
X118850Y324308D01*
X118767Y324683D01*
Y325142D01*
X118850Y325517D01*
X119058Y325850D01*
X119308Y326017D01*
X119600Y326100D01*
X119933Y326017D01*
X120183Y325850D01*
X120350Y325600D01*
X120433Y325267D01*
X120350Y324975D01*
X120142Y324683D01*
X119892Y324517D01*
X119600Y324475D01*
X119267Y324558D01*
X119017Y324767D01*
X118767Y325142D01*
G01X117333Y323600D02*
Y326100D01*
X116333D01*
X116000Y325975D01*
X115750Y325683D01*
X115667Y325350D01*
X115750Y325017D01*
X115958Y324767D01*
X116333Y324642D01*
X117333D01*
G01X114192Y325683D02*
X113942Y325933D01*
X113650Y326058D01*
X113317Y326100D01*
X112900Y326017D01*
X112608Y325808D01*
X112525Y325558D01*
X112567Y325308D01*
X112733Y325100D01*
X113567Y324683D01*
X113942Y324392D01*
X114192Y323975D01*
X114275Y323600D01*
X112525D01*
G01X109800D02*
Y326100D01*
X111342Y324308D01*
X109258D01*
G01X123668Y312035D02*
Y314535D01*
X122627D01*
X122293Y314410D01*
X122085Y314243D01*
X122002Y313910D01*
X122085Y313577D01*
X122335Y313368D01*
X122627Y313243D01*
X123668D01*
G01X122627D02*
X122002Y312035D01*
G01X120443Y312327D02*
X120152Y312118D01*
X119818Y312035D01*
X119485Y312118D01*
X119193Y312368D01*
X118985Y312743D01*
X118902Y313118D01*
Y313577D01*
X118985Y313952D01*
X119193Y314285D01*
X119443Y314452D01*
X119735Y314535D01*
X120068Y314452D01*
X120318Y314285D01*
X120485Y314035D01*
X120568Y313702D01*
X120485Y313410D01*
X120277Y313118D01*
X120027Y312952D01*
X119735Y312910D01*
X119402Y312993D01*
X119152Y313202D01*
X118902Y313577D01*
G01X117468Y312035D02*
Y314535D01*
X116468D01*
X116135Y314410D01*
X115885Y314118D01*
X115802Y313785D01*
X115885Y313452D01*
X116093Y313202D01*
X116468Y313077D01*
X117468D01*
G01X113535Y312035D02*
X113243Y312077D01*
X112910Y312202D01*
X112702Y312410D01*
X112618Y312702D01*
X112702Y312993D01*
X112952Y313243D01*
X113327Y313368D01*
X113743D01*
X113993Y313452D01*
X114202Y313660D01*
X114285Y313952D01*
X114160Y314243D01*
X113868Y314452D01*
X113535Y314535D01*
X113202Y314452D01*
X112910Y314243D01*
X112785Y313952D01*
X112868Y313660D01*
X113077Y313452D01*
X113327Y313368D01*
X113743D01*
X114118Y313243D01*
X114368Y312993D01*
X114452Y312702D01*
X114368Y312410D01*
X114160Y312202D01*
X113827Y312077D01*
X113535Y312035D01*
G01X111400Y286667D02*
X113900D01*
Y287708D01*
X113775Y288042D01*
X113608Y288250D01*
X113275Y288333D01*
X112942Y288250D01*
X112733Y288000D01*
X112608Y287708D01*
Y286667D01*
G01Y287708D02*
X111400Y288333D01*
G01X111692Y289892D02*
X111483Y290183D01*
X111400Y290517D01*
X111483Y290850D01*
X111733Y291142D01*
X112108Y291350D01*
X112483Y291433D01*
X112942D01*
X113317Y291350D01*
X113650Y291142D01*
X113817Y290892D01*
X113900Y290600D01*
X113817Y290267D01*
X113650Y290017D01*
X113400Y289850D01*
X113067Y289767D01*
X112775Y289850D01*
X112483Y290058D01*
X112317Y290308D01*
X112275Y290600D01*
X112358Y290933D01*
X112567Y291183D01*
X112942Y291433D01*
G01X111400Y292867D02*
X113900D01*
Y293867D01*
X113775Y294200D01*
X113483Y294450D01*
X113150Y294533D01*
X112817Y294450D01*
X112567Y294242D01*
X112442Y293867D01*
Y292867D01*
G01X113483Y296008D02*
X113733Y296258D01*
X113858Y296550D01*
X113900Y296883D01*
X113817Y297300D01*
X113608Y297592D01*
X113358Y297675D01*
X113108Y297633D01*
X112900Y297467D01*
X112483Y296633D01*
X112192Y296258D01*
X111775Y296008D01*
X111400Y295925D01*
Y297675D01*
G01X113900Y299900D02*
X113817Y299567D01*
X113608Y299317D01*
X113358Y299150D01*
X113025Y299025D01*
X112650Y298983D01*
X112275Y299025D01*
X111942Y299150D01*
X111692Y299317D01*
X111483Y299567D01*
X111400Y299900D01*
X111483Y300233D01*
X111692Y300483D01*
X111942Y300650D01*
X112275Y300775D01*
X112650Y300817D01*
X113025Y300775D01*
X113358Y300650D01*
X113608Y300483D01*
X113817Y300233D01*
X113900Y299900D01*
G01X119742Y281967D02*
X119867Y281717D01*
X119950Y281425D01*
Y281092D01*
X119825Y280717D01*
X119617Y280425D01*
X119367Y280217D01*
X118950Y280050D01*
X118575Y280008D01*
X118200Y280092D01*
X117950Y280217D01*
X117700Y280467D01*
X117533Y280758D01*
X117450Y281050D01*
Y281342D01*
X117533Y281633D01*
X117658Y281883D01*
X117825Y282092D01*
G01X119950Y284150D02*
X117450D01*
G01X119950Y283192D02*
Y285108D01*
G01Y286750D02*
Y287750D01*
G01Y287250D02*
X117450D01*
G01Y286750D02*
Y287750D01*
G01Y290267D02*
X117992Y290350D01*
X118450Y290475D01*
X118867Y290642D01*
X119325Y290850D01*
X119950Y291183D01*
Y289517D01*
G01X149000Y297500D02*
Y294802D01*
G01Y297500D02*
X171575D01*
G01X149000Y319500D02*
Y316802D01*
G01Y301500D02*
Y304195D01*
G01Y301500D02*
X171572D01*
G01X149000Y319500D02*
X171575D01*
G01X149000Y339500D02*
Y336802D01*
G01Y321500D02*
Y324195D01*
G01Y321500D02*
X171572D01*
G01X149000Y339500D02*
X171575D01*
G01X118354Y304926D02*
X118604Y305051D01*
X118896Y305134D01*
X119229D01*
X119604Y305009D01*
X119896Y304801D01*
X120104Y304551D01*
X120271Y304134D01*
X120313Y303759D01*
X120229Y303384D01*
X120104Y303134D01*
X119854Y302884D01*
X119563Y302717D01*
X119271Y302634D01*
X118979D01*
X118688Y302717D01*
X118438Y302842D01*
X118229Y303009D01*
G01X116171Y302634D02*
Y305134D01*
X116671Y304634D01*
G01Y302634D02*
X115671D01*
G01X113988D02*
Y305134D01*
X113154D01*
X112821Y305009D01*
X112571Y304842D01*
X112363Y304592D01*
X112196Y304301D01*
X112154Y303884D01*
X112196Y303467D01*
X112363Y303176D01*
X112571Y302926D01*
X112821Y302759D01*
X113154Y302634D01*
X113988D01*
G01X110888Y303009D02*
X110638Y302801D01*
X110346Y302676D01*
X109971Y302634D01*
X109596Y302717D01*
X109304Y302884D01*
X109096Y303176D01*
X109054Y303509D01*
X109138Y303842D01*
X109346Y304051D01*
X109638Y304217D01*
X109929Y304259D01*
X110221Y304217D01*
X110596Y304051D01*
X110471Y305134D01*
X109346D01*
G01X123763Y337292D02*
X124013Y337417D01*
X124305Y337500D01*
X124638D01*
X125013Y337375D01*
X125305Y337167D01*
X125513Y336917D01*
X125680Y336500D01*
X125722Y336125D01*
X125638Y335750D01*
X125513Y335500D01*
X125263Y335250D01*
X124972Y335083D01*
X124680Y335000D01*
X124388D01*
X124097Y335083D01*
X123847Y335208D01*
X123638Y335375D01*
G01X121580Y335000D02*
Y337500D01*
X122080Y337000D01*
G01Y335000D02*
X121080D01*
G01X117563Y337292D02*
X117813Y337417D01*
X118105Y337500D01*
X118438D01*
X118813Y337375D01*
X119105Y337167D01*
X119313Y336917D01*
X119480Y336500D01*
X119522Y336125D01*
X119438Y335750D01*
X119313Y335500D01*
X119063Y335250D01*
X118772Y335083D01*
X118480Y335000D01*
X118188D01*
X117897Y335083D01*
X117647Y335208D01*
X117438Y335375D01*
G01X115380Y335000D02*
Y337500D01*
X115880Y337000D01*
G01Y335000D02*
X114880D01*
G01X112280D02*
X111988Y335042D01*
X111655Y335167D01*
X111447Y335375D01*
X111363Y335667D01*
X111447Y335958D01*
X111697Y336208D01*
X112072Y336333D01*
X112488D01*
X112738Y336417D01*
X112947Y336625D01*
X113030Y336917D01*
X112905Y337208D01*
X112613Y337417D01*
X112280Y337500D01*
X111947Y337417D01*
X111655Y337208D01*
X111530Y336917D01*
X111613Y336625D01*
X111822Y336417D01*
X112072Y336333D01*
X112488D01*
X112863Y336208D01*
X113113Y335958D01*
X113197Y335667D01*
X113113Y335375D01*
X112905Y335167D01*
X112572Y335042D01*
X112280Y335000D01*
G01X121098Y356774D02*
X121348Y356899D01*
X121640Y356982D01*
X121973D01*
X122348Y356857D01*
X122640Y356649D01*
X122848Y356399D01*
X123015Y355982D01*
X123057Y355607D01*
X122973Y355232D01*
X122848Y354982D01*
X122598Y354732D01*
X122307Y354565D01*
X122015Y354482D01*
X121723D01*
X121432Y354565D01*
X121182Y354690D01*
X120973Y354857D01*
G01X119623Y354774D02*
X119332Y354565D01*
X118998Y354482D01*
X118665Y354565D01*
X118373Y354815D01*
X118165Y355190D01*
X118082Y355565D01*
Y356024D01*
X118165Y356399D01*
X118373Y356732D01*
X118623Y356899D01*
X118915Y356982D01*
X119248Y356899D01*
X119498Y356732D01*
X119665Y356482D01*
X119748Y356149D01*
X119665Y355857D01*
X119457Y355565D01*
X119207Y355399D01*
X118915Y355357D01*
X118582Y355440D01*
X118332Y355649D01*
X118082Y356024D01*
G01X116773Y354482D02*
Y356982D01*
X114857Y354482D01*
Y356982D01*
G01X113507Y356565D02*
X113257Y356815D01*
X112965Y356940D01*
X112632Y356982D01*
X112215Y356899D01*
X111923Y356690D01*
X111840Y356440D01*
X111882Y356190D01*
X112048Y355982D01*
X112882Y355565D01*
X113257Y355274D01*
X113507Y354857D01*
X113590Y354482D01*
X111840D01*
G01X109698D02*
X109615Y355024D01*
X109490Y355482D01*
X109323Y355899D01*
X109115Y356357D01*
X108782Y356982D01*
X110448D01*
G01X122862Y397502D02*
X123112Y397627D01*
X123404Y397710D01*
X123737D01*
X124112Y397585D01*
X124404Y397377D01*
X124612Y397127D01*
X124779Y396710D01*
X124821Y396335D01*
X124737Y395960D01*
X124612Y395710D01*
X124362Y395460D01*
X124071Y395293D01*
X123779Y395210D01*
X123487D01*
X123196Y395293D01*
X122946Y395418D01*
X122737Y395585D01*
G01X121387Y395502D02*
X121096Y395293D01*
X120762Y395210D01*
X120429Y395293D01*
X120137Y395543D01*
X119929Y395918D01*
X119846Y396293D01*
Y396752D01*
X119929Y397127D01*
X120137Y397460D01*
X120387Y397627D01*
X120679Y397710D01*
X121012Y397627D01*
X121262Y397460D01*
X121429Y397210D01*
X121512Y396877D01*
X121429Y396585D01*
X121221Y396293D01*
X120971Y396127D01*
X120679Y396085D01*
X120346Y396168D01*
X120096Y396377D01*
X119846Y396752D01*
G01X118537Y395210D02*
Y397710D01*
X116621Y395210D01*
Y397710D01*
G01X115271Y397293D02*
X115021Y397543D01*
X114729Y397668D01*
X114396Y397710D01*
X113979Y397627D01*
X113687Y397418D01*
X113604Y397168D01*
X113646Y396918D01*
X113812Y396710D01*
X114646Y396293D01*
X115021Y396002D01*
X115271Y395585D01*
X115354Y395210D01*
X113604D01*
G01X111379D02*
Y397710D01*
X111879Y397210D01*
G01Y395210D02*
X110879D01*
G01X122208Y388501D02*
X122458Y388626D01*
X122750Y388709D01*
X123083D01*
X123458Y388584D01*
X123750Y388376D01*
X123958Y388126D01*
X124125Y387709D01*
X124167Y387334D01*
X124083Y386959D01*
X123958Y386709D01*
X123708Y386459D01*
X123417Y386292D01*
X123125Y386209D01*
X122833D01*
X122542Y386292D01*
X122292Y386417D01*
X122083Y386584D01*
G01X120733Y386501D02*
X120442Y386292D01*
X120108Y386209D01*
X119775Y386292D01*
X119483Y386542D01*
X119275Y386917D01*
X119192Y387292D01*
Y387751D01*
X119275Y388126D01*
X119483Y388459D01*
X119733Y388626D01*
X120025Y388709D01*
X120358Y388626D01*
X120608Y388459D01*
X120775Y388209D01*
X120858Y387876D01*
X120775Y387584D01*
X120567Y387292D01*
X120317Y387126D01*
X120025Y387084D01*
X119692Y387167D01*
X119442Y387376D01*
X119192Y387751D01*
G01X117883Y386209D02*
Y388709D01*
X115967Y386209D01*
Y388709D01*
G01X113825Y386209D02*
Y388709D01*
X114325Y388209D01*
G01Y386209D02*
X113325D01*
G01X111642Y386709D02*
X111392Y386417D01*
X111058Y386251D01*
X110683Y386209D01*
X110350Y386251D01*
X110017Y386459D01*
X109808Y386709D01*
X109767Y386959D01*
X109850Y387251D01*
X110142Y387459D01*
X110433Y387542D01*
X110808D01*
G01X110433D02*
X110183Y387667D01*
X109975Y387876D01*
X109892Y388126D01*
X109975Y388376D01*
X110183Y388584D01*
X110558Y388709D01*
X110933Y388667D01*
X111308Y388501D01*
G01X121783Y392192D02*
X122033Y392317D01*
X122325Y392400D01*
X122658D01*
X123033Y392275D01*
X123325Y392067D01*
X123533Y391817D01*
X123700Y391400D01*
X123742Y391025D01*
X123658Y390650D01*
X123533Y390400D01*
X123283Y390150D01*
X122992Y389983D01*
X122700Y389900D01*
X122408D01*
X122117Y389983D01*
X121867Y390108D01*
X121658Y390275D01*
G01X120308Y390192D02*
X120017Y389983D01*
X119683Y389900D01*
X119350Y389983D01*
X119058Y390233D01*
X118850Y390608D01*
X118767Y390983D01*
Y391442D01*
X118850Y391817D01*
X119058Y392150D01*
X119308Y392317D01*
X119600Y392400D01*
X119933Y392317D01*
X120183Y392150D01*
X120350Y391900D01*
X120433Y391567D01*
X120350Y391275D01*
X120142Y390983D01*
X119892Y390817D01*
X119600Y390775D01*
X119267Y390858D01*
X119017Y391067D01*
X118767Y391442D01*
G01X117458Y389900D02*
Y392400D01*
X115542Y389900D01*
Y392400D01*
G01X113400Y389900D02*
Y392400D01*
X113900Y391900D01*
G01Y389900D02*
X112900D01*
G01X111008Y390192D02*
X110717Y389983D01*
X110383Y389900D01*
X110050Y389983D01*
X109758Y390233D01*
X109550Y390608D01*
X109467Y390983D01*
Y391442D01*
X109550Y391817D01*
X109758Y392150D01*
X110008Y392317D01*
X110300Y392400D01*
X110633Y392317D01*
X110883Y392150D01*
X111050Y391900D01*
X111133Y391567D01*
X111050Y391275D01*
X110842Y390983D01*
X110592Y390817D01*
X110300Y390775D01*
X109967Y390858D01*
X109717Y391067D01*
X109467Y391442D01*
G01X124848Y372222D02*
Y374722D01*
X123807D01*
X123473Y374597D01*
X123265Y374430D01*
X123182Y374097D01*
X123265Y373764D01*
X123515Y373555D01*
X123807Y373430D01*
X124848D01*
G01X123807D02*
X123182Y372222D01*
G01X121623Y372514D02*
X121332Y372305D01*
X120998Y372222D01*
X120665Y372305D01*
X120373Y372555D01*
X120165Y372930D01*
X120082Y373305D01*
Y373764D01*
X120165Y374139D01*
X120373Y374472D01*
X120623Y374639D01*
X120915Y374722D01*
X121248Y374639D01*
X121498Y374472D01*
X121665Y374222D01*
X121748Y373889D01*
X121665Y373597D01*
X121457Y373305D01*
X121207Y373139D01*
X120915Y373097D01*
X120582Y373180D01*
X120332Y373389D01*
X120082Y373764D01*
G01X118773Y372222D02*
Y374722D01*
X116857Y372222D01*
Y374722D01*
G01X115632Y372722D02*
X115382Y372430D01*
X115048Y372264D01*
X114673Y372222D01*
X114340Y372264D01*
X114007Y372472D01*
X113798Y372722D01*
X113757Y372972D01*
X113840Y373264D01*
X114132Y373472D01*
X114423Y373555D01*
X114798D01*
G01X114423D02*
X114173Y373680D01*
X113965Y373889D01*
X113882Y374139D01*
X113965Y374389D01*
X114173Y374597D01*
X114548Y374722D01*
X114923Y374680D01*
X115298Y374514D01*
G01X150574Y387363D02*
X173146D01*
G01X150574D02*
Y390058D01*
G01Y405363D02*
Y402665D01*
G01X149000Y361000D02*
Y358302D01*
G01Y343000D02*
Y345695D01*
G01Y343000D02*
X171572D01*
G01X149000Y361000D02*
X171575D01*
G01X150574Y385363D02*
Y382665D01*
G01Y367363D02*
Y370058D01*
G01Y367363D02*
X173146D01*
G01X150574Y385363D02*
X173149D01*
G01X146743Y369882D02*
X146993Y370007D01*
X147285Y370090D01*
X147618D01*
X147993Y369965D01*
X148285Y369757D01*
X148493Y369507D01*
X148660Y369090D01*
X148702Y368715D01*
X148618Y368340D01*
X148493Y368090D01*
X148243Y367840D01*
X147952Y367673D01*
X147660Y367590D01*
X147368D01*
X147077Y367673D01*
X146827Y367798D01*
X146618Y367965D01*
G01X144560Y367590D02*
Y370090D01*
X145060Y369590D01*
G01Y367590D02*
X144060D01*
G01X140543Y369882D02*
X140793Y370007D01*
X141085Y370090D01*
X141418D01*
X141793Y369965D01*
X142085Y369757D01*
X142293Y369507D01*
X142460Y369090D01*
X142502Y368715D01*
X142418Y368340D01*
X142293Y368090D01*
X142043Y367840D01*
X141752Y367673D01*
X141460Y367590D01*
X141168D01*
X140877Y367673D01*
X140627Y367798D01*
X140418Y367965D01*
G01X139277Y368090D02*
X139027Y367798D01*
X138693Y367632D01*
X138318Y367590D01*
X137985Y367632D01*
X137652Y367840D01*
X137443Y368090D01*
X137402Y368340D01*
X137485Y368632D01*
X137777Y368840D01*
X138068Y368923D01*
X138443D01*
G01X138068D02*
X137818Y369048D01*
X137610Y369257D01*
X137527Y369507D01*
X137610Y369757D01*
X137818Y369965D01*
X138193Y370090D01*
X138568Y370048D01*
X138943Y369882D01*
G01X158383Y426400D02*
Y428900D01*
X157342D01*
X157008Y428775D01*
X156800Y428608D01*
X156717Y428275D01*
X156800Y427942D01*
X157050Y427733D01*
X157342Y427608D01*
X158383D01*
G01X157342D02*
X156717Y426400D01*
G01X154450D02*
Y428900D01*
X154950Y428400D01*
G01Y426400D02*
X153950D01*
G01X150433Y428692D02*
X150683Y428817D01*
X150975Y428900D01*
X151308D01*
X151683Y428775D01*
X151975Y428567D01*
X152183Y428317D01*
X152350Y427900D01*
X152392Y427525D01*
X152308Y427150D01*
X152183Y426900D01*
X151933Y426650D01*
X151642Y426483D01*
X151350Y426400D01*
X151058D01*
X150767Y426483D01*
X150517Y426608D01*
X150308Y426775D01*
G01X149167Y426900D02*
X148917Y426608D01*
X148583Y426442D01*
X148208Y426400D01*
X147875Y426442D01*
X147542Y426650D01*
X147333Y426900D01*
X147292Y427150D01*
X147375Y427442D01*
X147667Y427650D01*
X147958Y427733D01*
X148333D01*
G01X147958D02*
X147708Y427858D01*
X147500Y428067D01*
X147417Y428317D01*
X147500Y428567D01*
X147708Y428775D01*
X148083Y428900D01*
X148458Y428858D01*
X148833Y428692D01*
G01X158383Y430400D02*
Y432900D01*
X157342D01*
X157008Y432775D01*
X156800Y432608D01*
X156717Y432275D01*
X156800Y431942D01*
X157050Y431733D01*
X157342Y431608D01*
X158383D01*
G01X157342D02*
X156717Y430400D01*
G01X154450D02*
Y432900D01*
X154950Y432400D01*
G01Y430400D02*
X153950D01*
G01X150433Y432692D02*
X150683Y432817D01*
X150975Y432900D01*
X151308D01*
X151683Y432775D01*
X151975Y432567D01*
X152183Y432317D01*
X152350Y431900D01*
X152392Y431525D01*
X152308Y431150D01*
X152183Y430900D01*
X151933Y430650D01*
X151642Y430483D01*
X151350Y430400D01*
X151058D01*
X150767Y430483D01*
X150517Y430608D01*
X150308Y430775D01*
G01X149042Y432483D02*
X148792Y432733D01*
X148500Y432858D01*
X148167Y432900D01*
X147750Y432817D01*
X147458Y432608D01*
X147375Y432358D01*
X147417Y432108D01*
X147583Y431900D01*
X148417Y431483D01*
X148792Y431192D01*
X149042Y430775D01*
X149125Y430400D01*
X147375D01*
G01X158383Y434400D02*
Y436900D01*
X157342D01*
X157008Y436775D01*
X156800Y436608D01*
X156717Y436275D01*
X156800Y435942D01*
X157050Y435733D01*
X157342Y435608D01*
X158383D01*
G01X157342D02*
X156717Y434400D01*
G01X154450D02*
Y436900D01*
X154950Y436400D01*
G01Y434400D02*
X153950D01*
G01X150433Y436692D02*
X150683Y436817D01*
X150975Y436900D01*
X151308D01*
X151683Y436775D01*
X151975Y436567D01*
X152183Y436317D01*
X152350Y435900D01*
X152392Y435525D01*
X152308Y435150D01*
X152183Y434900D01*
X151933Y434650D01*
X151642Y434483D01*
X151350Y434400D01*
X151058D01*
X150767Y434483D01*
X150517Y434608D01*
X150308Y434775D01*
G01X148250Y434400D02*
Y436900D01*
X148750Y436400D01*
G01Y434400D02*
X147750D01*
G01X172283Y416600D02*
Y419100D01*
X171242D01*
X170908Y418975D01*
X170700Y418808D01*
X170617Y418475D01*
X170700Y418142D01*
X170950Y417933D01*
X171242Y417808D01*
X172283D01*
G01X171242D02*
X170617Y416600D01*
G01X168350D02*
Y419100D01*
X168850Y418600D01*
G01Y416600D02*
X167850D01*
G01X164333Y418892D02*
X164583Y419017D01*
X164875Y419100D01*
X165208D01*
X165583Y418975D01*
X165875Y418767D01*
X166083Y418517D01*
X166250Y418100D01*
X166292Y417725D01*
X166208Y417350D01*
X166083Y417100D01*
X165833Y416850D01*
X165542Y416683D01*
X165250Y416600D01*
X164958D01*
X164667Y416683D01*
X164417Y416808D01*
X164208Y416975D01*
G01X161650Y416600D02*
Y419100D01*
X163192Y417308D01*
X161108D01*
G01X172053Y412570D02*
Y415070D01*
X171012D01*
X170678Y414945D01*
X170470Y414778D01*
X170387Y414445D01*
X170470Y414112D01*
X170720Y413903D01*
X171012Y413778D01*
X172053D01*
G01X171012D02*
X170387Y412570D01*
G01X168120D02*
Y415070D01*
X168620Y414570D01*
G01Y412570D02*
X167620D01*
G01X164103Y414862D02*
X164353Y414987D01*
X164645Y415070D01*
X164978D01*
X165353Y414945D01*
X165645Y414737D01*
X165853Y414487D01*
X166020Y414070D01*
X166062Y413695D01*
X165978Y413320D01*
X165853Y413070D01*
X165603Y412820D01*
X165312Y412653D01*
X165020Y412570D01*
X164728D01*
X164437Y412653D01*
X164187Y412778D01*
X163978Y412945D01*
G01X161920Y412570D02*
Y415070D01*
X162420Y414570D01*
G01Y412570D02*
X161420D01*
G01X159612Y414653D02*
X159362Y414903D01*
X159070Y415028D01*
X158737Y415070D01*
X158320Y414987D01*
X158028Y414778D01*
X157945Y414528D01*
X157987Y414278D01*
X158153Y414070D01*
X158987Y413653D01*
X159362Y413362D01*
X159612Y412945D01*
X159695Y412570D01*
X157945D01*
G01X150574Y405363D02*
X173149D01*
G01X118850Y497501D02*
Y500601D01*
X119310Y499981D01*
G01Y497501D02*
X118390D01*
G01X115290D02*
Y500601D01*
X116708Y498379D01*
X114792D01*
G01X113493Y497966D02*
X113263Y497708D01*
X112995Y497553D01*
X112650Y497501D01*
X112305Y497604D01*
X112037Y497811D01*
X111845Y498173D01*
X111807Y498586D01*
X111883Y498999D01*
X112075Y499258D01*
X112343Y499464D01*
X112612Y499516D01*
X112880Y499464D01*
X113225Y499258D01*
X113110Y500601D01*
X112075D01*
G01X133690Y565362D02*
X136190D01*
Y566403D01*
X136065Y566737D01*
X135898Y566945D01*
X135565Y567028D01*
X135232Y566945D01*
X135023Y566695D01*
X134898Y566403D01*
Y565362D01*
G01Y566403D02*
X133690Y567028D01*
G01X133982Y568587D02*
X133773Y568878D01*
X133690Y569212D01*
X133773Y569545D01*
X134023Y569837D01*
X134398Y570045D01*
X134773Y570128D01*
X135232D01*
X135607Y570045D01*
X135940Y569837D01*
X136107Y569587D01*
X136190Y569295D01*
X136107Y568962D01*
X135940Y568712D01*
X135690Y568545D01*
X135357Y568462D01*
X135065Y568545D01*
X134773Y568753D01*
X134607Y569003D01*
X134565Y569295D01*
X134648Y569628D01*
X134857Y569878D01*
X135232Y570128D01*
G01X136190Y571562D02*
X133690D01*
Y573228D01*
G01Y575495D02*
X133732Y575787D01*
X133857Y576120D01*
X134065Y576328D01*
X134357Y576412D01*
X134648Y576328D01*
X134898Y576078D01*
X135023Y575703D01*
Y575287D01*
X135107Y575037D01*
X135315Y574828D01*
X135607Y574745D01*
X135898Y574870D01*
X136107Y575162D01*
X136190Y575495D01*
X136107Y575828D01*
X135898Y576120D01*
X135607Y576245D01*
X135315Y576162D01*
X135107Y575953D01*
X135023Y575703D01*
Y575287D01*
X134898Y574912D01*
X134648Y574662D01*
X134357Y574578D01*
X134065Y574662D01*
X133857Y574870D01*
X133732Y575203D01*
X133690Y575495D01*
G01X138001Y565317D02*
X140501D01*
Y566358D01*
X140376Y566692D01*
X140209Y566900D01*
X139876Y566983D01*
X139543Y566900D01*
X139334Y566650D01*
X139209Y566358D01*
Y565317D01*
G01Y566358D02*
X138001Y566983D01*
G01X138293Y568542D02*
X138084Y568833D01*
X138001Y569167D01*
X138084Y569500D01*
X138334Y569792D01*
X138709Y570000D01*
X139084Y570083D01*
X139543D01*
X139918Y570000D01*
X140251Y569792D01*
X140418Y569542D01*
X140501Y569250D01*
X140418Y568917D01*
X140251Y568667D01*
X140001Y568500D01*
X139668Y568417D01*
X139376Y568500D01*
X139084Y568708D01*
X138918Y568958D01*
X138876Y569250D01*
X138959Y569583D01*
X139168Y569833D01*
X139543Y570083D01*
G01X140501Y571517D02*
X138001D01*
Y573183D01*
G01Y575367D02*
X138543Y575450D01*
X139001Y575575D01*
X139418Y575742D01*
X139876Y575950D01*
X140501Y576283D01*
Y574617D01*
G01X156533Y531650D02*
Y534150D01*
X155492D01*
X155158Y534025D01*
X154950Y533858D01*
X154867Y533525D01*
X154950Y533192D01*
X155200Y532983D01*
X155492Y532858D01*
X156533D01*
G01X155492D02*
X154867Y531650D01*
G01X153308Y531942D02*
X153017Y531733D01*
X152683Y531650D01*
X152350Y531733D01*
X152058Y531983D01*
X151850Y532358D01*
X151767Y532733D01*
Y533192D01*
X151850Y533567D01*
X152058Y533900D01*
X152308Y534067D01*
X152600Y534150D01*
X152933Y534067D01*
X153183Y533900D01*
X153350Y533650D01*
X153433Y533317D01*
X153350Y533025D01*
X153142Y532733D01*
X152892Y532567D01*
X152600Y532525D01*
X152267Y532608D01*
X152017Y532817D01*
X151767Y533192D01*
G01X150333Y534150D02*
Y531650D01*
X148667D01*
G01X146400D02*
Y534150D01*
X146900Y533650D01*
G01Y531650D02*
X145900D01*
G01X143300D02*
Y534150D01*
X143800Y533650D01*
G01Y531650D02*
X142800D01*
G01X143600Y565317D02*
X146100D01*
Y566358D01*
X145975Y566692D01*
X145808Y566900D01*
X145475Y566983D01*
X145142Y566900D01*
X144933Y566650D01*
X144808Y566358D01*
Y565317D01*
G01Y566358D02*
X143600Y566983D01*
G01X143892Y568542D02*
X143683Y568833D01*
X143600Y569167D01*
X143683Y569500D01*
X143933Y569792D01*
X144308Y570000D01*
X144683Y570083D01*
X145142D01*
X145517Y570000D01*
X145850Y569792D01*
X146017Y569542D01*
X146100Y569250D01*
X146017Y568917D01*
X145850Y568667D01*
X145600Y568500D01*
X145267Y568417D01*
X144975Y568500D01*
X144683Y568708D01*
X144517Y568958D01*
X144475Y569250D01*
X144558Y569583D01*
X144767Y569833D01*
X145142Y570083D01*
G01X146100Y571517D02*
X143600D01*
Y573183D01*
G01X144642Y574658D02*
X144933Y574950D01*
X145100Y575200D01*
X145183Y575533D01*
X145100Y575825D01*
X144933Y576033D01*
X144683Y576200D01*
X144392Y576242D01*
X144142Y576200D01*
X143892Y576033D01*
X143683Y575783D01*
X143600Y575492D01*
X143683Y575158D01*
X143933Y574867D01*
X144308Y574700D01*
X144725Y574658D01*
X145267Y574742D01*
X145558Y574867D01*
X145850Y575075D01*
X146058Y575367D01*
X146100Y575658D01*
X146017Y575950D01*
X145808Y576158D01*
G01X133591Y527562D02*
X136091D01*
Y528603D01*
X135966Y528937D01*
X135799Y529145D01*
X135466Y529228D01*
X135133Y529145D01*
X134924Y528895D01*
X134799Y528603D01*
Y527562D01*
G01Y528603D02*
X133591Y529228D01*
G01X133883Y530787D02*
X133674Y531078D01*
X133591Y531412D01*
X133674Y531745D01*
X133924Y532037D01*
X134299Y532245D01*
X134674Y532328D01*
X135133D01*
X135508Y532245D01*
X135841Y532037D01*
X136008Y531787D01*
X136091Y531495D01*
X136008Y531162D01*
X135841Y530912D01*
X135591Y530745D01*
X135258Y530662D01*
X134966Y530745D01*
X134674Y530953D01*
X134508Y531203D01*
X134466Y531495D01*
X134549Y531828D01*
X134758Y532078D01*
X135133Y532328D01*
G01X133591Y533512D02*
X136091D01*
X134008Y534595D01*
X136091Y535678D01*
X133591D01*
G01X135674Y536903D02*
X135924Y537153D01*
X136049Y537445D01*
X136091Y537778D01*
X136008Y538195D01*
X135799Y538487D01*
X135549Y538570D01*
X135299Y538528D01*
X135091Y538362D01*
X134674Y537528D01*
X134383Y537153D01*
X133966Y536903D01*
X133591Y536820D01*
Y538570D01*
G01X138127Y528283D02*
X140627D01*
Y529324D01*
X140502Y529658D01*
X140335Y529866D01*
X140002Y529949D01*
X139669Y529866D01*
X139460Y529616D01*
X139335Y529324D01*
Y528283D01*
G01Y529324D02*
X138127Y529949D01*
G01X138419Y531508D02*
X138210Y531799D01*
X138127Y532133D01*
X138210Y532466D01*
X138460Y532758D01*
X138835Y532966D01*
X139210Y533049D01*
X139669D01*
X140044Y532966D01*
X140377Y532758D01*
X140544Y532508D01*
X140627Y532216D01*
X140544Y531883D01*
X140377Y531633D01*
X140127Y531466D01*
X139794Y531383D01*
X139502Y531466D01*
X139210Y531674D01*
X139044Y531924D01*
X139002Y532216D01*
X139085Y532549D01*
X139294Y532799D01*
X139669Y533049D01*
G01X138127Y534233D02*
X140627D01*
X138544Y535316D01*
X140627Y536399D01*
X138127D01*
G01Y538416D02*
X140627D01*
X140127Y537916D01*
G01X138127D02*
Y538916D01*
G01X131014Y529312D02*
X131139Y529062D01*
X131222Y528770D01*
Y528437D01*
X131097Y528062D01*
X130889Y527770D01*
X130639Y527562D01*
X130222Y527395D01*
X129847Y527353D01*
X129472Y527437D01*
X129222Y527562D01*
X128972Y527812D01*
X128805Y528103D01*
X128722Y528395D01*
Y528687D01*
X128805Y528978D01*
X128930Y529228D01*
X129097Y529437D01*
G01X129014Y530787D02*
X128805Y531078D01*
X128722Y531412D01*
X128805Y531745D01*
X129055Y532037D01*
X129430Y532245D01*
X129805Y532328D01*
X130264D01*
X130639Y532245D01*
X130972Y532037D01*
X131139Y531787D01*
X131222Y531495D01*
X131139Y531162D01*
X130972Y530912D01*
X130722Y530745D01*
X130389Y530662D01*
X130097Y530745D01*
X129805Y530953D01*
X129639Y531203D01*
X129597Y531495D01*
X129680Y531828D01*
X129889Y532078D01*
X130264Y532328D01*
G01X128722Y533512D02*
X131222D01*
X129139Y534595D01*
X131222Y535678D01*
X128722D01*
G01X130805Y536903D02*
X131055Y537153D01*
X131180Y537445D01*
X131222Y537778D01*
X131139Y538195D01*
X130930Y538487D01*
X130680Y538570D01*
X130430Y538528D01*
X130222Y538362D01*
X129805Y537528D01*
X129514Y537153D01*
X129097Y536903D01*
X128722Y536820D01*
Y538570D01*
G01X132392Y567067D02*
X132517Y566817D01*
X132600Y566525D01*
Y566192D01*
X132475Y565817D01*
X132267Y565525D01*
X132017Y565317D01*
X131600Y565150D01*
X131225Y565108D01*
X130850Y565192D01*
X130600Y565317D01*
X130350Y565567D01*
X130183Y565858D01*
X130100Y566150D01*
Y566442D01*
X130183Y566733D01*
X130308Y566983D01*
X130475Y567192D01*
G01X130392Y568542D02*
X130183Y568833D01*
X130100Y569167D01*
X130183Y569500D01*
X130433Y569792D01*
X130808Y570000D01*
X131183Y570083D01*
X131642D01*
X132017Y570000D01*
X132350Y569792D01*
X132517Y569542D01*
X132600Y569250D01*
X132517Y568917D01*
X132350Y568667D01*
X132100Y568500D01*
X131767Y568417D01*
X131475Y568500D01*
X131183Y568708D01*
X131017Y568958D01*
X130975Y569250D01*
X131058Y569583D01*
X131267Y569833D01*
X131642Y570083D01*
G01X132600Y571517D02*
X130100D01*
Y573183D01*
G01Y575450D02*
X130142Y575742D01*
X130267Y576075D01*
X130475Y576283D01*
X130767Y576367D01*
X131058Y576283D01*
X131308Y576033D01*
X131433Y575658D01*
Y575242D01*
X131517Y574992D01*
X131725Y574783D01*
X132017Y574700D01*
X132308Y574825D01*
X132517Y575117D01*
X132600Y575450D01*
X132517Y575783D01*
X132308Y576075D01*
X132017Y576200D01*
X131725Y576117D01*
X131517Y575908D01*
X131433Y575658D01*
Y575242D01*
X131308Y574867D01*
X131058Y574617D01*
X130767Y574533D01*
X130475Y574617D01*
X130267Y574825D01*
X130142Y575158D01*
X130100Y575450D01*
G01X160017Y529467D02*
X160142Y529217D01*
X160225Y528925D01*
Y528592D01*
X160100Y528217D01*
X159892Y527925D01*
X159642Y527717D01*
X159225Y527550D01*
X158850Y527508D01*
X158475Y527592D01*
X158225Y527717D01*
X157975Y527967D01*
X157808Y528258D01*
X157725Y528550D01*
Y528842D01*
X157808Y529133D01*
X157933Y529383D01*
X158100Y529592D01*
G01X158017Y530942D02*
X157808Y531233D01*
X157725Y531567D01*
X157808Y531900D01*
X158058Y532192D01*
X158433Y532400D01*
X158808Y532483D01*
X159267D01*
X159642Y532400D01*
X159975Y532192D01*
X160142Y531942D01*
X160225Y531650D01*
X160142Y531317D01*
X159975Y531067D01*
X159725Y530900D01*
X159392Y530817D01*
X159100Y530900D01*
X158808Y531108D01*
X158642Y531358D01*
X158600Y531650D01*
X158683Y531983D01*
X158892Y532233D01*
X159267Y532483D01*
G01X157725Y533667D02*
X160225D01*
X158142Y534750D01*
X160225Y535833D01*
X157725D01*
G01Y537850D02*
X160225D01*
X159725Y537350D01*
G01X157725D02*
Y538350D01*
G01X149792Y567180D02*
X149917Y566930D01*
X150000Y566638D01*
Y566305D01*
X149875Y565930D01*
X149667Y565638D01*
X149417Y565430D01*
X149000Y565263D01*
X148625Y565221D01*
X148250Y565305D01*
X148000Y565430D01*
X147750Y565680D01*
X147583Y565971D01*
X147500Y566263D01*
Y566555D01*
X147583Y566846D01*
X147708Y567096D01*
X147875Y567305D01*
G01X147792Y568655D02*
X147583Y568946D01*
X147500Y569280D01*
X147583Y569613D01*
X147833Y569905D01*
X148208Y570113D01*
X148583Y570196D01*
X149042D01*
X149417Y570113D01*
X149750Y569905D01*
X149917Y569655D01*
X150000Y569363D01*
X149917Y569030D01*
X149750Y568780D01*
X149500Y568613D01*
X149167Y568530D01*
X148875Y568613D01*
X148583Y568821D01*
X148417Y569071D01*
X148375Y569363D01*
X148458Y569696D01*
X148667Y569946D01*
X149042Y570196D01*
G01X150000Y571630D02*
X147500D01*
Y573296D01*
G01Y575480D02*
X148042Y575563D01*
X148500Y575688D01*
X148917Y575855D01*
X149375Y576063D01*
X150000Y576396D01*
Y574730D01*
G01X124830Y573380D02*
Y576480D01*
X125290Y575860D01*
G01Y573380D02*
X124370D01*
G01X121270D02*
Y576480D01*
X122688Y574258D01*
X120772D01*
G01X119473Y573845D02*
X119243Y573587D01*
X118975Y573432D01*
X118630Y573380D01*
X118285Y573483D01*
X118017Y573690D01*
X117825Y574052D01*
X117787Y574465D01*
X117863Y574878D01*
X118055Y575137D01*
X118323Y575343D01*
X118592Y575395D01*
X118860Y575343D01*
X119205Y575137D01*
X119090Y576480D01*
X118055D01*
G01X126350Y535001D02*
Y538101D01*
X126810Y537481D01*
G01Y535001D02*
X125890D01*
G01X122790D02*
Y538101D01*
X124208Y535879D01*
X122292D01*
G01X120993Y535466D02*
X120763Y535208D01*
X120495Y535053D01*
X120150Y535001D01*
X119805Y535104D01*
X119537Y535311D01*
X119345Y535673D01*
X119307Y536086D01*
X119383Y536499D01*
X119575Y536758D01*
X119843Y536964D01*
X120112Y537016D01*
X120380Y536964D01*
X120725Y536758D01*
X120610Y538101D01*
X119575D01*
G01X131583Y616000D02*
Y618500D01*
X130542D01*
X130208Y618375D01*
X130000Y618208D01*
X129917Y617875D01*
X130000Y617542D01*
X130250Y617333D01*
X130542Y617208D01*
X131583D01*
G01X130542D02*
X129917Y616000D01*
G01X128358Y616292D02*
X128067Y616083D01*
X127733Y616000D01*
X127400Y616083D01*
X127108Y616333D01*
X126900Y616708D01*
X126817Y617083D01*
Y617542D01*
X126900Y617917D01*
X127108Y618250D01*
X127358Y618417D01*
X127650Y618500D01*
X127983Y618417D01*
X128233Y618250D01*
X128400Y618000D01*
X128483Y617667D01*
X128400Y617375D01*
X128192Y617083D01*
X127942Y616917D01*
X127650Y616875D01*
X127317Y616958D01*
X127067Y617167D01*
X126817Y617542D01*
G01X125383Y618500D02*
Y616000D01*
X123717D01*
G01X122367Y616500D02*
X122117Y616208D01*
X121783Y616042D01*
X121408Y616000D01*
X121075Y616042D01*
X120742Y616250D01*
X120533Y616500D01*
X120492Y616750D01*
X120575Y617042D01*
X120867Y617250D01*
X121158Y617333D01*
X121533D01*
G01X121158D02*
X120908Y617458D01*
X120700Y617667D01*
X120617Y617917D01*
X120700Y618167D01*
X120908Y618375D01*
X121283Y618500D01*
X121658Y618458D01*
X122033Y618292D01*
G01X144783Y616000D02*
Y618500D01*
X143742D01*
X143408Y618375D01*
X143200Y618208D01*
X143117Y617875D01*
X143200Y617542D01*
X143450Y617333D01*
X143742Y617208D01*
X144783D01*
G01X143742D02*
X143117Y616000D01*
G01X141558Y616292D02*
X141267Y616083D01*
X140933Y616000D01*
X140600Y616083D01*
X140308Y616333D01*
X140100Y616708D01*
X140017Y617083D01*
Y617542D01*
X140100Y617917D01*
X140308Y618250D01*
X140558Y618417D01*
X140850Y618500D01*
X141183Y618417D01*
X141433Y618250D01*
X141600Y618000D01*
X141683Y617667D01*
X141600Y617375D01*
X141392Y617083D01*
X141142Y616917D01*
X140850Y616875D01*
X140517Y616958D01*
X140267Y617167D01*
X140017Y617542D01*
G01X138583Y618500D02*
Y616000D01*
X136917D01*
G01X135442Y618083D02*
X135192Y618333D01*
X134900Y618458D01*
X134567Y618500D01*
X134150Y618417D01*
X133858Y618208D01*
X133775Y617958D01*
X133817Y617708D01*
X133983Y617500D01*
X134817Y617083D01*
X135192Y616792D01*
X135442Y616375D01*
X135525Y616000D01*
X133775D01*
G01X157983D02*
Y618500D01*
X156942D01*
X156608Y618375D01*
X156400Y618208D01*
X156317Y617875D01*
X156400Y617542D01*
X156650Y617333D01*
X156942Y617208D01*
X157983D01*
G01X156942D02*
X156317Y616000D01*
G01X154758Y616292D02*
X154467Y616083D01*
X154133Y616000D01*
X153800Y616083D01*
X153508Y616333D01*
X153300Y616708D01*
X153217Y617083D01*
Y617542D01*
X153300Y617917D01*
X153508Y618250D01*
X153758Y618417D01*
X154050Y618500D01*
X154383Y618417D01*
X154633Y618250D01*
X154800Y618000D01*
X154883Y617667D01*
X154800Y617375D01*
X154592Y617083D01*
X154342Y616917D01*
X154050Y616875D01*
X153717Y616958D01*
X153467Y617167D01*
X153217Y617542D01*
G01X151783Y618500D02*
Y616000D01*
X150117D01*
G01X147850D02*
Y618500D01*
X148350Y618000D01*
G01Y616000D02*
X147350D01*
G01X169433Y618292D02*
X169683Y618417D01*
X169975Y618500D01*
X170308D01*
X170683Y618375D01*
X170975Y618167D01*
X171183Y617917D01*
X171350Y617500D01*
X171392Y617125D01*
X171308Y616750D01*
X171183Y616500D01*
X170933Y616250D01*
X170642Y616083D01*
X170350Y616000D01*
X170058D01*
X169767Y616083D01*
X169517Y616208D01*
X169308Y616375D01*
G01X167958Y616292D02*
X167667Y616083D01*
X167333Y616000D01*
X167000Y616083D01*
X166708Y616333D01*
X166500Y616708D01*
X166417Y617083D01*
Y617542D01*
X166500Y617917D01*
X166708Y618250D01*
X166958Y618417D01*
X167250Y618500D01*
X167583Y618417D01*
X167833Y618250D01*
X168000Y618000D01*
X168083Y617667D01*
X168000Y617375D01*
X167792Y617083D01*
X167542Y616917D01*
X167250Y616875D01*
X166917Y616958D01*
X166667Y617167D01*
X166417Y617542D01*
G01X164983Y618500D02*
Y616000D01*
X163317D01*
G01X161050D02*
Y618500D01*
X161550Y618000D01*
G01Y616000D02*
X160550D01*
G01X306400Y-55400D02*
Y-58400D01*
X304400D01*
G01X301800D02*
Y-55400D01*
X302400Y-56000D01*
G01Y-58400D02*
X301200D01*
G01X297600D02*
Y-55400D01*
X299450Y-57550D01*
X296950D01*
G01X292000Y-55400D02*
Y-58400D01*
X290000D01*
G01X287400D02*
Y-55400D01*
X288000Y-56000D01*
G01Y-58400D02*
X286800D01*
G01X284750Y-55900D02*
X284450Y-55600D01*
X284100Y-55450D01*
X283700Y-55400D01*
X283200Y-55500D01*
X282850Y-55750D01*
X282750Y-56050D01*
X282800Y-56350D01*
X283000Y-56600D01*
X284000Y-57100D01*
X284450Y-57450D01*
X284750Y-57950D01*
X284850Y-58400D01*
X282750D01*
G01X277600Y-55400D02*
Y-58400D01*
X275600D01*
G01X273000D02*
Y-55400D01*
X273600Y-56000D01*
G01Y-58400D02*
X272400D01*
G01X269400Y-55400D02*
X269800Y-55500D01*
X270100Y-55750D01*
X270300Y-56050D01*
X270450Y-56450D01*
X270500Y-56900D01*
X270450Y-57350D01*
X270300Y-57750D01*
X270100Y-58050D01*
X269800Y-58300D01*
X269400Y-58400D01*
X269000Y-58300D01*
X268700Y-58050D01*
X268500Y-57750D01*
X268350Y-57350D01*
X268300Y-56900D01*
X268350Y-56450D01*
X268500Y-56050D01*
X268700Y-55750D01*
X269000Y-55500D01*
X269400Y-55400D01*
G01X263200D02*
Y-58400D01*
X261200D01*
G01X259700Y-57950D02*
X259400Y-58200D01*
X259050Y-58350D01*
X258600Y-58400D01*
X258150Y-58300D01*
X257800Y-58100D01*
X257550Y-57750D01*
X257500Y-57350D01*
X257600Y-56950D01*
X257850Y-56700D01*
X258200Y-56500D01*
X258550Y-56450D01*
X258900Y-56500D01*
X259350Y-56700D01*
X259200Y-55400D01*
X257850D01*
G01X252400D02*
Y-58400D01*
X250400D01*
G01X248900Y-57800D02*
X248600Y-58150D01*
X248200Y-58350D01*
X247750Y-58400D01*
X247350Y-58350D01*
X246950Y-58100D01*
X246700Y-57800D01*
X246650Y-57500D01*
X246750Y-57150D01*
X247100Y-56900D01*
X247450Y-56800D01*
X247900D01*
G01X247450D02*
X247150Y-56650D01*
X246900Y-56400D01*
X246800Y-56100D01*
X246900Y-55800D01*
X247150Y-55550D01*
X247600Y-55400D01*
X248050Y-55450D01*
X248500Y-55650D01*
G01X241600Y-55400D02*
Y-58400D01*
X239600D01*
G01X237000D02*
Y-55400D01*
X237600Y-56000D01*
G01Y-58400D02*
X236400D01*
G01X234900Y-59400D02*
X231900D01*
G01X230900Y-57950D02*
X230600Y-58200D01*
X230250Y-58350D01*
X229800Y-58400D01*
X229350Y-58300D01*
X229000Y-58100D01*
X228750Y-57750D01*
X228700Y-57350D01*
X228800Y-56950D01*
X229050Y-56700D01*
X229400Y-56500D01*
X229750Y-56450D01*
X230100Y-56500D01*
X230550Y-56700D01*
X230400Y-55400D01*
X229050D01*
G01X226200D02*
X226600Y-55500D01*
X226900Y-55750D01*
X227100Y-56050D01*
X227250Y-56450D01*
X227300Y-56900D01*
X227250Y-57350D01*
X227100Y-57750D01*
X226900Y-58050D01*
X226600Y-58300D01*
X226200Y-58400D01*
X225800Y-58300D01*
X225500Y-58050D01*
X225300Y-57750D01*
X225150Y-57350D01*
X225100Y-56900D01*
X225150Y-56450D01*
X225300Y-56050D01*
X225500Y-55750D01*
X225800Y-55500D01*
X226200Y-55400D01*
G01X222600Y-58400D02*
X223000Y-58350D01*
X223350Y-58150D01*
X223650Y-57850D01*
X223850Y-57500D01*
X223950Y-57100D01*
Y-56700D01*
X223850Y-56300D01*
X223650Y-55950D01*
X223350Y-55650D01*
X223000Y-55450D01*
X222600Y-55400D01*
X222200Y-55450D01*
X221850Y-55650D01*
X221550Y-55950D01*
X221350Y-56300D01*
X221250Y-56700D01*
Y-57100D01*
X221350Y-57500D01*
X221550Y-57850D01*
X221850Y-58150D01*
X222200Y-58350D01*
X222600Y-58400D01*
G01X219850D02*
Y-55400D01*
G01Y-56850D02*
X219600Y-56600D01*
X219350Y-56450D01*
X218950Y-56400D01*
X218650Y-56450D01*
X218300Y-56650D01*
X218150Y-56950D01*
Y-58400D01*
G01X216900D02*
Y-56400D01*
G01Y-56950D02*
X216750Y-56700D01*
X216500Y-56500D01*
X216150Y-56400D01*
X215800Y-56500D01*
X215550Y-56700D01*
X215400Y-56950D01*
Y-58400D01*
G01Y-56950D02*
X215250Y-56700D01*
X215000Y-56500D01*
X214650Y-56400D01*
X214300Y-56500D01*
X214050Y-56700D01*
X213900Y-57000D01*
Y-58400D01*
G01X213300Y-59400D02*
X210300D01*
G01X209250Y-58000D02*
X208850Y-58250D01*
X208400Y-58400D01*
X208000D01*
X207600Y-58250D01*
X207300Y-58000D01*
X207150Y-57650D01*
X207250Y-57300D01*
X207500Y-57000D01*
X207950Y-56800D01*
X208550Y-56700D01*
X208900Y-56500D01*
X209050Y-56150D01*
X208950Y-55800D01*
X208700Y-55550D01*
X208350Y-55400D01*
X208000D01*
X207650Y-55500D01*
X207350Y-55750D01*
G01X306800Y-36300D02*
Y-39300D01*
X304800D01*
G01X302200D02*
Y-36300D01*
X302800Y-36900D01*
G01Y-39300D02*
X301600D01*
G01X298000D02*
Y-36300D01*
X299850Y-38450D01*
X297350D01*
G01X292400Y-36300D02*
Y-39300D01*
X290400D01*
G01X287800D02*
Y-36300D01*
X288400Y-36900D01*
G01Y-39300D02*
X287200D01*
G01X285150Y-36800D02*
X284850Y-36500D01*
X284500Y-36350D01*
X284100Y-36300D01*
X283600Y-36400D01*
X283250Y-36650D01*
X283150Y-36950D01*
X283200Y-37250D01*
X283400Y-37500D01*
X284400Y-38000D01*
X284850Y-38350D01*
X285150Y-38850D01*
X285250Y-39300D01*
X283150D01*
G01X278000Y-36300D02*
Y-39300D01*
X276000D01*
G01X273400D02*
Y-36300D01*
X274000Y-36900D01*
G01Y-39300D02*
X272800D01*
G01X269800Y-36300D02*
X270200Y-36400D01*
X270500Y-36650D01*
X270700Y-36950D01*
X270850Y-37350D01*
X270900Y-37800D01*
X270850Y-38250D01*
X270700Y-38650D01*
X270500Y-38950D01*
X270200Y-39200D01*
X269800Y-39300D01*
X269400Y-39200D01*
X269100Y-38950D01*
X268900Y-38650D01*
X268750Y-38250D01*
X268700Y-37800D01*
X268750Y-37350D01*
X268900Y-36950D01*
X269100Y-36650D01*
X269400Y-36400D01*
X269800Y-36300D01*
G01X263600D02*
Y-39300D01*
X261600D01*
G01X260100Y-38850D02*
X259800Y-39100D01*
X259450Y-39250D01*
X259000Y-39300D01*
X258550Y-39200D01*
X258200Y-39000D01*
X257950Y-38650D01*
X257900Y-38250D01*
X258000Y-37850D01*
X258250Y-37600D01*
X258600Y-37400D01*
X258950Y-37350D01*
X259300Y-37400D01*
X259750Y-37600D01*
X259600Y-36300D01*
X258250D01*
G01X252800D02*
Y-39300D01*
X250800D01*
G01X249300Y-38700D02*
X249000Y-39050D01*
X248600Y-39250D01*
X248150Y-39300D01*
X247750Y-39250D01*
X247350Y-39000D01*
X247100Y-38700D01*
X247050Y-38400D01*
X247150Y-38050D01*
X247500Y-37800D01*
X247850Y-37700D01*
X248300D01*
G01X247850D02*
X247550Y-37550D01*
X247300Y-37300D01*
X247200Y-37000D01*
X247300Y-36700D01*
X247550Y-36450D01*
X248000Y-36300D01*
X248450Y-36350D01*
X248900Y-36550D01*
G01X242000Y-36300D02*
Y-39300D01*
X240000D01*
G01X237400D02*
Y-36300D01*
X238000Y-36900D01*
G01Y-39300D02*
X236800D01*
G01X235300Y-40300D02*
X232300D01*
G01X229600Y-39300D02*
Y-36300D01*
X231450Y-38450D01*
X228950D01*
G01X226600Y-36300D02*
X227000Y-36400D01*
X227300Y-36650D01*
X227500Y-36950D01*
X227650Y-37350D01*
X227700Y-37800D01*
X227650Y-38250D01*
X227500Y-38650D01*
X227300Y-38950D01*
X227000Y-39200D01*
X226600Y-39300D01*
X226200Y-39200D01*
X225900Y-38950D01*
X225700Y-38650D01*
X225550Y-38250D01*
X225500Y-37800D01*
X225550Y-37350D01*
X225700Y-36950D01*
X225900Y-36650D01*
X226200Y-36400D01*
X226600Y-36300D01*
G01X223000Y-39300D02*
X223400Y-39250D01*
X223750Y-39050D01*
X224050Y-38750D01*
X224250Y-38400D01*
X224350Y-38000D01*
Y-37600D01*
X224250Y-37200D01*
X224050Y-36850D01*
X223750Y-36550D01*
X223400Y-36350D01*
X223000Y-36300D01*
X222600Y-36350D01*
X222250Y-36550D01*
X221950Y-36850D01*
X221750Y-37200D01*
X221650Y-37600D01*
Y-38000D01*
X221750Y-38400D01*
X221950Y-38750D01*
X222250Y-39050D01*
X222600Y-39250D01*
X223000Y-39300D01*
G01X220250D02*
Y-36300D01*
G01Y-37750D02*
X220000Y-37500D01*
X219750Y-37350D01*
X219350Y-37300D01*
X219050Y-37350D01*
X218700Y-37550D01*
X218550Y-37850D01*
Y-39300D01*
G01X217300D02*
Y-37300D01*
G01Y-37850D02*
X217150Y-37600D01*
X216900Y-37400D01*
X216550Y-37300D01*
X216200Y-37400D01*
X215950Y-37600D01*
X215800Y-37850D01*
Y-39300D01*
G01Y-37850D02*
X215650Y-37600D01*
X215400Y-37400D01*
X215050Y-37300D01*
X214700Y-37400D01*
X214450Y-37600D01*
X214300Y-37900D01*
Y-39300D01*
G01X213700Y-40300D02*
X210700D01*
G01X209650Y-38900D02*
X209250Y-39150D01*
X208800Y-39300D01*
X208400D01*
X208000Y-39150D01*
X207700Y-38900D01*
X207550Y-38550D01*
X207650Y-38200D01*
X207900Y-37900D01*
X208350Y-37700D01*
X208950Y-37600D01*
X209300Y-37400D01*
X209450Y-37050D01*
X209350Y-36700D01*
X209100Y-36450D01*
X208750Y-36300D01*
X208400D01*
X208050Y-36400D01*
X207750Y-36650D01*
G01X320000Y153300D02*
X206033D01*
Y127100D01*
X240030D01*
G01X237430Y136537D02*
X237680Y136662D01*
X237972Y136745D01*
X238305D01*
X238680Y136620D01*
X238972Y136412D01*
X239180Y136162D01*
X239347Y135745D01*
X239389Y135370D01*
X239305Y134995D01*
X239180Y134745D01*
X238930Y134495D01*
X238639Y134328D01*
X238347Y134245D01*
X238055D01*
X237764Y134328D01*
X237514Y134453D01*
X237305Y134620D01*
G01X236164D02*
X235914Y134412D01*
X235622Y134287D01*
X235247Y134245D01*
X234872Y134328D01*
X234580Y134495D01*
X234372Y134787D01*
X234330Y135120D01*
X234414Y135453D01*
X234622Y135662D01*
X234914Y135828D01*
X235205Y135870D01*
X235497Y135828D01*
X235872Y135662D01*
X235747Y136745D01*
X234622D01*
G01X231897Y135495D02*
X231064D01*
Y134745D01*
X231314Y134495D01*
X231605Y134328D01*
X232022Y134245D01*
X232439Y134328D01*
X232730Y134495D01*
X232980Y134745D01*
X233147Y135037D01*
X233230Y135370D01*
Y135662D01*
X233147Y135912D01*
X232980Y136203D01*
X232730Y136453D01*
X232480Y136620D01*
X232147Y136745D01*
X231855D01*
X231522Y136662D01*
X231272Y136495D01*
G01X229047Y134245D02*
X228755Y134287D01*
X228422Y134412D01*
X228214Y134620D01*
X228130Y134912D01*
X228214Y135203D01*
X228464Y135453D01*
X228839Y135578D01*
X229255D01*
X229505Y135662D01*
X229714Y135870D01*
X229797Y136162D01*
X229672Y136453D01*
X229380Y136662D01*
X229047Y136745D01*
X228714Y136662D01*
X228422Y136453D01*
X228297Y136162D01*
X228380Y135870D01*
X228589Y135662D01*
X228839Y135578D01*
X229255D01*
X229630Y135453D01*
X229880Y135203D01*
X229964Y134912D01*
X229880Y134620D01*
X229672Y134412D01*
X229339Y134287D01*
X229047Y134245D01*
G01X225947D02*
X225655Y134287D01*
X225322Y134412D01*
X225114Y134620D01*
X225030Y134912D01*
X225114Y135203D01*
X225364Y135453D01*
X225739Y135578D01*
X226155D01*
X226405Y135662D01*
X226614Y135870D01*
X226697Y136162D01*
X226572Y136453D01*
X226280Y136662D01*
X225947Y136745D01*
X225614Y136662D01*
X225322Y136453D01*
X225197Y136162D01*
X225280Y135870D01*
X225489Y135662D01*
X225739Y135578D01*
X226155D01*
X226530Y135453D01*
X226780Y135203D01*
X226864Y134912D01*
X226780Y134620D01*
X226572Y134412D01*
X226239Y134287D01*
X225947Y134245D01*
G01X220734Y136537D02*
X220984Y136662D01*
X221276Y136745D01*
X221609D01*
X221984Y136620D01*
X222276Y136412D01*
X222484Y136162D01*
X222651Y135745D01*
X222693Y135370D01*
X222609Y134995D01*
X222484Y134745D01*
X222234Y134495D01*
X221943Y134328D01*
X221651Y134245D01*
X221359D01*
X221068Y134328D01*
X220818Y134453D01*
X220609Y134620D01*
G01X219468D02*
X219218Y134412D01*
X218926Y134287D01*
X218551Y134245D01*
X218176Y134328D01*
X217884Y134495D01*
X217676Y134787D01*
X217634Y135120D01*
X217718Y135453D01*
X217926Y135662D01*
X218218Y135828D01*
X218509Y135870D01*
X218801Y135828D01*
X219176Y135662D01*
X219051Y136745D01*
X217926D01*
G01X215201Y135495D02*
X214368D01*
Y134745D01*
X214618Y134495D01*
X214909Y134328D01*
X215326Y134245D01*
X215743Y134328D01*
X216034Y134495D01*
X216284Y134745D01*
X216451Y135037D01*
X216534Y135370D01*
Y135662D01*
X216451Y135912D01*
X216284Y136203D01*
X216034Y136453D01*
X215784Y136620D01*
X215451Y136745D01*
X215159D01*
X214826Y136662D01*
X214576Y136495D01*
G01X212351Y134245D02*
X212059Y134287D01*
X211726Y134412D01*
X211518Y134620D01*
X211434Y134912D01*
X211518Y135203D01*
X211768Y135453D01*
X212143Y135578D01*
X212559D01*
X212809Y135662D01*
X213018Y135870D01*
X213101Y136162D01*
X212976Y136453D01*
X212684Y136662D01*
X212351Y136745D01*
X212018Y136662D01*
X211726Y136453D01*
X211601Y136162D01*
X211684Y135870D01*
X211893Y135662D01*
X212143Y135578D01*
X212559D01*
X212934Y135453D01*
X213184Y135203D01*
X213268Y134912D01*
X213184Y134620D01*
X212976Y134412D01*
X212643Y134287D01*
X212351Y134245D01*
G01X209334D02*
X209251Y134787D01*
X209126Y135245D01*
X208959Y135662D01*
X208751Y136120D01*
X208418Y136745D01*
X210084D01*
G01X220734Y144537D02*
X220984Y144662D01*
X221276Y144745D01*
X221609D01*
X221984Y144620D01*
X222276Y144412D01*
X222484Y144162D01*
X222651Y143745D01*
X222693Y143370D01*
X222609Y142995D01*
X222484Y142745D01*
X222234Y142495D01*
X221943Y142328D01*
X221651Y142245D01*
X221359D01*
X221068Y142328D01*
X220818Y142453D01*
X220609Y142620D01*
G01X219468D02*
X219218Y142412D01*
X218926Y142287D01*
X218551Y142245D01*
X218176Y142328D01*
X217884Y142495D01*
X217676Y142787D01*
X217634Y143120D01*
X217718Y143453D01*
X217926Y143662D01*
X218218Y143828D01*
X218509Y143870D01*
X218801Y143828D01*
X219176Y143662D01*
X219051Y144745D01*
X217926D01*
G01X215201Y143495D02*
X214368D01*
Y142745D01*
X214618Y142495D01*
X214909Y142328D01*
X215326Y142245D01*
X215743Y142328D01*
X216034Y142495D01*
X216284Y142745D01*
X216451Y143037D01*
X216534Y143370D01*
Y143662D01*
X216451Y143912D01*
X216284Y144203D01*
X216034Y144453D01*
X215784Y144620D01*
X215451Y144745D01*
X215159D01*
X214826Y144662D01*
X214576Y144495D01*
G01X212434Y142245D02*
X212351Y142787D01*
X212226Y143245D01*
X212059Y143662D01*
X211851Y144120D01*
X211518Y144745D01*
X213184D01*
G01X209959Y142537D02*
X209668Y142328D01*
X209334Y142245D01*
X209001Y142328D01*
X208709Y142578D01*
X208501Y142953D01*
X208418Y143328D01*
Y143787D01*
X208501Y144162D01*
X208709Y144495D01*
X208959Y144662D01*
X209251Y144745D01*
X209584Y144662D01*
X209834Y144495D01*
X210001Y144245D01*
X210084Y143912D01*
X210001Y143620D01*
X209793Y143328D01*
X209543Y143162D01*
X209251Y143120D01*
X208918Y143203D01*
X208668Y143412D01*
X208418Y143787D01*
G01X237430Y144537D02*
X237680Y144662D01*
X237972Y144745D01*
X238305D01*
X238680Y144620D01*
X238972Y144412D01*
X239180Y144162D01*
X239347Y143745D01*
X239389Y143370D01*
X239305Y142995D01*
X239180Y142745D01*
X238930Y142495D01*
X238639Y142328D01*
X238347Y142245D01*
X238055D01*
X237764Y142328D01*
X237514Y142453D01*
X237305Y142620D01*
G01X236164D02*
X235914Y142412D01*
X235622Y142287D01*
X235247Y142245D01*
X234872Y142328D01*
X234580Y142495D01*
X234372Y142787D01*
X234330Y143120D01*
X234414Y143453D01*
X234622Y143662D01*
X234914Y143828D01*
X235205Y143870D01*
X235497Y143828D01*
X235872Y143662D01*
X235747Y144745D01*
X234622D01*
G01X231897Y143495D02*
X231064D01*
Y142745D01*
X231314Y142495D01*
X231605Y142328D01*
X232022Y142245D01*
X232439Y142328D01*
X232730Y142495D01*
X232980Y142745D01*
X233147Y143037D01*
X233230Y143370D01*
Y143662D01*
X233147Y143912D01*
X232980Y144203D01*
X232730Y144453D01*
X232480Y144620D01*
X232147Y144745D01*
X231855D01*
X231522Y144662D01*
X231272Y144495D01*
G01X229047Y142245D02*
X228755Y142287D01*
X228422Y142412D01*
X228214Y142620D01*
X228130Y142912D01*
X228214Y143203D01*
X228464Y143453D01*
X228839Y143578D01*
X229255D01*
X229505Y143662D01*
X229714Y143870D01*
X229797Y144162D01*
X229672Y144453D01*
X229380Y144662D01*
X229047Y144745D01*
X228714Y144662D01*
X228422Y144453D01*
X228297Y144162D01*
X228380Y143870D01*
X228589Y143662D01*
X228839Y143578D01*
X229255D01*
X229630Y143453D01*
X229880Y143203D01*
X229964Y142912D01*
X229880Y142620D01*
X229672Y142412D01*
X229339Y142287D01*
X229047Y142245D01*
G01X225947Y144745D02*
X226280Y144662D01*
X226530Y144453D01*
X226697Y144203D01*
X226822Y143870D01*
X226864Y143495D01*
X226822Y143120D01*
X226697Y142787D01*
X226530Y142537D01*
X226280Y142328D01*
X225947Y142245D01*
X225614Y142328D01*
X225364Y142537D01*
X225197Y142787D01*
X225072Y143120D01*
X225030Y143495D01*
X225072Y143870D01*
X225197Y144203D01*
X225364Y144453D01*
X225614Y144662D01*
X225947Y144745D01*
G01X220734Y140537D02*
X220984Y140662D01*
X221276Y140745D01*
X221609D01*
X221984Y140620D01*
X222276Y140412D01*
X222484Y140162D01*
X222651Y139745D01*
X222693Y139370D01*
X222609Y138995D01*
X222484Y138745D01*
X222234Y138495D01*
X221943Y138328D01*
X221651Y138245D01*
X221359D01*
X221068Y138328D01*
X220818Y138453D01*
X220609Y138620D01*
G01X218551Y138245D02*
X218259Y138287D01*
X217926Y138412D01*
X217718Y138620D01*
X217634Y138912D01*
X217718Y139203D01*
X217968Y139453D01*
X218343Y139578D01*
X218759D01*
X219009Y139662D01*
X219218Y139870D01*
X219301Y140162D01*
X219176Y140453D01*
X218884Y140662D01*
X218551Y140745D01*
X218218Y140662D01*
X217926Y140453D01*
X217801Y140162D01*
X217884Y139870D01*
X218093Y139662D01*
X218343Y139578D01*
X218759D01*
X219134Y139453D01*
X219384Y139203D01*
X219468Y138912D01*
X219384Y138620D01*
X219176Y138412D01*
X218843Y138287D01*
X218551Y138245D01*
G01X216368Y140745D02*
Y138953D01*
X216201Y138578D01*
X215868Y138328D01*
X215451Y138245D01*
X215034Y138328D01*
X214701Y138578D01*
X214534Y138953D01*
Y140745D01*
G01X212434Y138245D02*
X212351Y138787D01*
X212226Y139245D01*
X212059Y139662D01*
X211851Y140120D01*
X211518Y140745D01*
X213184D01*
G01X237430Y140537D02*
X237680Y140662D01*
X237972Y140745D01*
X238305D01*
X238680Y140620D01*
X238972Y140412D01*
X239180Y140162D01*
X239347Y139745D01*
X239389Y139370D01*
X239305Y138995D01*
X239180Y138745D01*
X238930Y138495D01*
X238639Y138328D01*
X238347Y138245D01*
X238055D01*
X237764Y138328D01*
X237514Y138453D01*
X237305Y138620D01*
G01X235247Y138245D02*
X234955Y138287D01*
X234622Y138412D01*
X234414Y138620D01*
X234330Y138912D01*
X234414Y139203D01*
X234664Y139453D01*
X235039Y139578D01*
X235455D01*
X235705Y139662D01*
X235914Y139870D01*
X235997Y140162D01*
X235872Y140453D01*
X235580Y140662D01*
X235247Y140745D01*
X234914Y140662D01*
X234622Y140453D01*
X234497Y140162D01*
X234580Y139870D01*
X234789Y139662D01*
X235039Y139578D01*
X235455D01*
X235830Y139453D01*
X236080Y139203D01*
X236164Y138912D01*
X236080Y138620D01*
X235872Y138412D01*
X235539Y138287D01*
X235247Y138245D01*
G01X233064Y140745D02*
Y138953D01*
X232897Y138578D01*
X232564Y138328D01*
X232147Y138245D01*
X231730Y138328D01*
X231397Y138578D01*
X231230Y138953D01*
Y140745D01*
G01X229839Y139287D02*
X229547Y139578D01*
X229297Y139745D01*
X228964Y139828D01*
X228672Y139745D01*
X228464Y139578D01*
X228297Y139328D01*
X228255Y139037D01*
X228297Y138787D01*
X228464Y138537D01*
X228714Y138328D01*
X229005Y138245D01*
X229339Y138328D01*
X229630Y138578D01*
X229797Y138953D01*
X229839Y139370D01*
X229755Y139912D01*
X229630Y140203D01*
X229422Y140495D01*
X229130Y140703D01*
X228839Y140745D01*
X228547Y140662D01*
X228339Y140453D01*
G01X220734Y148537D02*
X220984Y148662D01*
X221276Y148745D01*
X221609D01*
X221984Y148620D01*
X222276Y148412D01*
X222484Y148162D01*
X222651Y147745D01*
X222693Y147370D01*
X222609Y146995D01*
X222484Y146745D01*
X222234Y146495D01*
X221943Y146328D01*
X221651Y146245D01*
X221359D01*
X221068Y146328D01*
X220818Y146453D01*
X220609Y146620D01*
G01X218551Y146245D02*
X218259Y146287D01*
X217926Y146412D01*
X217718Y146620D01*
X217634Y146912D01*
X217718Y147203D01*
X217968Y147453D01*
X218343Y147578D01*
X218759D01*
X219009Y147662D01*
X219218Y147870D01*
X219301Y148162D01*
X219176Y148453D01*
X218884Y148662D01*
X218551Y148745D01*
X218218Y148662D01*
X217926Y148453D01*
X217801Y148162D01*
X217884Y147870D01*
X218093Y147662D01*
X218343Y147578D01*
X218759D01*
X219134Y147453D01*
X219384Y147203D01*
X219468Y146912D01*
X219384Y146620D01*
X219176Y146412D01*
X218843Y146287D01*
X218551Y146245D01*
G01X215451Y148745D02*
Y146245D01*
G01X216409Y148745D02*
X214493D01*
G01X212351Y146245D02*
Y148745D01*
X212851Y148245D01*
G01Y146245D02*
X211851D01*
G01X209251Y148745D02*
X209584Y148662D01*
X209834Y148453D01*
X210001Y148203D01*
X210126Y147870D01*
X210168Y147495D01*
X210126Y147120D01*
X210001Y146787D01*
X209834Y146537D01*
X209584Y146328D01*
X209251Y146245D01*
X208918Y146328D01*
X208668Y146537D01*
X208501Y146787D01*
X208376Y147120D01*
X208334Y147495D01*
X208376Y147870D01*
X208501Y148203D01*
X208668Y148453D01*
X208918Y148662D01*
X209251Y148745D01*
G01X237430Y148537D02*
X237680Y148662D01*
X237972Y148745D01*
X238305D01*
X238680Y148620D01*
X238972Y148412D01*
X239180Y148162D01*
X239347Y147745D01*
X239389Y147370D01*
X239305Y146995D01*
X239180Y146745D01*
X238930Y146495D01*
X238639Y146328D01*
X238347Y146245D01*
X238055D01*
X237764Y146328D01*
X237514Y146453D01*
X237305Y146620D01*
G01X235247Y146245D02*
X234955Y146287D01*
X234622Y146412D01*
X234414Y146620D01*
X234330Y146912D01*
X234414Y147203D01*
X234664Y147453D01*
X235039Y147578D01*
X235455D01*
X235705Y147662D01*
X235914Y147870D01*
X235997Y148162D01*
X235872Y148453D01*
X235580Y148662D01*
X235247Y148745D01*
X234914Y148662D01*
X234622Y148453D01*
X234497Y148162D01*
X234580Y147870D01*
X234789Y147662D01*
X235039Y147578D01*
X235455D01*
X235830Y147453D01*
X236080Y147203D01*
X236164Y146912D01*
X236080Y146620D01*
X235872Y146412D01*
X235539Y146287D01*
X235247Y146245D01*
G01X232147Y148745D02*
Y146245D01*
G01X233105Y148745D02*
X231189D01*
G01X229755Y146537D02*
X229464Y146328D01*
X229130Y146245D01*
X228797Y146328D01*
X228505Y146578D01*
X228297Y146953D01*
X228214Y147328D01*
Y147787D01*
X228297Y148162D01*
X228505Y148495D01*
X228755Y148662D01*
X229047Y148745D01*
X229380Y148662D01*
X229630Y148495D01*
X229797Y148245D01*
X229880Y147912D01*
X229797Y147620D01*
X229589Y147328D01*
X229339Y147162D01*
X229047Y147120D01*
X228714Y147203D01*
X228464Y147412D01*
X228214Y147787D01*
G01X184364Y218200D02*
Y214409D01*
X171568D01*
Y218200D01*
G01X211117Y237100D02*
Y234000D01*
X209583D01*
G01X207748Y235033D02*
X206752D01*
G01X204993Y234000D02*
Y237100D01*
G01X203537D02*
X204993Y235188D01*
G01X203307Y234000D02*
X204342Y236067D01*
G01X201893Y234465D02*
X201663Y234207D01*
X201395Y234052D01*
X201050Y234000D01*
X200705Y234103D01*
X200437Y234310D01*
X200245Y234672D01*
X200207Y235085D01*
X200283Y235498D01*
X200475Y235757D01*
X200743Y235963D01*
X201012Y236015D01*
X201280Y235963D01*
X201625Y235757D01*
X201510Y237100D01*
X200475D01*
G01X192992Y252967D02*
X193117Y252717D01*
X193200Y252425D01*
Y252092D01*
X193075Y251717D01*
X192867Y251425D01*
X192617Y251217D01*
X192200Y251050D01*
X191825Y251008D01*
X191450Y251092D01*
X191200Y251217D01*
X190950Y251467D01*
X190783Y251758D01*
X190700Y252050D01*
Y252342D01*
X190783Y252633D01*
X190908Y252883D01*
X191075Y253092D01*
G01X190992Y254442D02*
X190783Y254733D01*
X190700Y255067D01*
X190783Y255400D01*
X191033Y255692D01*
X191408Y255900D01*
X191783Y255983D01*
X192242D01*
X192617Y255900D01*
X192950Y255692D01*
X193117Y255442D01*
X193200Y255150D01*
X193117Y254817D01*
X192950Y254567D01*
X192700Y254400D01*
X192367Y254317D01*
X192075Y254400D01*
X191783Y254608D01*
X191617Y254858D01*
X191575Y255150D01*
X191658Y255483D01*
X191867Y255733D01*
X192242Y255983D01*
G01X190700Y257417D02*
X193200D01*
Y258458D01*
X193075Y258792D01*
X192908Y259000D01*
X192575Y259083D01*
X192242Y259000D01*
X192033Y258750D01*
X191908Y258458D01*
Y257417D01*
G01Y258458D02*
X190700Y259083D01*
G01X192783Y260558D02*
X193033Y260808D01*
X193158Y261100D01*
X193200Y261433D01*
X193117Y261850D01*
X192908Y262142D01*
X192658Y262225D01*
X192408Y262183D01*
X192200Y262017D01*
X191783Y261183D01*
X191492Y260808D01*
X191075Y260558D01*
X190700Y260475D01*
Y262225D01*
G01X191633Y222807D02*
X191758Y222557D01*
X191841Y222265D01*
Y221932D01*
X191716Y221557D01*
X191508Y221265D01*
X191258Y221057D01*
X190841Y220890D01*
X190466Y220848D01*
X190091Y220932D01*
X189841Y221057D01*
X189591Y221307D01*
X189424Y221598D01*
X189341Y221890D01*
Y222182D01*
X189424Y222473D01*
X189549Y222723D01*
X189716Y222932D01*
G01X189633Y224282D02*
X189424Y224573D01*
X189341Y224907D01*
X189424Y225240D01*
X189674Y225532D01*
X190049Y225740D01*
X190424Y225823D01*
X190883D01*
X191258Y225740D01*
X191591Y225532D01*
X191758Y225282D01*
X191841Y224990D01*
X191758Y224657D01*
X191591Y224407D01*
X191341Y224240D01*
X191008Y224157D01*
X190716Y224240D01*
X190424Y224448D01*
X190258Y224698D01*
X190216Y224990D01*
X190299Y225323D01*
X190508Y225573D01*
X190883Y225823D01*
G01X189341Y227257D02*
X191841D01*
Y228298D01*
X191716Y228632D01*
X191549Y228840D01*
X191216Y228923D01*
X190883Y228840D01*
X190674Y228590D01*
X190549Y228298D01*
Y227257D01*
G01Y228298D02*
X189341Y228923D01*
G01Y231190D02*
X189383Y231482D01*
X189508Y231815D01*
X189716Y232023D01*
X190008Y232107D01*
X190299Y232023D01*
X190549Y231773D01*
X190674Y231398D01*
Y230982D01*
X190758Y230732D01*
X190966Y230523D01*
X191258Y230440D01*
X191549Y230565D01*
X191758Y230857D01*
X191841Y231190D01*
X191758Y231523D01*
X191549Y231815D01*
X191258Y231940D01*
X190966Y231857D01*
X190758Y231648D01*
X190674Y231398D01*
Y230982D01*
X190549Y230607D01*
X190299Y230357D01*
X190008Y230273D01*
X189716Y230357D01*
X189508Y230565D01*
X189383Y230898D01*
X189341Y231190D01*
G01X189542Y281617D02*
X189667Y281367D01*
X189750Y281075D01*
Y280742D01*
X189625Y280367D01*
X189417Y280075D01*
X189167Y279867D01*
X188750Y279700D01*
X188375Y279658D01*
X188000Y279742D01*
X187750Y279867D01*
X187500Y280117D01*
X187333Y280408D01*
X187250Y280700D01*
Y280992D01*
X187333Y281283D01*
X187458Y281533D01*
X187625Y281742D01*
G01X187542Y283092D02*
X187333Y283383D01*
X187250Y283717D01*
X187333Y284050D01*
X187583Y284342D01*
X187958Y284550D01*
X188333Y284633D01*
X188792D01*
X189167Y284550D01*
X189500Y284342D01*
X189667Y284092D01*
X189750Y283800D01*
X189667Y283467D01*
X189500Y283217D01*
X189250Y283050D01*
X188917Y282967D01*
X188625Y283050D01*
X188333Y283258D01*
X188167Y283508D01*
X188125Y283800D01*
X188208Y284133D01*
X188417Y284383D01*
X188792Y284633D01*
G01X187250Y286067D02*
X189750D01*
Y287067D01*
X189625Y287400D01*
X189333Y287650D01*
X189000Y287733D01*
X188667Y287650D01*
X188417Y287442D01*
X188292Y287067D01*
Y286067D01*
G01X187250Y290000D02*
X189750D01*
X189250Y289500D01*
G01X187250D02*
Y290500D01*
G01Y293100D02*
X187292Y293392D01*
X187417Y293725D01*
X187625Y293933D01*
X187917Y294017D01*
X188208Y293933D01*
X188458Y293683D01*
X188583Y293308D01*
Y292892D01*
X188667Y292642D01*
X188875Y292433D01*
X189167Y292350D01*
X189458Y292475D01*
X189667Y292767D01*
X189750Y293100D01*
X189667Y293433D01*
X189458Y293725D01*
X189167Y293850D01*
X188875Y293767D01*
X188667Y293558D01*
X188583Y293308D01*
Y292892D01*
X188458Y292517D01*
X188208Y292267D01*
X187917Y292183D01*
X187625Y292267D01*
X187417Y292475D01*
X187292Y292808D01*
X187250Y293100D01*
G01X184364Y282200D02*
Y278409D01*
X171568D01*
Y282200D01*
G01X188172Y256966D02*
X188297Y256716D01*
X188380Y256424D01*
Y256091D01*
X188255Y255716D01*
X188047Y255424D01*
X187797Y255216D01*
X187380Y255049D01*
X187005Y255007D01*
X186630Y255091D01*
X186380Y255216D01*
X186130Y255466D01*
X185963Y255757D01*
X185880Y256049D01*
Y256341D01*
X185963Y256632D01*
X186088Y256882D01*
X186255Y257091D01*
G01X186172Y258441D02*
X185963Y258732D01*
X185880Y259066D01*
X185963Y259399D01*
X186213Y259691D01*
X186588Y259899D01*
X186963Y259982D01*
X187422D01*
X187797Y259899D01*
X188130Y259691D01*
X188297Y259441D01*
X188380Y259149D01*
X188297Y258816D01*
X188130Y258566D01*
X187880Y258399D01*
X187547Y258316D01*
X187255Y258399D01*
X186963Y258607D01*
X186797Y258857D01*
X186755Y259149D01*
X186838Y259482D01*
X187047Y259732D01*
X187422Y259982D01*
G01X185880Y261416D02*
X188380D01*
Y262416D01*
X188255Y262749D01*
X187963Y262999D01*
X187630Y263082D01*
X187297Y262999D01*
X187047Y262791D01*
X186922Y262416D01*
Y261416D01*
G01X187963Y264557D02*
X188213Y264807D01*
X188338Y265099D01*
X188380Y265432D01*
X188297Y265849D01*
X188088Y266141D01*
X187838Y266224D01*
X187588Y266182D01*
X187380Y266016D01*
X186963Y265182D01*
X186672Y264807D01*
X186255Y264557D01*
X185880Y264474D01*
Y266224D01*
G01X186380Y267532D02*
X186088Y267782D01*
X185922Y268116D01*
X185880Y268491D01*
X185922Y268824D01*
X186130Y269157D01*
X186380Y269366D01*
X186630Y269407D01*
X186922Y269324D01*
X187130Y269032D01*
X187213Y268741D01*
Y268366D01*
G01Y268741D02*
X187338Y268991D01*
X187547Y269199D01*
X187797Y269282D01*
X188047Y269199D01*
X188255Y268991D01*
X188380Y268616D01*
X188338Y268241D01*
X188172Y267866D01*
G01X184364Y261200D02*
Y257409D01*
X171568D01*
Y261200D01*
G01X184364Y273800D02*
Y277362D01*
X171568D01*
Y273800D01*
G01X188142Y243467D02*
X188267Y243217D01*
X188350Y242925D01*
Y242592D01*
X188225Y242217D01*
X188017Y241925D01*
X187767Y241717D01*
X187350Y241550D01*
X186975Y241508D01*
X186600Y241592D01*
X186350Y241717D01*
X186100Y241967D01*
X185933Y242258D01*
X185850Y242550D01*
Y242842D01*
X185933Y243133D01*
X186058Y243383D01*
X186225Y243592D01*
G01X186142Y244942D02*
X185933Y245233D01*
X185850Y245567D01*
X185933Y245900D01*
X186183Y246192D01*
X186558Y246400D01*
X186933Y246483D01*
X187392D01*
X187767Y246400D01*
X188100Y246192D01*
X188267Y245942D01*
X188350Y245650D01*
X188267Y245317D01*
X188100Y245067D01*
X187850Y244900D01*
X187517Y244817D01*
X187225Y244900D01*
X186933Y245108D01*
X186767Y245358D01*
X186725Y245650D01*
X186808Y245983D01*
X187017Y246233D01*
X187392Y246483D01*
G01X185850Y247917D02*
X188350D01*
Y248958D01*
X188225Y249292D01*
X188058Y249500D01*
X187725Y249583D01*
X187392Y249500D01*
X187183Y249250D01*
X187058Y248958D01*
Y247917D01*
G01Y248958D02*
X185850Y249583D01*
G01X186350Y250933D02*
X186058Y251183D01*
X185892Y251517D01*
X185850Y251892D01*
X185892Y252225D01*
X186100Y252558D01*
X186350Y252767D01*
X186600Y252808D01*
X186892Y252725D01*
X187100Y252433D01*
X187183Y252142D01*
Y251767D01*
G01Y252142D02*
X187308Y252392D01*
X187517Y252600D01*
X187767Y252683D01*
X188017Y252600D01*
X188225Y252392D01*
X188350Y252017D01*
X188308Y251642D01*
X188142Y251267D01*
G01X184364Y240200D02*
Y236409D01*
X171568D01*
Y240200D01*
G01X184364Y252800D02*
Y256362D01*
X171568D01*
Y252800D01*
G01X184364Y230800D02*
Y234362D01*
X171568D01*
Y230800D01*
G01X195597Y313363D02*
X195722Y313113D01*
X195805Y312821D01*
Y312488D01*
X195680Y312113D01*
X195472Y311821D01*
X195222Y311613D01*
X194805Y311446D01*
X194430Y311404D01*
X194055Y311488D01*
X193805Y311613D01*
X193555Y311863D01*
X193388Y312154D01*
X193305Y312446D01*
Y312738D01*
X193388Y313029D01*
X193513Y313279D01*
X193680Y313488D01*
G01X193597Y314838D02*
X193388Y315129D01*
X193305Y315463D01*
X193388Y315796D01*
X193638Y316088D01*
X194013Y316296D01*
X194388Y316379D01*
X194847D01*
X195222Y316296D01*
X195555Y316088D01*
X195722Y315838D01*
X195805Y315546D01*
X195722Y315213D01*
X195555Y314963D01*
X195305Y314796D01*
X194972Y314713D01*
X194680Y314796D01*
X194388Y315004D01*
X194222Y315254D01*
X194180Y315546D01*
X194263Y315879D01*
X194472Y316129D01*
X194847Y316379D01*
G01X193305Y317813D02*
X195805D01*
Y318813D01*
X195680Y319146D01*
X195388Y319396D01*
X195055Y319479D01*
X194722Y319396D01*
X194472Y319188D01*
X194347Y318813D01*
Y317813D01*
G01X193305Y321746D02*
X195805D01*
X195305Y321246D01*
G01X193305D02*
Y322246D01*
G01X195805Y324846D02*
X195722Y324513D01*
X195513Y324263D01*
X195263Y324096D01*
X194930Y323971D01*
X194555Y323929D01*
X194180Y323971D01*
X193847Y324096D01*
X193597Y324263D01*
X193388Y324513D01*
X193305Y324846D01*
X193388Y325179D01*
X193597Y325429D01*
X193847Y325596D01*
X194180Y325721D01*
X194555Y325763D01*
X194930Y325721D01*
X195263Y325596D01*
X195513Y325429D01*
X195722Y325179D01*
X195805Y324846D01*
G01X195292Y285817D02*
X195417Y285567D01*
X195500Y285275D01*
Y284942D01*
X195375Y284567D01*
X195167Y284275D01*
X194917Y284067D01*
X194500Y283900D01*
X194125Y283858D01*
X193750Y283942D01*
X193500Y284067D01*
X193250Y284317D01*
X193083Y284608D01*
X193000Y284900D01*
Y285192D01*
X193083Y285483D01*
X193208Y285733D01*
X193375Y285942D01*
G01X193292Y287292D02*
X193083Y287583D01*
X193000Y287917D01*
X193083Y288250D01*
X193333Y288542D01*
X193708Y288750D01*
X194083Y288833D01*
X194542D01*
X194917Y288750D01*
X195250Y288542D01*
X195417Y288292D01*
X195500Y288000D01*
X195417Y287667D01*
X195250Y287417D01*
X195000Y287250D01*
X194667Y287167D01*
X194375Y287250D01*
X194083Y287458D01*
X193917Y287708D01*
X193875Y288000D01*
X193958Y288333D01*
X194167Y288583D01*
X194542Y288833D01*
G01X193000Y290267D02*
X195500D01*
Y291267D01*
X195375Y291600D01*
X195083Y291850D01*
X194750Y291933D01*
X194417Y291850D01*
X194167Y291642D01*
X194042Y291267D01*
Y290267D01*
G01X195083Y293408D02*
X195333Y293658D01*
X195458Y293950D01*
X195500Y294283D01*
X195417Y294700D01*
X195208Y294992D01*
X194958Y295075D01*
X194708Y295033D01*
X194500Y294867D01*
X194083Y294033D01*
X193792Y293658D01*
X193375Y293408D01*
X193000Y293325D01*
Y295075D01*
G01X195500Y297300D02*
X195417Y296967D01*
X195208Y296717D01*
X194958Y296550D01*
X194625Y296425D01*
X194250Y296383D01*
X193875Y296425D01*
X193542Y296550D01*
X193292Y296717D01*
X193083Y296967D01*
X193000Y297300D01*
X193083Y297633D01*
X193292Y297883D01*
X193542Y298050D01*
X193875Y298175D01*
X194250Y298217D01*
X194625Y298175D01*
X194958Y298050D01*
X195208Y297883D01*
X195417Y297633D01*
X195500Y297300D01*
G01X184364Y294800D02*
Y298362D01*
X171568D01*
Y294800D01*
G01X188042Y307867D02*
X188167Y307617D01*
X188250Y307325D01*
Y306992D01*
X188125Y306617D01*
X187917Y306325D01*
X187667Y306117D01*
X187250Y305950D01*
X186875Y305908D01*
X186500Y305992D01*
X186250Y306117D01*
X186000Y306367D01*
X185833Y306658D01*
X185750Y306950D01*
Y307242D01*
X185833Y307533D01*
X185958Y307783D01*
X186125Y307992D01*
G01X186042Y309342D02*
X185833Y309633D01*
X185750Y309967D01*
X185833Y310300D01*
X186083Y310592D01*
X186458Y310800D01*
X186833Y310883D01*
X187292D01*
X187667Y310800D01*
X188000Y310592D01*
X188167Y310342D01*
X188250Y310050D01*
X188167Y309717D01*
X188000Y309467D01*
X187750Y309300D01*
X187417Y309217D01*
X187125Y309300D01*
X186833Y309508D01*
X186667Y309758D01*
X186625Y310050D01*
X186708Y310383D01*
X186917Y310633D01*
X187292Y310883D01*
G01X185750Y312317D02*
X188250D01*
Y313317D01*
X188125Y313650D01*
X187833Y313900D01*
X187500Y313983D01*
X187167Y313900D01*
X186917Y313692D01*
X186792Y313317D01*
Y312317D01*
G01X185750Y316250D02*
X185792Y316542D01*
X185917Y316875D01*
X186125Y317083D01*
X186417Y317167D01*
X186708Y317083D01*
X186958Y316833D01*
X187083Y316458D01*
Y316042D01*
X187167Y315792D01*
X187375Y315583D01*
X187667Y315500D01*
X187958Y315625D01*
X188167Y315917D01*
X188250Y316250D01*
X188167Y316583D01*
X187958Y316875D01*
X187667Y317000D01*
X187375Y316917D01*
X187167Y316708D01*
X187083Y316458D01*
Y316042D01*
X186958Y315667D01*
X186708Y315417D01*
X186417Y315333D01*
X186125Y315417D01*
X185917Y315625D01*
X185792Y315958D01*
X185750Y316250D01*
G01X184364Y304200D02*
Y300409D01*
X171568D01*
Y304200D01*
G01X184364Y316800D02*
Y320362D01*
X171568D01*
Y316800D01*
G01X187411Y322849D02*
X187536Y322599D01*
X187619Y322307D01*
Y321974D01*
X187494Y321599D01*
X187286Y321307D01*
X187036Y321099D01*
X186619Y320932D01*
X186244Y320890D01*
X185869Y320974D01*
X185619Y321099D01*
X185369Y321349D01*
X185202Y321640D01*
X185119Y321932D01*
Y322224D01*
X185202Y322515D01*
X185327Y322765D01*
X185494Y322974D01*
G01X185411Y324324D02*
X185202Y324615D01*
X185119Y324949D01*
X185202Y325282D01*
X185452Y325574D01*
X185827Y325782D01*
X186202Y325865D01*
X186661D01*
X187036Y325782D01*
X187369Y325574D01*
X187536Y325324D01*
X187619Y325032D01*
X187536Y324699D01*
X187369Y324449D01*
X187119Y324282D01*
X186786Y324199D01*
X186494Y324282D01*
X186202Y324490D01*
X186036Y324740D01*
X185994Y325032D01*
X186077Y325365D01*
X186286Y325615D01*
X186661Y325865D01*
G01X185119Y327299D02*
X187619D01*
Y328299D01*
X187494Y328632D01*
X187202Y328882D01*
X186869Y328965D01*
X186536Y328882D01*
X186286Y328674D01*
X186161Y328299D01*
Y327299D01*
G01X185494Y330315D02*
X185286Y330565D01*
X185161Y330857D01*
X185119Y331232D01*
X185202Y331607D01*
X185369Y331899D01*
X185661Y332107D01*
X185994Y332149D01*
X186327Y332065D01*
X186536Y331857D01*
X186702Y331565D01*
X186744Y331274D01*
X186702Y330982D01*
X186536Y330607D01*
X187619Y330732D01*
Y331857D01*
G01X184364Y324200D02*
Y320409D01*
X171568D01*
Y324200D01*
G01X184364Y336800D02*
Y340362D01*
X171568D01*
Y336800D01*
G01X240783Y365500D02*
Y368000D01*
X239742D01*
X239408Y367875D01*
X239200Y367708D01*
X239117Y367375D01*
X239200Y367042D01*
X239450Y366833D01*
X239742Y366708D01*
X240783D01*
G01X239742D02*
X239117Y365500D01*
G01X236850D02*
X236558Y365542D01*
X236225Y365667D01*
X236017Y365875D01*
X235933Y366167D01*
X236017Y366458D01*
X236267Y366708D01*
X236642Y366833D01*
X237058D01*
X237308Y366917D01*
X237517Y367125D01*
X237600Y367417D01*
X237475Y367708D01*
X237183Y367917D01*
X236850Y368000D01*
X236517Y367917D01*
X236225Y367708D01*
X236100Y367417D01*
X236183Y367125D01*
X236392Y366917D01*
X236642Y366833D01*
X237058D01*
X237433Y366708D01*
X237683Y366458D01*
X237767Y366167D01*
X237683Y365875D01*
X237475Y365667D01*
X237142Y365542D01*
X236850Y365500D01*
G01X234708D02*
Y368000D01*
X232792Y365500D01*
Y368000D01*
G01X230650Y365500D02*
Y368000D01*
X231150Y367500D01*
G01Y365500D02*
X230150D01*
G01X240783Y361500D02*
Y364000D01*
X239742D01*
X239408Y363875D01*
X239200Y363708D01*
X239117Y363375D01*
X239200Y363042D01*
X239450Y362833D01*
X239742Y362708D01*
X240783D01*
G01X239742D02*
X239117Y361500D01*
G01X236850D02*
X236558Y361542D01*
X236225Y361667D01*
X236017Y361875D01*
X235933Y362167D01*
X236017Y362458D01*
X236267Y362708D01*
X236642Y362833D01*
X237058D01*
X237308Y362917D01*
X237517Y363125D01*
X237600Y363417D01*
X237475Y363708D01*
X237183Y363917D01*
X236850Y364000D01*
X236517Y363917D01*
X236225Y363708D01*
X236100Y363417D01*
X236183Y363125D01*
X236392Y362917D01*
X236642Y362833D01*
X237058D01*
X237433Y362708D01*
X237683Y362458D01*
X237767Y362167D01*
X237683Y361875D01*
X237475Y361667D01*
X237142Y361542D01*
X236850Y361500D01*
G01X234708D02*
Y364000D01*
X232792Y361500D01*
Y364000D01*
G01X231442Y363583D02*
X231192Y363833D01*
X230900Y363958D01*
X230567Y364000D01*
X230150Y363917D01*
X229858Y363708D01*
X229775Y363458D01*
X229817Y363208D01*
X229983Y363000D01*
X230817Y362583D01*
X231192Y362292D01*
X231442Y361875D01*
X231525Y361500D01*
X229775D01*
G01X240783Y357500D02*
Y360000D01*
X239742D01*
X239408Y359875D01*
X239200Y359708D01*
X239117Y359375D01*
X239200Y359042D01*
X239450Y358833D01*
X239742Y358708D01*
X240783D01*
G01X239742D02*
X239117Y357500D01*
G01X236850D02*
X236558Y357542D01*
X236225Y357667D01*
X236017Y357875D01*
X235933Y358167D01*
X236017Y358458D01*
X236267Y358708D01*
X236642Y358833D01*
X237058D01*
X237308Y358917D01*
X237517Y359125D01*
X237600Y359417D01*
X237475Y359708D01*
X237183Y359917D01*
X236850Y360000D01*
X236517Y359917D01*
X236225Y359708D01*
X236100Y359417D01*
X236183Y359125D01*
X236392Y358917D01*
X236642Y358833D01*
X237058D01*
X237433Y358708D01*
X237683Y358458D01*
X237767Y358167D01*
X237683Y357875D01*
X237475Y357667D01*
X237142Y357542D01*
X236850Y357500D01*
G01X234708D02*
Y360000D01*
X232792Y357500D01*
Y360000D01*
G01X231567Y358000D02*
X231317Y357708D01*
X230983Y357542D01*
X230608Y357500D01*
X230275Y357542D01*
X229942Y357750D01*
X229733Y358000D01*
X229692Y358250D01*
X229775Y358542D01*
X230067Y358750D01*
X230358Y358833D01*
X230733D01*
G01X230358D02*
X230108Y358958D01*
X229900Y359167D01*
X229817Y359417D01*
X229900Y359667D01*
X230108Y359875D01*
X230483Y360000D01*
X230858Y359958D01*
X231233Y359792D01*
G01X240783Y353500D02*
Y356000D01*
X239742D01*
X239408Y355875D01*
X239200Y355708D01*
X239117Y355375D01*
X239200Y355042D01*
X239450Y354833D01*
X239742Y354708D01*
X240783D01*
G01X239742D02*
X239117Y353500D01*
G01X236850D02*
X236558Y353542D01*
X236225Y353667D01*
X236017Y353875D01*
X235933Y354167D01*
X236017Y354458D01*
X236267Y354708D01*
X236642Y354833D01*
X237058D01*
X237308Y354917D01*
X237517Y355125D01*
X237600Y355417D01*
X237475Y355708D01*
X237183Y355917D01*
X236850Y356000D01*
X236517Y355917D01*
X236225Y355708D01*
X236100Y355417D01*
X236183Y355125D01*
X236392Y354917D01*
X236642Y354833D01*
X237058D01*
X237433Y354708D01*
X237683Y354458D01*
X237767Y354167D01*
X237683Y353875D01*
X237475Y353667D01*
X237142Y353542D01*
X236850Y353500D01*
G01X234708D02*
Y356000D01*
X232792Y353500D01*
Y356000D01*
G01X230150Y353500D02*
Y356000D01*
X231692Y354208D01*
X229608D01*
G01X240783Y349500D02*
Y352000D01*
X239742D01*
X239408Y351875D01*
X239200Y351708D01*
X239117Y351375D01*
X239200Y351042D01*
X239450Y350833D01*
X239742Y350708D01*
X240783D01*
G01X239742D02*
X239117Y349500D01*
G01X236850D02*
X236558Y349542D01*
X236225Y349667D01*
X236017Y349875D01*
X235933Y350167D01*
X236017Y350458D01*
X236267Y350708D01*
X236642Y350833D01*
X237058D01*
X237308Y350917D01*
X237517Y351125D01*
X237600Y351417D01*
X237475Y351708D01*
X237183Y351917D01*
X236850Y352000D01*
X236517Y351917D01*
X236225Y351708D01*
X236100Y351417D01*
X236183Y351125D01*
X236392Y350917D01*
X236642Y350833D01*
X237058D01*
X237433Y350708D01*
X237683Y350458D01*
X237767Y350167D01*
X237683Y349875D01*
X237475Y349667D01*
X237142Y349542D01*
X236850Y349500D01*
G01X234708D02*
Y352000D01*
X232792Y349500D01*
Y352000D01*
G01X231567Y349875D02*
X231317Y349667D01*
X231025Y349542D01*
X230650Y349500D01*
X230275Y349583D01*
X229983Y349750D01*
X229775Y350042D01*
X229733Y350375D01*
X229817Y350708D01*
X230025Y350917D01*
X230317Y351083D01*
X230608Y351125D01*
X230900Y351083D01*
X231275Y350917D01*
X231150Y352000D01*
X230025D01*
G01X197600Y381617D02*
X200100D01*
Y382658D01*
X199975Y382992D01*
X199808Y383200D01*
X199475Y383283D01*
X199142Y383200D01*
X198933Y382950D01*
X198808Y382658D01*
Y381617D01*
G01Y382658D02*
X197600Y383283D01*
G01X197892Y384842D02*
X197683Y385133D01*
X197600Y385467D01*
X197683Y385800D01*
X197933Y386092D01*
X198308Y386300D01*
X198683Y386383D01*
X199142D01*
X199517Y386300D01*
X199850Y386092D01*
X200017Y385842D01*
X200100Y385550D01*
X200017Y385217D01*
X199850Y384967D01*
X199600Y384800D01*
X199267Y384717D01*
X198975Y384800D01*
X198683Y385008D01*
X198517Y385258D01*
X198475Y385550D01*
X198558Y385883D01*
X198767Y386133D01*
X199142Y386383D01*
G01X197600Y387692D02*
X200100D01*
X197600Y389608D01*
X200100D01*
G01X197600Y392250D02*
X200100D01*
X198308Y390708D01*
Y392792D01*
G01X200842Y356417D02*
X200967Y356167D01*
X201050Y355875D01*
Y355542D01*
X200925Y355167D01*
X200717Y354875D01*
X200467Y354667D01*
X200050Y354500D01*
X199675Y354458D01*
X199300Y354542D01*
X199050Y354667D01*
X198800Y354917D01*
X198633Y355208D01*
X198550Y355500D01*
Y355792D01*
X198633Y356083D01*
X198758Y356333D01*
X198925Y356542D01*
G01X198842Y357892D02*
X198633Y358183D01*
X198550Y358517D01*
X198633Y358850D01*
X198883Y359142D01*
X199258Y359350D01*
X199633Y359433D01*
X200092D01*
X200467Y359350D01*
X200800Y359142D01*
X200967Y358892D01*
X201050Y358600D01*
X200967Y358267D01*
X200800Y358017D01*
X200550Y357850D01*
X200217Y357767D01*
X199925Y357850D01*
X199633Y358058D01*
X199467Y358308D01*
X199425Y358600D01*
X199508Y358933D01*
X199717Y359183D01*
X200092Y359433D01*
G01X198550Y360742D02*
X201050D01*
X198550Y362658D01*
X201050D01*
G01X200633Y364008D02*
X200883Y364258D01*
X201008Y364550D01*
X201050Y364883D01*
X200967Y365300D01*
X200758Y365592D01*
X200508Y365675D01*
X200258Y365633D01*
X200050Y365467D01*
X199633Y364633D01*
X199342Y364258D01*
X198925Y364008D01*
X198550Y363925D01*
Y365675D01*
G01X200633Y367108D02*
X200883Y367358D01*
X201008Y367650D01*
X201050Y367983D01*
X200967Y368400D01*
X200758Y368692D01*
X200508Y368775D01*
X200258Y368733D01*
X200050Y368567D01*
X199633Y367733D01*
X199342Y367358D01*
X198925Y367108D01*
X198550Y367025D01*
Y368775D01*
G01X193082Y346524D02*
X193207Y346274D01*
X193290Y345982D01*
Y345649D01*
X193165Y345274D01*
X192957Y344982D01*
X192707Y344774D01*
X192290Y344607D01*
X191915Y344565D01*
X191540Y344649D01*
X191290Y344774D01*
X191040Y345024D01*
X190873Y345315D01*
X190790Y345607D01*
Y345899D01*
X190873Y346190D01*
X190998Y346440D01*
X191165Y346649D01*
G01X191082Y347999D02*
X190873Y348290D01*
X190790Y348624D01*
X190873Y348957D01*
X191123Y349249D01*
X191498Y349457D01*
X191873Y349540D01*
X192332D01*
X192707Y349457D01*
X193040Y349249D01*
X193207Y348999D01*
X193290Y348707D01*
X193207Y348374D01*
X193040Y348124D01*
X192790Y347957D01*
X192457Y347874D01*
X192165Y347957D01*
X191873Y348165D01*
X191707Y348415D01*
X191665Y348707D01*
X191748Y349040D01*
X191957Y349290D01*
X192332Y349540D01*
G01X190790Y350974D02*
X193290D01*
Y351974D01*
X193165Y352307D01*
X192873Y352557D01*
X192540Y352640D01*
X192207Y352557D01*
X191957Y352349D01*
X191832Y351974D01*
Y350974D01*
G01X191290Y353990D02*
X190998Y354240D01*
X190832Y354574D01*
X190790Y354949D01*
X190832Y355282D01*
X191040Y355615D01*
X191290Y355824D01*
X191540Y355865D01*
X191832Y355782D01*
X192040Y355490D01*
X192123Y355199D01*
Y354824D01*
G01Y355199D02*
X192248Y355449D01*
X192457Y355657D01*
X192707Y355740D01*
X192957Y355657D01*
X193165Y355449D01*
X193290Y355074D01*
X193248Y354699D01*
X193082Y354324D01*
G01X191100Y396404D02*
X191225Y396154D01*
X191308Y395862D01*
Y395529D01*
X191183Y395154D01*
X190975Y394862D01*
X190725Y394654D01*
X190308Y394487D01*
X189933Y394445D01*
X189558Y394529D01*
X189308Y394654D01*
X189058Y394904D01*
X188891Y395195D01*
X188808Y395487D01*
Y395779D01*
X188891Y396070D01*
X189016Y396320D01*
X189183Y396529D01*
G01X189100Y397879D02*
X188891Y398170D01*
X188808Y398504D01*
X188891Y398837D01*
X189141Y399129D01*
X189516Y399337D01*
X189891Y399420D01*
X190350D01*
X190725Y399337D01*
X191058Y399129D01*
X191225Y398879D01*
X191308Y398587D01*
X191225Y398254D01*
X191058Y398004D01*
X190808Y397837D01*
X190475Y397754D01*
X190183Y397837D01*
X189891Y398045D01*
X189725Y398295D01*
X189683Y398587D01*
X189766Y398920D01*
X189975Y399170D01*
X190350Y399420D01*
G01X188808Y400729D02*
X191308D01*
X188808Y402645D01*
X191308D01*
G01X188808Y404787D02*
X191308D01*
X190808Y404287D01*
G01X188808D02*
Y405287D01*
G01Y407887D02*
X191308D01*
X190808Y407387D01*
G01X188808D02*
Y408387D01*
G01X185938Y402663D02*
Y406225D01*
X173142D01*
Y402663D01*
G01X185938Y390063D02*
Y386272D01*
X173142D01*
Y390063D01*
G01X188342Y346556D02*
X188467Y346306D01*
X188550Y346014D01*
Y345681D01*
X188425Y345306D01*
X188217Y345014D01*
X187967Y344806D01*
X187550Y344639D01*
X187175Y344597D01*
X186800Y344681D01*
X186550Y344806D01*
X186300Y345056D01*
X186133Y345347D01*
X186050Y345639D01*
Y345931D01*
X186133Y346222D01*
X186258Y346472D01*
X186425Y346681D01*
G01X186342Y348031D02*
X186133Y348322D01*
X186050Y348656D01*
X186133Y348989D01*
X186383Y349281D01*
X186758Y349489D01*
X187133Y349572D01*
X187592D01*
X187967Y349489D01*
X188300Y349281D01*
X188467Y349031D01*
X188550Y348739D01*
X188467Y348406D01*
X188300Y348156D01*
X188050Y347989D01*
X187717Y347906D01*
X187425Y347989D01*
X187133Y348197D01*
X186967Y348447D01*
X186925Y348739D01*
X187008Y349072D01*
X187217Y349322D01*
X187592Y349572D01*
G01X186050Y350881D02*
X188550D01*
X186050Y352797D01*
X188550D01*
G01X188133Y354147D02*
X188383Y354397D01*
X188508Y354689D01*
X188550Y355022D01*
X188467Y355439D01*
X188258Y355731D01*
X188008Y355814D01*
X187758Y355772D01*
X187550Y355606D01*
X187133Y354772D01*
X186842Y354397D01*
X186425Y354147D01*
X186050Y354064D01*
Y355814D01*
G01Y358539D02*
X188550D01*
X186758Y356997D01*
Y359081D01*
G01X184364Y345700D02*
Y341909D01*
X171568D01*
Y345700D01*
G01X184364Y358300D02*
Y361862D01*
X171568D01*
Y358300D01*
G01X189655Y373943D02*
X189780Y373693D01*
X189863Y373401D01*
Y373068D01*
X189738Y372693D01*
X189530Y372401D01*
X189280Y372193D01*
X188863Y372026D01*
X188488Y371984D01*
X188113Y372068D01*
X187863Y372193D01*
X187613Y372443D01*
X187446Y372734D01*
X187363Y373026D01*
Y373318D01*
X187446Y373609D01*
X187571Y373859D01*
X187738Y374068D01*
G01X187655Y375418D02*
X187446Y375709D01*
X187363Y376043D01*
X187446Y376376D01*
X187696Y376668D01*
X188071Y376876D01*
X188446Y376959D01*
X188905D01*
X189280Y376876D01*
X189613Y376668D01*
X189780Y376418D01*
X189863Y376126D01*
X189780Y375793D01*
X189613Y375543D01*
X189363Y375376D01*
X189030Y375293D01*
X188738Y375376D01*
X188446Y375584D01*
X188280Y375834D01*
X188238Y376126D01*
X188321Y376459D01*
X188530Y376709D01*
X188905Y376959D01*
G01X187363Y378268D02*
X189863D01*
X187363Y380184D01*
X189863D01*
G01X189446Y381534D02*
X189696Y381784D01*
X189821Y382076D01*
X189863Y382409D01*
X189780Y382826D01*
X189571Y383118D01*
X189321Y383201D01*
X189071Y383159D01*
X188863Y382993D01*
X188446Y382159D01*
X188155Y381784D01*
X187738Y381534D01*
X187363Y381451D01*
Y383201D01*
G01X189863Y385426D02*
X189780Y385093D01*
X189571Y384843D01*
X189321Y384676D01*
X188988Y384551D01*
X188613Y384509D01*
X188238Y384551D01*
X187905Y384676D01*
X187655Y384843D01*
X187446Y385093D01*
X187363Y385426D01*
X187446Y385759D01*
X187655Y386009D01*
X187905Y386176D01*
X188238Y386301D01*
X188613Y386343D01*
X188988Y386301D01*
X189321Y386176D01*
X189571Y386009D01*
X189780Y385759D01*
X189863Y385426D01*
G01X185938Y370063D02*
Y366272D01*
X173142D01*
Y370063D01*
G01X185938Y382663D02*
Y386225D01*
X173142D01*
Y382663D01*
G01X385740Y470340D02*
X184580D01*
Y448560D01*
X388250D01*
Y470340D01*
X385740D01*
G01X204271Y459538D02*
X204521Y459663D01*
X204813Y459746D01*
X205146D01*
X205521Y459621D01*
X205813Y459413D01*
X206021Y459163D01*
X206188Y458746D01*
X206230Y458371D01*
X206146Y457996D01*
X206021Y457746D01*
X205771Y457496D01*
X205480Y457329D01*
X205188Y457246D01*
X204896D01*
X204605Y457329D01*
X204355Y457454D01*
X204146Y457621D01*
G01X203005D02*
X202755Y457413D01*
X202463Y457288D01*
X202088Y457246D01*
X201713Y457329D01*
X201421Y457496D01*
X201213Y457788D01*
X201171Y458121D01*
X201255Y458454D01*
X201463Y458663D01*
X201755Y458829D01*
X202046Y458871D01*
X202338Y458829D01*
X202713Y458663D01*
X202588Y459746D01*
X201463D01*
G01X198738Y458496D02*
X197905D01*
Y457746D01*
X198155Y457496D01*
X198446Y457329D01*
X198863Y457246D01*
X199280Y457329D01*
X199571Y457496D01*
X199821Y457746D01*
X199988Y458038D01*
X200071Y458371D01*
Y458663D01*
X199988Y458913D01*
X199821Y459204D01*
X199571Y459454D01*
X199321Y459621D01*
X198988Y459746D01*
X198696D01*
X198363Y459663D01*
X198113Y459496D01*
G01X195888Y457246D02*
Y459746D01*
X196388Y459246D01*
G01Y457246D02*
X195388D01*
G01X192788D02*
Y459746D01*
X193288Y459246D01*
G01Y457246D02*
X192288D01*
G01X189188D02*
Y459746D01*
X190730Y457954D01*
X188646D01*
G01X223941Y459775D02*
X224191Y459900D01*
X224483Y459983D01*
X224816D01*
X225191Y459858D01*
X225483Y459650D01*
X225691Y459400D01*
X225858Y458983D01*
X225900Y458608D01*
X225816Y458233D01*
X225691Y457983D01*
X225441Y457733D01*
X225150Y457566D01*
X224858Y457483D01*
X224566D01*
X224275Y457566D01*
X224025Y457691D01*
X223816Y457858D01*
G01X222675D02*
X222425Y457650D01*
X222133Y457525D01*
X221758Y457483D01*
X221383Y457566D01*
X221091Y457733D01*
X220883Y458025D01*
X220841Y458358D01*
X220925Y458691D01*
X221133Y458900D01*
X221425Y459066D01*
X221716Y459108D01*
X222008Y459066D01*
X222383Y458900D01*
X222258Y459983D01*
X221133D01*
G01X218408Y458733D02*
X217575D01*
Y457983D01*
X217825Y457733D01*
X218116Y457566D01*
X218533Y457483D01*
X218950Y457566D01*
X219241Y457733D01*
X219491Y457983D01*
X219658Y458275D01*
X219741Y458608D01*
Y458900D01*
X219658Y459150D01*
X219491Y459441D01*
X219241Y459691D01*
X218991Y459858D01*
X218658Y459983D01*
X218366D01*
X218033Y459900D01*
X217783Y459733D01*
G01X215558Y457483D02*
Y459983D01*
X216058Y459483D01*
G01Y457483D02*
X215058D01*
G01X212458D02*
Y459983D01*
X212958Y459483D01*
G01Y457483D02*
X211958D01*
G01X210275Y457983D02*
X210025Y457691D01*
X209691Y457525D01*
X209316Y457483D01*
X208983Y457525D01*
X208650Y457733D01*
X208441Y457983D01*
X208400Y458233D01*
X208483Y458525D01*
X208775Y458733D01*
X209066Y458816D01*
X209441D01*
G01X209066D02*
X208816Y458941D01*
X208608Y459150D01*
X208525Y459400D01*
X208608Y459650D01*
X208816Y459858D01*
X209191Y459983D01*
X209566Y459941D01*
X209941Y459775D01*
G01X243244D02*
X243494Y459900D01*
X243786Y459983D01*
X244119D01*
X244494Y459858D01*
X244786Y459650D01*
X244994Y459400D01*
X245161Y458983D01*
X245203Y458608D01*
X245119Y458233D01*
X244994Y457983D01*
X244744Y457733D01*
X244453Y457566D01*
X244161Y457483D01*
X243869D01*
X243578Y457566D01*
X243328Y457691D01*
X243119Y457858D01*
G01X241978D02*
X241728Y457650D01*
X241436Y457525D01*
X241061Y457483D01*
X240686Y457566D01*
X240394Y457733D01*
X240186Y458025D01*
X240144Y458358D01*
X240228Y458691D01*
X240436Y458900D01*
X240728Y459066D01*
X241019Y459108D01*
X241311Y459066D01*
X241686Y458900D01*
X241561Y459983D01*
X240436D01*
G01X237711Y458733D02*
X236878D01*
Y457983D01*
X237128Y457733D01*
X237419Y457566D01*
X237836Y457483D01*
X238253Y457566D01*
X238544Y457733D01*
X238794Y457983D01*
X238961Y458275D01*
X239044Y458608D01*
Y458900D01*
X238961Y459150D01*
X238794Y459441D01*
X238544Y459691D01*
X238294Y459858D01*
X237961Y459983D01*
X237669D01*
X237336Y459900D01*
X237086Y459733D01*
G01X234861Y457483D02*
Y459983D01*
X235361Y459483D01*
G01Y457483D02*
X234361D01*
G01X231761D02*
Y459983D01*
X232261Y459483D01*
G01Y457483D02*
X231261D01*
G01X229453Y459566D02*
X229203Y459816D01*
X228911Y459941D01*
X228578Y459983D01*
X228161Y459900D01*
X227869Y459691D01*
X227786Y459441D01*
X227828Y459191D01*
X227994Y458983D01*
X228828Y458566D01*
X229203Y458275D01*
X229453Y457858D01*
X229536Y457483D01*
X227786D01*
G01X204271Y467538D02*
X204521Y467663D01*
X204813Y467746D01*
X205146D01*
X205521Y467621D01*
X205813Y467413D01*
X206021Y467163D01*
X206188Y466746D01*
X206230Y466371D01*
X206146Y465996D01*
X206021Y465746D01*
X205771Y465496D01*
X205480Y465329D01*
X205188Y465246D01*
X204896D01*
X204605Y465329D01*
X204355Y465454D01*
X204146Y465621D01*
G01X203005D02*
X202755Y465413D01*
X202463Y465288D01*
X202088Y465246D01*
X201713Y465329D01*
X201421Y465496D01*
X201213Y465788D01*
X201171Y466121D01*
X201255Y466454D01*
X201463Y466663D01*
X201755Y466829D01*
X202046Y466871D01*
X202338Y466829D01*
X202713Y466663D01*
X202588Y467746D01*
X201463D01*
G01X198738Y466496D02*
X197905D01*
Y465746D01*
X198155Y465496D01*
X198446Y465329D01*
X198863Y465246D01*
X199280Y465329D01*
X199571Y465496D01*
X199821Y465746D01*
X199988Y466038D01*
X200071Y466371D01*
Y466663D01*
X199988Y466913D01*
X199821Y467204D01*
X199571Y467454D01*
X199321Y467621D01*
X198988Y467746D01*
X198696D01*
X198363Y467663D01*
X198113Y467496D01*
G01X195888Y465246D02*
Y467746D01*
X196388Y467246D01*
G01Y465246D02*
X195388D01*
G01X192788Y467746D02*
X193121Y467663D01*
X193371Y467454D01*
X193538Y467204D01*
X193663Y466871D01*
X193705Y466496D01*
X193663Y466121D01*
X193538Y465788D01*
X193371Y465538D01*
X193121Y465329D01*
X192788Y465246D01*
X192455Y465329D01*
X192205Y465538D01*
X192038Y465788D01*
X191913Y466121D01*
X191871Y466496D01*
X191913Y466871D01*
X192038Y467204D01*
X192205Y467454D01*
X192455Y467663D01*
X192788Y467746D01*
G01X189688Y465246D02*
Y467746D01*
X190188Y467246D01*
G01Y465246D02*
X189188D01*
G01X223941Y467775D02*
X224191Y467900D01*
X224483Y467983D01*
X224816D01*
X225191Y467858D01*
X225483Y467650D01*
X225691Y467400D01*
X225858Y466983D01*
X225900Y466608D01*
X225816Y466233D01*
X225691Y465983D01*
X225441Y465733D01*
X225150Y465566D01*
X224858Y465483D01*
X224566D01*
X224275Y465566D01*
X224025Y465691D01*
X223816Y465858D01*
G01X222675D02*
X222425Y465650D01*
X222133Y465525D01*
X221758Y465483D01*
X221383Y465566D01*
X221091Y465733D01*
X220883Y466025D01*
X220841Y466358D01*
X220925Y466691D01*
X221133Y466900D01*
X221425Y467066D01*
X221716Y467108D01*
X222008Y467066D01*
X222383Y466900D01*
X222258Y467983D01*
X221133D01*
G01X218408Y466733D02*
X217575D01*
Y465983D01*
X217825Y465733D01*
X218116Y465566D01*
X218533Y465483D01*
X218950Y465566D01*
X219241Y465733D01*
X219491Y465983D01*
X219658Y466275D01*
X219741Y466608D01*
Y466900D01*
X219658Y467150D01*
X219491Y467441D01*
X219241Y467691D01*
X218991Y467858D01*
X218658Y467983D01*
X218366D01*
X218033Y467900D01*
X217783Y467733D01*
G01X215558Y465483D02*
Y467983D01*
X216058Y467483D01*
G01Y465483D02*
X215058D01*
G01X212458Y467983D02*
X212791Y467900D01*
X213041Y467691D01*
X213208Y467441D01*
X213333Y467108D01*
X213375Y466733D01*
X213333Y466358D01*
X213208Y466025D01*
X213041Y465775D01*
X212791Y465566D01*
X212458Y465483D01*
X212125Y465566D01*
X211875Y465775D01*
X211708Y466025D01*
X211583Y466358D01*
X211541Y466733D01*
X211583Y467108D01*
X211708Y467441D01*
X211875Y467691D01*
X212125Y467900D01*
X212458Y467983D01*
G01X209358D02*
X209691Y467900D01*
X209941Y467691D01*
X210108Y467441D01*
X210233Y467108D01*
X210275Y466733D01*
X210233Y466358D01*
X210108Y466025D01*
X209941Y465775D01*
X209691Y465566D01*
X209358Y465483D01*
X209025Y465566D01*
X208775Y465775D01*
X208608Y466025D01*
X208483Y466358D01*
X208441Y466733D01*
X208483Y467108D01*
X208608Y467441D01*
X208775Y467691D01*
X209025Y467900D01*
X209358Y467983D01*
G01X243244Y467775D02*
X243494Y467900D01*
X243786Y467983D01*
X244119D01*
X244494Y467858D01*
X244786Y467650D01*
X244994Y467400D01*
X245161Y466983D01*
X245203Y466608D01*
X245119Y466233D01*
X244994Y465983D01*
X244744Y465733D01*
X244453Y465566D01*
X244161Y465483D01*
X243869D01*
X243578Y465566D01*
X243328Y465691D01*
X243119Y465858D01*
G01X241978D02*
X241728Y465650D01*
X241436Y465525D01*
X241061Y465483D01*
X240686Y465566D01*
X240394Y465733D01*
X240186Y466025D01*
X240144Y466358D01*
X240228Y466691D01*
X240436Y466900D01*
X240728Y467066D01*
X241019Y467108D01*
X241311Y467066D01*
X241686Y466900D01*
X241561Y467983D01*
X240436D01*
G01X237711Y466733D02*
X236878D01*
Y465983D01*
X237128Y465733D01*
X237419Y465566D01*
X237836Y465483D01*
X238253Y465566D01*
X238544Y465733D01*
X238794Y465983D01*
X238961Y466275D01*
X239044Y466608D01*
Y466900D01*
X238961Y467150D01*
X238794Y467441D01*
X238544Y467691D01*
X238294Y467858D01*
X237961Y467983D01*
X237669D01*
X237336Y467900D01*
X237086Y467733D01*
G01X235569Y465775D02*
X235278Y465566D01*
X234944Y465483D01*
X234611Y465566D01*
X234319Y465816D01*
X234111Y466191D01*
X234028Y466566D01*
Y467025D01*
X234111Y467400D01*
X234319Y467733D01*
X234569Y467900D01*
X234861Y467983D01*
X235194Y467900D01*
X235444Y467733D01*
X235611Y467483D01*
X235694Y467150D01*
X235611Y466858D01*
X235403Y466566D01*
X235153Y466400D01*
X234861Y466358D01*
X234528Y466441D01*
X234278Y466650D01*
X234028Y467025D01*
G01X232469Y465775D02*
X232178Y465566D01*
X231844Y465483D01*
X231511Y465566D01*
X231219Y465816D01*
X231011Y466191D01*
X230928Y466566D01*
Y467025D01*
X231011Y467400D01*
X231219Y467733D01*
X231469Y467900D01*
X231761Y467983D01*
X232094Y467900D01*
X232344Y467733D01*
X232511Y467483D01*
X232594Y467150D01*
X232511Y466858D01*
X232303Y466566D01*
X232053Y466400D01*
X231761Y466358D01*
X231428Y466441D01*
X231178Y466650D01*
X230928Y467025D01*
G01X204271Y455538D02*
X204521Y455663D01*
X204813Y455746D01*
X205146D01*
X205521Y455621D01*
X205813Y455413D01*
X206021Y455163D01*
X206188Y454746D01*
X206230Y454371D01*
X206146Y453996D01*
X206021Y453746D01*
X205771Y453496D01*
X205480Y453329D01*
X205188Y453246D01*
X204896D01*
X204605Y453329D01*
X204355Y453454D01*
X204146Y453621D01*
G01X202088Y453246D02*
X201796Y453288D01*
X201463Y453413D01*
X201255Y453621D01*
X201171Y453913D01*
X201255Y454204D01*
X201505Y454454D01*
X201880Y454579D01*
X202296D01*
X202546Y454663D01*
X202755Y454871D01*
X202838Y455163D01*
X202713Y455454D01*
X202421Y455663D01*
X202088Y455746D01*
X201755Y455663D01*
X201463Y455454D01*
X201338Y455163D01*
X201421Y454871D01*
X201630Y454663D01*
X201880Y454579D01*
X202296D01*
X202671Y454454D01*
X202921Y454204D01*
X203005Y453913D01*
X202921Y453621D01*
X202713Y453413D01*
X202380Y453288D01*
X202088Y453246D01*
G01X200071D02*
Y455746D01*
X198988Y453663D01*
X197905Y455746D01*
Y453246D01*
G01X196680Y454288D02*
X196388Y454579D01*
X196138Y454746D01*
X195805Y454829D01*
X195513Y454746D01*
X195305Y454579D01*
X195138Y454329D01*
X195096Y454038D01*
X195138Y453788D01*
X195305Y453538D01*
X195555Y453329D01*
X195846Y453246D01*
X196180Y453329D01*
X196471Y453579D01*
X196638Y453954D01*
X196680Y454371D01*
X196596Y454913D01*
X196471Y455204D01*
X196263Y455496D01*
X195971Y455704D01*
X195680Y455746D01*
X195388Y455663D01*
X195180Y455454D01*
G01X223941Y455775D02*
X224191Y455900D01*
X224483Y455983D01*
X224816D01*
X225191Y455858D01*
X225483Y455650D01*
X225691Y455400D01*
X225858Y454983D01*
X225900Y454608D01*
X225816Y454233D01*
X225691Y453983D01*
X225441Y453733D01*
X225150Y453566D01*
X224858Y453483D01*
X224566D01*
X224275Y453566D01*
X224025Y453691D01*
X223816Y453858D01*
G01X221758Y453483D02*
X221466Y453525D01*
X221133Y453650D01*
X220925Y453858D01*
X220841Y454150D01*
X220925Y454441D01*
X221175Y454691D01*
X221550Y454816D01*
X221966D01*
X222216Y454900D01*
X222425Y455108D01*
X222508Y455400D01*
X222383Y455691D01*
X222091Y455900D01*
X221758Y455983D01*
X221425Y455900D01*
X221133Y455691D01*
X221008Y455400D01*
X221091Y455108D01*
X221300Y454900D01*
X221550Y454816D01*
X221966D01*
X222341Y454691D01*
X222591Y454441D01*
X222675Y454150D01*
X222591Y453858D01*
X222383Y453650D01*
X222050Y453525D01*
X221758Y453483D01*
G01X219741D02*
Y455983D01*
X218658Y453900D01*
X217575Y455983D01*
Y453483D01*
G01X216475Y453858D02*
X216225Y453650D01*
X215933Y453525D01*
X215558Y453483D01*
X215183Y453566D01*
X214891Y453733D01*
X214683Y454025D01*
X214641Y454358D01*
X214725Y454691D01*
X214933Y454900D01*
X215225Y455066D01*
X215516Y455108D01*
X215808Y455066D01*
X216183Y454900D01*
X216058Y455983D01*
X214933D01*
G01X204271Y463538D02*
X204521Y463663D01*
X204813Y463746D01*
X205146D01*
X205521Y463621D01*
X205813Y463413D01*
X206021Y463163D01*
X206188Y462746D01*
X206230Y462371D01*
X206146Y461996D01*
X206021Y461746D01*
X205771Y461496D01*
X205480Y461329D01*
X205188Y461246D01*
X204896D01*
X204605Y461329D01*
X204355Y461454D01*
X204146Y461621D01*
G01X202088Y461246D02*
X201796Y461288D01*
X201463Y461413D01*
X201255Y461621D01*
X201171Y461913D01*
X201255Y462204D01*
X201505Y462454D01*
X201880Y462579D01*
X202296D01*
X202546Y462663D01*
X202755Y462871D01*
X202838Y463163D01*
X202713Y463454D01*
X202421Y463663D01*
X202088Y463746D01*
X201755Y463663D01*
X201463Y463454D01*
X201338Y463163D01*
X201421Y462871D01*
X201630Y462663D01*
X201880Y462579D01*
X202296D01*
X202671Y462454D01*
X202921Y462204D01*
X203005Y461913D01*
X202921Y461621D01*
X202713Y461413D01*
X202380Y461288D01*
X202088Y461246D01*
G01X199821Y463746D02*
Y461246D01*
X198155D01*
G01X195888D02*
Y463746D01*
X196388Y463246D01*
G01Y461246D02*
X195388D01*
G01X192788Y463746D02*
X193121Y463663D01*
X193371Y463454D01*
X193538Y463204D01*
X193663Y462871D01*
X193705Y462496D01*
X193663Y462121D01*
X193538Y461788D01*
X193371Y461538D01*
X193121Y461329D01*
X192788Y461246D01*
X192455Y461329D01*
X192205Y461538D01*
X192038Y461788D01*
X191913Y462121D01*
X191871Y462496D01*
X191913Y462871D01*
X192038Y463204D01*
X192205Y463454D01*
X192455Y463663D01*
X192788Y463746D01*
G01X223941Y463775D02*
X224191Y463900D01*
X224483Y463983D01*
X224816D01*
X225191Y463858D01*
X225483Y463650D01*
X225691Y463400D01*
X225858Y462983D01*
X225900Y462608D01*
X225816Y462233D01*
X225691Y461983D01*
X225441Y461733D01*
X225150Y461566D01*
X224858Y461483D01*
X224566D01*
X224275Y461566D01*
X224025Y461691D01*
X223816Y461858D01*
G01X221758Y461483D02*
X221466Y461525D01*
X221133Y461650D01*
X220925Y461858D01*
X220841Y462150D01*
X220925Y462441D01*
X221175Y462691D01*
X221550Y462816D01*
X221966D01*
X222216Y462900D01*
X222425Y463108D01*
X222508Y463400D01*
X222383Y463691D01*
X222091Y463900D01*
X221758Y463983D01*
X221425Y463900D01*
X221133Y463691D01*
X221008Y463400D01*
X221091Y463108D01*
X221300Y462900D01*
X221550Y462816D01*
X221966D01*
X222341Y462691D01*
X222591Y462441D01*
X222675Y462150D01*
X222591Y461858D01*
X222383Y461650D01*
X222050Y461525D01*
X221758Y461483D01*
G01X219491Y463983D02*
Y461483D01*
X217825D01*
G01X216266Y461775D02*
X215975Y461566D01*
X215641Y461483D01*
X215308Y461566D01*
X215016Y461816D01*
X214808Y462191D01*
X214725Y462566D01*
Y463025D01*
X214808Y463400D01*
X215016Y463733D01*
X215266Y463900D01*
X215558Y463983D01*
X215891Y463900D01*
X216141Y463733D01*
X216308Y463483D01*
X216391Y463150D01*
X216308Y462858D01*
X216100Y462566D01*
X215850Y462400D01*
X215558Y462358D01*
X215225Y462441D01*
X214975Y462650D01*
X214725Y463025D01*
G01X205500Y500500D02*
X208000Y498000D01*
X203000D01*
X205500Y500500D01*
Y470330D01*
G01X227582Y640370D02*
X260282D01*
Y659070D01*
X227582D01*
Y640370D01*
G01X225520Y659070D02*
X192820D01*
Y640370D01*
X225520D01*
Y659070D01*
G01X276170Y127100D02*
X318600D01*
G01X308405Y135235D02*
X308655Y135360D01*
X308947Y135443D01*
X309280D01*
X309655Y135318D01*
X309947Y135110D01*
X310155Y134860D01*
X310322Y134443D01*
X310364Y134068D01*
X310280Y133693D01*
X310155Y133443D01*
X309905Y133193D01*
X309614Y133026D01*
X309322Y132943D01*
X309030D01*
X308739Y133026D01*
X308489Y133151D01*
X308280Y133318D01*
G01X307139D02*
X306889Y133110D01*
X306597Y132985D01*
X306222Y132943D01*
X305847Y133026D01*
X305555Y133193D01*
X305347Y133485D01*
X305305Y133818D01*
X305389Y134151D01*
X305597Y134360D01*
X305889Y134526D01*
X306180Y134568D01*
X306472Y134526D01*
X306847Y134360D01*
X306722Y135443D01*
X305597D01*
G01X302872Y134193D02*
X302039D01*
Y133443D01*
X302289Y133193D01*
X302580Y133026D01*
X302997Y132943D01*
X303414Y133026D01*
X303705Y133193D01*
X303955Y133443D01*
X304122Y133735D01*
X304205Y134068D01*
Y134360D01*
X304122Y134610D01*
X303955Y134901D01*
X303705Y135151D01*
X303455Y135318D01*
X303122Y135443D01*
X302830D01*
X302497Y135360D01*
X302247Y135193D01*
G01X300022Y132943D02*
Y135443D01*
X300522Y134943D01*
G01Y132943D02*
X299522D01*
G01X296922D02*
Y135443D01*
X297422Y134943D01*
G01Y132943D02*
X296422D01*
G01X293905D02*
X293822Y133485D01*
X293697Y133943D01*
X293530Y134360D01*
X293322Y134818D01*
X292989Y135443D01*
X294655D01*
G01X308475Y143235D02*
X308725Y143360D01*
X309017Y143443D01*
X309350D01*
X309725Y143318D01*
X310017Y143110D01*
X310225Y142860D01*
X310392Y142443D01*
X310434Y142068D01*
X310350Y141693D01*
X310225Y141443D01*
X309975Y141193D01*
X309684Y141026D01*
X309392Y140943D01*
X309100D01*
X308809Y141026D01*
X308559Y141151D01*
X308350Y141318D01*
G01X307209D02*
X306959Y141110D01*
X306667Y140985D01*
X306292Y140943D01*
X305917Y141026D01*
X305625Y141193D01*
X305417Y141485D01*
X305375Y141818D01*
X305459Y142151D01*
X305667Y142360D01*
X305959Y142526D01*
X306250Y142568D01*
X306542Y142526D01*
X306917Y142360D01*
X306792Y143443D01*
X305667D01*
G01X302942Y142193D02*
X302109D01*
Y141443D01*
X302359Y141193D01*
X302650Y141026D01*
X303067Y140943D01*
X303484Y141026D01*
X303775Y141193D01*
X304025Y141443D01*
X304192Y141735D01*
X304275Y142068D01*
Y142360D01*
X304192Y142610D01*
X304025Y142901D01*
X303775Y143151D01*
X303525Y143318D01*
X303192Y143443D01*
X302900D01*
X302567Y143360D01*
X302317Y143193D01*
G01X300092Y140943D02*
Y143443D01*
X300592Y142943D01*
G01Y140943D02*
X299592D01*
G01X296992D02*
Y143443D01*
X297492Y142943D01*
G01Y140943D02*
X296492D01*
G01X293892D02*
X293600Y140985D01*
X293267Y141110D01*
X293059Y141318D01*
X292975Y141610D01*
X293059Y141901D01*
X293309Y142151D01*
X293684Y142276D01*
X294100D01*
X294350Y142360D01*
X294559Y142568D01*
X294642Y142860D01*
X294517Y143151D01*
X294225Y143360D01*
X293892Y143443D01*
X293559Y143360D01*
X293267Y143151D01*
X293142Y142860D01*
X293225Y142568D01*
X293434Y142360D01*
X293684Y142276D01*
X294100D01*
X294475Y142151D01*
X294725Y141901D01*
X294809Y141610D01*
X294725Y141318D01*
X294517Y141110D01*
X294184Y140985D01*
X293892Y140943D01*
G01X271792Y136300D02*
X272042Y136425D01*
X272334Y136508D01*
X272667D01*
X273042Y136383D01*
X273334Y136175D01*
X273542Y135925D01*
X273709Y135508D01*
X273751Y135133D01*
X273667Y134758D01*
X273542Y134508D01*
X273292Y134258D01*
X273001Y134091D01*
X272709Y134008D01*
X272417D01*
X272126Y134091D01*
X271876Y134216D01*
X271667Y134383D01*
G01X270526D02*
X270276Y134175D01*
X269984Y134050D01*
X269609Y134008D01*
X269234Y134091D01*
X268942Y134258D01*
X268734Y134550D01*
X268692Y134883D01*
X268776Y135216D01*
X268984Y135425D01*
X269276Y135591D01*
X269567Y135633D01*
X269859Y135591D01*
X270234Y135425D01*
X270109Y136508D01*
X268984D01*
G01X266259Y135258D02*
X265426D01*
Y134508D01*
X265676Y134258D01*
X265967Y134091D01*
X266384Y134008D01*
X266801Y134091D01*
X267092Y134258D01*
X267342Y134508D01*
X267509Y134800D01*
X267592Y135133D01*
Y135425D01*
X267509Y135675D01*
X267342Y135966D01*
X267092Y136216D01*
X266842Y136383D01*
X266509Y136508D01*
X266217D01*
X265884Y136425D01*
X265634Y136258D01*
G01X263409Y134008D02*
X263117Y134050D01*
X262784Y134175D01*
X262576Y134383D01*
X262492Y134675D01*
X262576Y134966D01*
X262826Y135216D01*
X263201Y135341D01*
X263617D01*
X263867Y135425D01*
X264076Y135633D01*
X264159Y135925D01*
X264034Y136216D01*
X263742Y136425D01*
X263409Y136508D01*
X263076Y136425D01*
X262784Y136216D01*
X262659Y135925D01*
X262742Y135633D01*
X262951Y135425D01*
X263201Y135341D01*
X263617D01*
X263992Y135216D01*
X264242Y134966D01*
X264326Y134675D01*
X264242Y134383D01*
X264034Y134175D01*
X263701Y134050D01*
X263409Y134008D01*
G01X261226Y134383D02*
X260976Y134175D01*
X260684Y134050D01*
X260309Y134008D01*
X259934Y134091D01*
X259642Y134258D01*
X259434Y134550D01*
X259392Y134883D01*
X259476Y135216D01*
X259684Y135425D01*
X259976Y135591D01*
X260267Y135633D01*
X260559Y135591D01*
X260934Y135425D01*
X260809Y136508D01*
X259684D01*
G01X288865Y143589D02*
X289115Y143714D01*
X289407Y143797D01*
X289740D01*
X290115Y143672D01*
X290407Y143464D01*
X290615Y143214D01*
X290782Y142797D01*
X290824Y142422D01*
X290740Y142047D01*
X290615Y141797D01*
X290365Y141547D01*
X290074Y141380D01*
X289782Y141297D01*
X289490D01*
X289199Y141380D01*
X288949Y141505D01*
X288740Y141672D01*
G01X287599D02*
X287349Y141464D01*
X287057Y141339D01*
X286682Y141297D01*
X286307Y141380D01*
X286015Y141547D01*
X285807Y141839D01*
X285765Y142172D01*
X285849Y142505D01*
X286057Y142714D01*
X286349Y142880D01*
X286640Y142922D01*
X286932Y142880D01*
X287307Y142714D01*
X287182Y143797D01*
X286057D01*
G01X283332Y142547D02*
X282499D01*
Y141797D01*
X282749Y141547D01*
X283040Y141380D01*
X283457Y141297D01*
X283874Y141380D01*
X284165Y141547D01*
X284415Y141797D01*
X284582Y142089D01*
X284665Y142422D01*
Y142714D01*
X284582Y142964D01*
X284415Y143255D01*
X284165Y143505D01*
X283915Y143672D01*
X283582Y143797D01*
X283290D01*
X282957Y143714D01*
X282707Y143547D01*
G01X280482Y141297D02*
X280190Y141339D01*
X279857Y141464D01*
X279649Y141672D01*
X279565Y141964D01*
X279649Y142255D01*
X279899Y142505D01*
X280274Y142630D01*
X280690D01*
X280940Y142714D01*
X281149Y142922D01*
X281232Y143214D01*
X281107Y143505D01*
X280815Y143714D01*
X280482Y143797D01*
X280149Y143714D01*
X279857Y143505D01*
X279732Y143214D01*
X279815Y142922D01*
X280024Y142714D01*
X280274Y142630D01*
X280690D01*
X281065Y142505D01*
X281315Y142255D01*
X281399Y141964D01*
X281315Y141672D01*
X281107Y141464D01*
X280774Y141339D01*
X280482Y141297D01*
G01X278299Y141797D02*
X278049Y141505D01*
X277715Y141339D01*
X277340Y141297D01*
X277007Y141339D01*
X276674Y141547D01*
X276465Y141797D01*
X276424Y142047D01*
X276507Y142339D01*
X276799Y142547D01*
X277090Y142630D01*
X277465D01*
G01X277090D02*
X276840Y142755D01*
X276632Y142964D01*
X276549Y143214D01*
X276632Y143464D01*
X276840Y143672D01*
X277215Y143797D01*
X277590Y143755D01*
X277965Y143589D01*
G01X288615Y135589D02*
X288865Y135714D01*
X289157Y135797D01*
X289490D01*
X289865Y135672D01*
X290157Y135464D01*
X290365Y135214D01*
X290532Y134797D01*
X290574Y134422D01*
X290490Y134047D01*
X290365Y133797D01*
X290115Y133547D01*
X289824Y133380D01*
X289532Y133297D01*
X289240D01*
X288949Y133380D01*
X288699Y133505D01*
X288490Y133672D01*
G01X287349D02*
X287099Y133464D01*
X286807Y133339D01*
X286432Y133297D01*
X286057Y133380D01*
X285765Y133547D01*
X285557Y133839D01*
X285515Y134172D01*
X285599Y134505D01*
X285807Y134714D01*
X286099Y134880D01*
X286390Y134922D01*
X286682Y134880D01*
X287057Y134714D01*
X286932Y135797D01*
X285807D01*
G01X283082Y134547D02*
X282249D01*
Y133797D01*
X282499Y133547D01*
X282790Y133380D01*
X283207Y133297D01*
X283624Y133380D01*
X283915Y133547D01*
X284165Y133797D01*
X284332Y134089D01*
X284415Y134422D01*
Y134714D01*
X284332Y134964D01*
X284165Y135255D01*
X283915Y135505D01*
X283665Y135672D01*
X283332Y135797D01*
X283040D01*
X282707Y135714D01*
X282457Y135547D01*
G01X280232Y133297D02*
X279940Y133339D01*
X279607Y133464D01*
X279399Y133672D01*
X279315Y133964D01*
X279399Y134255D01*
X279649Y134505D01*
X280024Y134630D01*
X280440D01*
X280690Y134714D01*
X280899Y134922D01*
X280982Y135214D01*
X280857Y135505D01*
X280565Y135714D01*
X280232Y135797D01*
X279899Y135714D01*
X279607Y135505D01*
X279482Y135214D01*
X279565Y134922D01*
X279774Y134714D01*
X280024Y134630D01*
X280440D01*
X280815Y134505D01*
X281065Y134255D01*
X281149Y133964D01*
X281065Y133672D01*
X280857Y133464D01*
X280524Y133339D01*
X280232Y133297D01*
G01X276632D02*
Y135797D01*
X278174Y134005D01*
X276090D01*
G01X271792Y144300D02*
X272042Y144425D01*
X272334Y144508D01*
X272667D01*
X273042Y144383D01*
X273334Y144175D01*
X273542Y143925D01*
X273709Y143508D01*
X273751Y143133D01*
X273667Y142758D01*
X273542Y142508D01*
X273292Y142258D01*
X273001Y142091D01*
X272709Y142008D01*
X272417D01*
X272126Y142091D01*
X271876Y142216D01*
X271667Y142383D01*
G01X270526D02*
X270276Y142175D01*
X269984Y142050D01*
X269609Y142008D01*
X269234Y142091D01*
X268942Y142258D01*
X268734Y142550D01*
X268692Y142883D01*
X268776Y143216D01*
X268984Y143425D01*
X269276Y143591D01*
X269567Y143633D01*
X269859Y143591D01*
X270234Y143425D01*
X270109Y144508D01*
X268984D01*
G01X266259Y143258D02*
X265426D01*
Y142508D01*
X265676Y142258D01*
X265967Y142091D01*
X266384Y142008D01*
X266801Y142091D01*
X267092Y142258D01*
X267342Y142508D01*
X267509Y142800D01*
X267592Y143133D01*
Y143425D01*
X267509Y143675D01*
X267342Y143966D01*
X267092Y144216D01*
X266842Y144383D01*
X266509Y144508D01*
X266217D01*
X265884Y144425D01*
X265634Y144258D01*
G01X263409Y142008D02*
X263117Y142050D01*
X262784Y142175D01*
X262576Y142383D01*
X262492Y142675D01*
X262576Y142966D01*
X262826Y143216D01*
X263201Y143341D01*
X263617D01*
X263867Y143425D01*
X264076Y143633D01*
X264159Y143925D01*
X264034Y144216D01*
X263742Y144425D01*
X263409Y144508D01*
X263076Y144425D01*
X262784Y144216D01*
X262659Y143925D01*
X262742Y143633D01*
X262951Y143425D01*
X263201Y143341D01*
X263617D01*
X263992Y143216D01*
X264242Y142966D01*
X264326Y142675D01*
X264242Y142383D01*
X264034Y142175D01*
X263701Y142050D01*
X263409Y142008D01*
G01X261101Y144091D02*
X260851Y144341D01*
X260559Y144466D01*
X260226Y144508D01*
X259809Y144425D01*
X259517Y144216D01*
X259434Y143966D01*
X259476Y143716D01*
X259642Y143508D01*
X260476Y143091D01*
X260851Y142800D01*
X261101Y142383D01*
X261184Y142008D01*
X259434D01*
G01X254019Y136774D02*
X254269Y136899D01*
X254561Y136982D01*
X254894D01*
X255269Y136857D01*
X255561Y136649D01*
X255769Y136399D01*
X255936Y135982D01*
X255978Y135607D01*
X255894Y135232D01*
X255769Y134982D01*
X255519Y134732D01*
X255228Y134565D01*
X254936Y134482D01*
X254644D01*
X254353Y134565D01*
X254103Y134690D01*
X253894Y134857D01*
G01X252753D02*
X252503Y134649D01*
X252211Y134524D01*
X251836Y134482D01*
X251461Y134565D01*
X251169Y134732D01*
X250961Y135024D01*
X250919Y135357D01*
X251003Y135690D01*
X251211Y135899D01*
X251503Y136065D01*
X251794Y136107D01*
X252086Y136065D01*
X252461Y135899D01*
X252336Y136982D01*
X251211D01*
G01X248486Y135732D02*
X247653D01*
Y134982D01*
X247903Y134732D01*
X248194Y134565D01*
X248611Y134482D01*
X249028Y134565D01*
X249319Y134732D01*
X249569Y134982D01*
X249736Y135274D01*
X249819Y135607D01*
Y135899D01*
X249736Y136149D01*
X249569Y136440D01*
X249319Y136690D01*
X249069Y136857D01*
X248736Y136982D01*
X248444D01*
X248111Y136899D01*
X247861Y136732D01*
G01X245636Y134482D02*
X245344Y134524D01*
X245011Y134649D01*
X244803Y134857D01*
X244719Y135149D01*
X244803Y135440D01*
X245053Y135690D01*
X245428Y135815D01*
X245844D01*
X246094Y135899D01*
X246303Y136107D01*
X246386Y136399D01*
X246261Y136690D01*
X245969Y136899D01*
X245636Y136982D01*
X245303Y136899D01*
X245011Y136690D01*
X244886Y136399D01*
X244969Y136107D01*
X245178Y135899D01*
X245428Y135815D01*
X245844D01*
X246219Y135690D01*
X246469Y135440D01*
X246553Y135149D01*
X246469Y134857D01*
X246261Y134649D01*
X245928Y134524D01*
X245636Y134482D01*
G01X243328Y135524D02*
X243036Y135815D01*
X242786Y135982D01*
X242453Y136065D01*
X242161Y135982D01*
X241953Y135815D01*
X241786Y135565D01*
X241744Y135274D01*
X241786Y135024D01*
X241953Y134774D01*
X242203Y134565D01*
X242494Y134482D01*
X242828Y134565D01*
X243119Y134815D01*
X243286Y135190D01*
X243328Y135607D01*
X243244Y136149D01*
X243119Y136440D01*
X242911Y136732D01*
X242619Y136940D01*
X242328Y136982D01*
X242036Y136899D01*
X241828Y136690D01*
G01X254019Y144774D02*
X254269Y144899D01*
X254561Y144982D01*
X254894D01*
X255269Y144857D01*
X255561Y144649D01*
X255769Y144399D01*
X255936Y143982D01*
X255978Y143607D01*
X255894Y143232D01*
X255769Y142982D01*
X255519Y142732D01*
X255228Y142565D01*
X254936Y142482D01*
X254644D01*
X254353Y142565D01*
X254103Y142690D01*
X253894Y142857D01*
G01X252753D02*
X252503Y142649D01*
X252211Y142524D01*
X251836Y142482D01*
X251461Y142565D01*
X251169Y142732D01*
X250961Y143024D01*
X250919Y143357D01*
X251003Y143690D01*
X251211Y143899D01*
X251503Y144065D01*
X251794Y144107D01*
X252086Y144065D01*
X252461Y143899D01*
X252336Y144982D01*
X251211D01*
G01X248486Y143732D02*
X247653D01*
Y142982D01*
X247903Y142732D01*
X248194Y142565D01*
X248611Y142482D01*
X249028Y142565D01*
X249319Y142732D01*
X249569Y142982D01*
X249736Y143274D01*
X249819Y143607D01*
Y143899D01*
X249736Y144149D01*
X249569Y144440D01*
X249319Y144690D01*
X249069Y144857D01*
X248736Y144982D01*
X248444D01*
X248111Y144899D01*
X247861Y144732D01*
G01X245636Y142482D02*
X245344Y142524D01*
X245011Y142649D01*
X244803Y142857D01*
X244719Y143149D01*
X244803Y143440D01*
X245053Y143690D01*
X245428Y143815D01*
X245844D01*
X246094Y143899D01*
X246303Y144107D01*
X246386Y144399D01*
X246261Y144690D01*
X245969Y144899D01*
X245636Y144982D01*
X245303Y144899D01*
X245011Y144690D01*
X244886Y144399D01*
X244969Y144107D01*
X245178Y143899D01*
X245428Y143815D01*
X245844D01*
X246219Y143690D01*
X246469Y143440D01*
X246553Y143149D01*
X246469Y142857D01*
X246261Y142649D01*
X245928Y142524D01*
X245636Y142482D01*
G01X242536D02*
Y144982D01*
X243036Y144482D01*
G01Y142482D02*
X242036D01*
G01X288865Y147589D02*
X289115Y147714D01*
X289407Y147797D01*
X289740D01*
X290115Y147672D01*
X290407Y147464D01*
X290615Y147214D01*
X290782Y146797D01*
X290824Y146422D01*
X290740Y146047D01*
X290615Y145797D01*
X290365Y145547D01*
X290074Y145380D01*
X289782Y145297D01*
X289490D01*
X289199Y145380D01*
X288949Y145505D01*
X288740Y145672D01*
G01X286682Y145297D02*
X286390Y145339D01*
X286057Y145464D01*
X285849Y145672D01*
X285765Y145964D01*
X285849Y146255D01*
X286099Y146505D01*
X286474Y146630D01*
X286890D01*
X287140Y146714D01*
X287349Y146922D01*
X287432Y147214D01*
X287307Y147505D01*
X287015Y147714D01*
X286682Y147797D01*
X286349Y147714D01*
X286057Y147505D01*
X285932Y147214D01*
X286015Y146922D01*
X286224Y146714D01*
X286474Y146630D01*
X286890D01*
X287265Y146505D01*
X287515Y146255D01*
X287599Y145964D01*
X287515Y145672D01*
X287307Y145464D01*
X286974Y145339D01*
X286682Y145297D01*
G01X283582Y147797D02*
Y145297D01*
G01X284540Y147797D02*
X282624D01*
G01X280482Y145297D02*
Y147797D01*
X280982Y147297D01*
G01Y145297D02*
X279982D01*
G01X277382D02*
Y147797D01*
X277882Y147297D01*
G01Y145297D02*
X276882D01*
G01X288865Y139589D02*
X289115Y139714D01*
X289407Y139797D01*
X289740D01*
X290115Y139672D01*
X290407Y139464D01*
X290615Y139214D01*
X290782Y138797D01*
X290824Y138422D01*
X290740Y138047D01*
X290615Y137797D01*
X290365Y137547D01*
X290074Y137380D01*
X289782Y137297D01*
X289490D01*
X289199Y137380D01*
X288949Y137505D01*
X288740Y137672D01*
G01X286682Y137297D02*
X286390Y137339D01*
X286057Y137464D01*
X285849Y137672D01*
X285765Y137964D01*
X285849Y138255D01*
X286099Y138505D01*
X286474Y138630D01*
X286890D01*
X287140Y138714D01*
X287349Y138922D01*
X287432Y139214D01*
X287307Y139505D01*
X287015Y139714D01*
X286682Y139797D01*
X286349Y139714D01*
X286057Y139505D01*
X285932Y139214D01*
X286015Y138922D01*
X286224Y138714D01*
X286474Y138630D01*
X286890D01*
X287265Y138505D01*
X287515Y138255D01*
X287599Y137964D01*
X287515Y137672D01*
X287307Y137464D01*
X286974Y137339D01*
X286682Y137297D01*
G01X284499Y139797D02*
Y138005D01*
X284332Y137630D01*
X283999Y137380D01*
X283582Y137297D01*
X283165Y137380D01*
X282832Y137630D01*
X282665Y138005D01*
Y139797D01*
G01X281190Y137589D02*
X280899Y137380D01*
X280565Y137297D01*
X280232Y137380D01*
X279940Y137630D01*
X279732Y138005D01*
X279649Y138380D01*
Y138839D01*
X279732Y139214D01*
X279940Y139547D01*
X280190Y139714D01*
X280482Y139797D01*
X280815Y139714D01*
X281065Y139547D01*
X281232Y139297D01*
X281315Y138964D01*
X281232Y138672D01*
X281024Y138380D01*
X280774Y138214D01*
X280482Y138172D01*
X280149Y138255D01*
X279899Y138464D01*
X279649Y138839D01*
G01X254019Y140774D02*
X254269Y140899D01*
X254561Y140982D01*
X254894D01*
X255269Y140857D01*
X255561Y140649D01*
X255769Y140399D01*
X255936Y139982D01*
X255978Y139607D01*
X255894Y139232D01*
X255769Y138982D01*
X255519Y138732D01*
X255228Y138565D01*
X254936Y138482D01*
X254644D01*
X254353Y138565D01*
X254103Y138690D01*
X253894Y138857D01*
G01X251836Y138482D02*
X251544Y138524D01*
X251211Y138649D01*
X251003Y138857D01*
X250919Y139149D01*
X251003Y139440D01*
X251253Y139690D01*
X251628Y139815D01*
X252044D01*
X252294Y139899D01*
X252503Y140107D01*
X252586Y140399D01*
X252461Y140690D01*
X252169Y140899D01*
X251836Y140982D01*
X251503Y140899D01*
X251211Y140690D01*
X251086Y140399D01*
X251169Y140107D01*
X251378Y139899D01*
X251628Y139815D01*
X252044D01*
X252419Y139690D01*
X252669Y139440D01*
X252753Y139149D01*
X252669Y138857D01*
X252461Y138649D01*
X252128Y138524D01*
X251836Y138482D01*
G01X249653Y140982D02*
Y139190D01*
X249486Y138815D01*
X249153Y138565D01*
X248736Y138482D01*
X248319Y138565D01*
X247986Y138815D01*
X247819Y139190D01*
Y140982D01*
G01X246553Y138857D02*
X246303Y138649D01*
X246011Y138524D01*
X245636Y138482D01*
X245261Y138565D01*
X244969Y138732D01*
X244761Y139024D01*
X244719Y139357D01*
X244803Y139690D01*
X245011Y139899D01*
X245303Y140065D01*
X245594Y140107D01*
X245886Y140065D01*
X246261Y139899D01*
X246136Y140982D01*
X245011D01*
G01X271792Y140300D02*
X272042Y140425D01*
X272334Y140508D01*
X272667D01*
X273042Y140383D01*
X273334Y140175D01*
X273542Y139925D01*
X273709Y139508D01*
X273751Y139133D01*
X273667Y138758D01*
X273542Y138508D01*
X273292Y138258D01*
X273001Y138091D01*
X272709Y138008D01*
X272417D01*
X272126Y138091D01*
X271876Y138216D01*
X271667Y138383D01*
G01X269609Y138008D02*
X269317Y138050D01*
X268984Y138175D01*
X268776Y138383D01*
X268692Y138675D01*
X268776Y138966D01*
X269026Y139216D01*
X269401Y139341D01*
X269817D01*
X270067Y139425D01*
X270276Y139633D01*
X270359Y139925D01*
X270234Y140216D01*
X269942Y140425D01*
X269609Y140508D01*
X269276Y140425D01*
X268984Y140216D01*
X268859Y139925D01*
X268942Y139633D01*
X269151Y139425D01*
X269401Y139341D01*
X269817D01*
X270192Y139216D01*
X270442Y138966D01*
X270526Y138675D01*
X270442Y138383D01*
X270234Y138175D01*
X269901Y138050D01*
X269609Y138008D01*
G01X267426Y140508D02*
Y138716D01*
X267259Y138341D01*
X266926Y138091D01*
X266509Y138008D01*
X266092Y138091D01*
X265759Y138341D01*
X265592Y138716D01*
Y140508D01*
G01X262909Y138008D02*
Y140508D01*
X264451Y138716D01*
X262367D01*
G01X254019Y148774D02*
X254269Y148899D01*
X254561Y148982D01*
X254894D01*
X255269Y148857D01*
X255561Y148649D01*
X255769Y148399D01*
X255936Y147982D01*
X255978Y147607D01*
X255894Y147232D01*
X255769Y146982D01*
X255519Y146732D01*
X255228Y146565D01*
X254936Y146482D01*
X254644D01*
X254353Y146565D01*
X254103Y146690D01*
X253894Y146857D01*
G01X251836Y146482D02*
X251544Y146524D01*
X251211Y146649D01*
X251003Y146857D01*
X250919Y147149D01*
X251003Y147440D01*
X251253Y147690D01*
X251628Y147815D01*
X252044D01*
X252294Y147899D01*
X252503Y148107D01*
X252586Y148399D01*
X252461Y148690D01*
X252169Y148899D01*
X251836Y148982D01*
X251503Y148899D01*
X251211Y148690D01*
X251086Y148399D01*
X251169Y148107D01*
X251378Y147899D01*
X251628Y147815D01*
X252044D01*
X252419Y147690D01*
X252669Y147440D01*
X252753Y147149D01*
X252669Y146857D01*
X252461Y146649D01*
X252128Y146524D01*
X251836Y146482D01*
G01X248736Y148982D02*
Y146482D01*
G01X249694Y148982D02*
X247778D01*
G01X245636Y146482D02*
X245344Y146524D01*
X245011Y146649D01*
X244803Y146857D01*
X244719Y147149D01*
X244803Y147440D01*
X245053Y147690D01*
X245428Y147815D01*
X245844D01*
X246094Y147899D01*
X246303Y148107D01*
X246386Y148399D01*
X246261Y148690D01*
X245969Y148899D01*
X245636Y148982D01*
X245303Y148899D01*
X245011Y148690D01*
X244886Y148399D01*
X244969Y148107D01*
X245178Y147899D01*
X245428Y147815D01*
X245844D01*
X246219Y147690D01*
X246469Y147440D01*
X246553Y147149D01*
X246469Y146857D01*
X246261Y146649D01*
X245928Y146524D01*
X245636Y146482D01*
G01X271792Y148300D02*
X272042Y148425D01*
X272334Y148508D01*
X272667D01*
X273042Y148383D01*
X273334Y148175D01*
X273542Y147925D01*
X273709Y147508D01*
X273751Y147133D01*
X273667Y146758D01*
X273542Y146508D01*
X273292Y146258D01*
X273001Y146091D01*
X272709Y146008D01*
X272417D01*
X272126Y146091D01*
X271876Y146216D01*
X271667Y146383D01*
G01X269609Y146008D02*
X269317Y146050D01*
X268984Y146175D01*
X268776Y146383D01*
X268692Y146675D01*
X268776Y146966D01*
X269026Y147216D01*
X269401Y147341D01*
X269817D01*
X270067Y147425D01*
X270276Y147633D01*
X270359Y147925D01*
X270234Y148216D01*
X269942Y148425D01*
X269609Y148508D01*
X269276Y148425D01*
X268984Y148216D01*
X268859Y147925D01*
X268942Y147633D01*
X269151Y147425D01*
X269401Y147341D01*
X269817D01*
X270192Y147216D01*
X270442Y146966D01*
X270526Y146675D01*
X270442Y146383D01*
X270234Y146175D01*
X269901Y146050D01*
X269609Y146008D01*
G01X266509Y148508D02*
Y146008D01*
G01X267467Y148508D02*
X265551D01*
G01X263492Y146008D02*
X263409Y146550D01*
X263284Y147008D01*
X263117Y147425D01*
X262909Y147883D01*
X262576Y148508D01*
X264242D01*
G01X262533Y244850D02*
Y247350D01*
X261492D01*
X261158Y247225D01*
X260950Y247058D01*
X260867Y246725D01*
X260950Y246392D01*
X261200Y246183D01*
X261492Y246058D01*
X262533D01*
G01X261492D02*
X260867Y244850D01*
G01X258600D02*
X258308Y244892D01*
X257975Y245017D01*
X257767Y245225D01*
X257683Y245517D01*
X257767Y245808D01*
X258017Y246058D01*
X258392Y246183D01*
X258808D01*
X259058Y246267D01*
X259267Y246475D01*
X259350Y246767D01*
X259225Y247058D01*
X258933Y247267D01*
X258600Y247350D01*
X258267Y247267D01*
X257975Y247058D01*
X257850Y246767D01*
X257933Y246475D01*
X258142Y246267D01*
X258392Y246183D01*
X258808D01*
X259183Y246058D01*
X259433Y245808D01*
X259517Y245517D01*
X259433Y245225D01*
X259225Y245017D01*
X258892Y244892D01*
X258600Y244850D01*
G01X256333D02*
Y247350D01*
X255292D01*
X254958Y247225D01*
X254750Y247058D01*
X254667Y246725D01*
X254750Y246392D01*
X255000Y246183D01*
X255292Y246058D01*
X256333D01*
G01X255292D02*
X254667Y244850D01*
G01X252400D02*
Y247350D01*
X252900Y246850D01*
G01Y244850D02*
X251900D01*
G01X262633Y248800D02*
Y251300D01*
X261592D01*
X261258Y251175D01*
X261050Y251008D01*
X260967Y250675D01*
X261050Y250342D01*
X261300Y250133D01*
X261592Y250008D01*
X262633D01*
G01X261592D02*
X260967Y248800D01*
G01X258700D02*
X258408Y248842D01*
X258075Y248967D01*
X257867Y249175D01*
X257783Y249467D01*
X257867Y249758D01*
X258117Y250008D01*
X258492Y250133D01*
X258908D01*
X259158Y250217D01*
X259367Y250425D01*
X259450Y250717D01*
X259325Y251008D01*
X259033Y251217D01*
X258700Y251300D01*
X258367Y251217D01*
X258075Y251008D01*
X257950Y250717D01*
X258033Y250425D01*
X258242Y250217D01*
X258492Y250133D01*
X258908D01*
X259283Y250008D01*
X259533Y249758D01*
X259617Y249467D01*
X259533Y249175D01*
X259325Y248967D01*
X258992Y248842D01*
X258700Y248800D01*
G01X256433D02*
Y251300D01*
X255433D01*
X255100Y251175D01*
X254850Y250883D01*
X254767Y250550D01*
X254850Y250217D01*
X255058Y249967D01*
X255433Y249842D01*
X256433D01*
G01X253417Y249300D02*
X253167Y249008D01*
X252833Y248842D01*
X252458Y248800D01*
X252125Y248842D01*
X251792Y249050D01*
X251583Y249300D01*
X251542Y249550D01*
X251625Y249842D01*
X251917Y250050D01*
X252208Y250133D01*
X252583D01*
G01X252208D02*
X251958Y250258D01*
X251750Y250467D01*
X251667Y250717D01*
X251750Y250967D01*
X251958Y251175D01*
X252333Y251300D01*
X252708Y251258D01*
X253083Y251092D01*
G01X251700Y261167D02*
X254200D01*
Y262208D01*
X254075Y262542D01*
X253908Y262750D01*
X253575Y262833D01*
X253242Y262750D01*
X253033Y262500D01*
X252908Y262208D01*
Y261167D01*
G01Y262208D02*
X251700Y262833D01*
G01Y265100D02*
X254200D01*
X253700Y264600D01*
G01X251700D02*
Y265600D01*
G01Y269033D02*
Y267367D01*
X254200D01*
Y269033D01*
G01X252992Y268367D02*
Y267367D01*
G01X251700Y271300D02*
X251742Y271592D01*
X251867Y271925D01*
X252075Y272133D01*
X252367Y272217D01*
X252658Y272133D01*
X252908Y271883D01*
X253033Y271508D01*
Y271092D01*
X253117Y270842D01*
X253325Y270633D01*
X253617Y270550D01*
X253908Y270675D01*
X254117Y270967D01*
X254200Y271300D01*
X254117Y271633D01*
X253908Y271925D01*
X253617Y272050D01*
X253325Y271967D01*
X253117Y271758D01*
X253033Y271508D01*
Y271092D01*
X252908Y270717D01*
X252658Y270467D01*
X252367Y270383D01*
X252075Y270467D01*
X251867Y270675D01*
X251742Y271008D01*
X251700Y271300D01*
G01X247700Y261167D02*
X250200D01*
Y262208D01*
X250075Y262542D01*
X249908Y262750D01*
X249575Y262833D01*
X249242Y262750D01*
X249033Y262500D01*
X248908Y262208D01*
Y261167D01*
G01Y262208D02*
X247700Y262833D01*
G01Y265100D02*
X250200D01*
X249700Y264600D01*
G01X247700D02*
Y265600D01*
G01Y269033D02*
Y267367D01*
X250200D01*
Y269033D01*
G01X248992Y268367D02*
Y267367D01*
G01X247700Y271800D02*
X250200D01*
X248408Y270258D01*
Y272342D01*
G01X262096Y332509D02*
Y335009D01*
X261055D01*
X260721Y334884D01*
X260513Y334717D01*
X260430Y334384D01*
X260513Y334051D01*
X260763Y333842D01*
X261055Y333717D01*
X262096D01*
G01X261055D02*
X260430Y332509D01*
G01X258163D02*
X257871Y332551D01*
X257538Y332676D01*
X257330Y332884D01*
X257246Y333176D01*
X257330Y333467D01*
X257580Y333717D01*
X257955Y333842D01*
X258371D01*
X258621Y333926D01*
X258830Y334134D01*
X258913Y334426D01*
X258788Y334717D01*
X258496Y334926D01*
X258163Y335009D01*
X257830Y334926D01*
X257538Y334717D01*
X257413Y334426D01*
X257496Y334134D01*
X257705Y333926D01*
X257955Y333842D01*
X258371D01*
X258746Y333717D01*
X258996Y333467D01*
X259080Y333176D01*
X258996Y332884D01*
X258788Y332676D01*
X258455Y332551D01*
X258163Y332509D01*
G01X255896D02*
Y335009D01*
X254896D01*
X254563Y334884D01*
X254313Y334592D01*
X254230Y334259D01*
X254313Y333926D01*
X254521Y333676D01*
X254896Y333551D01*
X255896D01*
G01X251963Y332509D02*
Y335009D01*
X252463Y334509D01*
G01Y332509D02*
X251463D01*
G01X262196Y328709D02*
Y331209D01*
X261155D01*
X260821Y331084D01*
X260613Y330917D01*
X260530Y330584D01*
X260613Y330251D01*
X260863Y330042D01*
X261155Y329917D01*
X262196D01*
G01X261155D02*
X260530Y328709D01*
G01X258263D02*
X257971Y328751D01*
X257638Y328876D01*
X257430Y329084D01*
X257346Y329376D01*
X257430Y329667D01*
X257680Y329917D01*
X258055Y330042D01*
X258471D01*
X258721Y330126D01*
X258930Y330334D01*
X259013Y330626D01*
X258888Y330917D01*
X258596Y331126D01*
X258263Y331209D01*
X257930Y331126D01*
X257638Y330917D01*
X257513Y330626D01*
X257596Y330334D01*
X257805Y330126D01*
X258055Y330042D01*
X258471D01*
X258846Y329917D01*
X259096Y329667D01*
X259180Y329376D01*
X259096Y329084D01*
X258888Y328876D01*
X258555Y328751D01*
X258263Y328709D01*
G01X255996D02*
Y331209D01*
X254996D01*
X254663Y331084D01*
X254413Y330792D01*
X254330Y330459D01*
X254413Y330126D01*
X254621Y329876D01*
X254996Y329751D01*
X255996D01*
G01X252855Y330792D02*
X252605Y331042D01*
X252313Y331167D01*
X251980Y331209D01*
X251563Y331126D01*
X251271Y330917D01*
X251188Y330667D01*
X251230Y330417D01*
X251396Y330209D01*
X252230Y329792D01*
X252605Y329501D01*
X252855Y329084D01*
X252938Y328709D01*
X251188D01*
G01X301828Y459320D02*
X302078Y459445D01*
X302370Y459528D01*
X302703D01*
X303078Y459403D01*
X303370Y459195D01*
X303578Y458945D01*
X303745Y458528D01*
X303787Y458153D01*
X303703Y457778D01*
X303578Y457528D01*
X303328Y457278D01*
X303037Y457111D01*
X302745Y457028D01*
X302453D01*
X302162Y457111D01*
X301912Y457236D01*
X301703Y457403D01*
G01X300562D02*
X300312Y457195D01*
X300020Y457070D01*
X299645Y457028D01*
X299270Y457111D01*
X298978Y457278D01*
X298770Y457570D01*
X298728Y457903D01*
X298812Y458236D01*
X299020Y458445D01*
X299312Y458611D01*
X299603Y458653D01*
X299895Y458611D01*
X300270Y458445D01*
X300145Y459528D01*
X299020D01*
G01X296295Y458278D02*
X295462D01*
Y457528D01*
X295712Y457278D01*
X296003Y457111D01*
X296420Y457028D01*
X296837Y457111D01*
X297128Y457278D01*
X297378Y457528D01*
X297545Y457820D01*
X297628Y458153D01*
Y458445D01*
X297545Y458695D01*
X297378Y458986D01*
X297128Y459236D01*
X296878Y459403D01*
X296545Y459528D01*
X296253D01*
X295920Y459445D01*
X295670Y459278D01*
G01X293445Y457028D02*
Y459528D01*
X293945Y459028D01*
G01Y457028D02*
X292945D01*
G01X290345D02*
Y459528D01*
X290845Y459028D01*
G01Y457028D02*
X289845D01*
G01X288162Y457403D02*
X287912Y457195D01*
X287620Y457070D01*
X287245Y457028D01*
X286870Y457111D01*
X286578Y457278D01*
X286370Y457570D01*
X286328Y457903D01*
X286412Y458236D01*
X286620Y458445D01*
X286912Y458611D01*
X287203Y458653D01*
X287495Y458611D01*
X287870Y458445D01*
X287745Y459528D01*
X286620D01*
G01X301688Y455320D02*
X301938Y455445D01*
X302230Y455528D01*
X302563D01*
X302938Y455403D01*
X303230Y455195D01*
X303438Y454945D01*
X303605Y454528D01*
X303647Y454153D01*
X303563Y453778D01*
X303438Y453528D01*
X303188Y453278D01*
X302897Y453111D01*
X302605Y453028D01*
X302313D01*
X302022Y453111D01*
X301772Y453236D01*
X301563Y453403D01*
G01X299505Y453028D02*
X299213Y453070D01*
X298880Y453195D01*
X298672Y453403D01*
X298588Y453695D01*
X298672Y453986D01*
X298922Y454236D01*
X299297Y454361D01*
X299713D01*
X299963Y454445D01*
X300172Y454653D01*
X300255Y454945D01*
X300130Y455236D01*
X299838Y455445D01*
X299505Y455528D01*
X299172Y455445D01*
X298880Y455236D01*
X298755Y454945D01*
X298838Y454653D01*
X299047Y454445D01*
X299297Y454361D01*
X299713D01*
X300088Y454236D01*
X300338Y453986D01*
X300422Y453695D01*
X300338Y453403D01*
X300130Y453195D01*
X299797Y453070D01*
X299505Y453028D01*
G01X297488D02*
Y455528D01*
X296405Y453445D01*
X295322Y455528D01*
Y453028D01*
G01X293388D02*
X293305Y453570D01*
X293180Y454028D01*
X293013Y454445D01*
X292805Y454903D01*
X292472Y455528D01*
X294138D01*
G01X301788Y467320D02*
X302038Y467445D01*
X302330Y467528D01*
X302663D01*
X303038Y467403D01*
X303330Y467195D01*
X303538Y466945D01*
X303705Y466528D01*
X303747Y466153D01*
X303663Y465778D01*
X303538Y465528D01*
X303288Y465278D01*
X302997Y465111D01*
X302705Y465028D01*
X302413D01*
X302122Y465111D01*
X301872Y465236D01*
X301663Y465403D01*
G01X300522D02*
X300272Y465195D01*
X299980Y465070D01*
X299605Y465028D01*
X299230Y465111D01*
X298938Y465278D01*
X298730Y465570D01*
X298688Y465903D01*
X298772Y466236D01*
X298980Y466445D01*
X299272Y466611D01*
X299563Y466653D01*
X299855Y466611D01*
X300230Y466445D01*
X300105Y467528D01*
X298980D01*
G01X296255Y466278D02*
X295422D01*
Y465528D01*
X295672Y465278D01*
X295963Y465111D01*
X296380Y465028D01*
X296797Y465111D01*
X297088Y465278D01*
X297338Y465528D01*
X297505Y465820D01*
X297588Y466153D01*
Y466445D01*
X297505Y466695D01*
X297338Y466986D01*
X297088Y467236D01*
X296838Y467403D01*
X296505Y467528D01*
X296213D01*
X295880Y467445D01*
X295630Y467278D01*
G01X293405Y465028D02*
Y467528D01*
X293905Y467028D01*
G01Y465028D02*
X292905D01*
G01X290305D02*
Y467528D01*
X290805Y467028D01*
G01Y465028D02*
X289805D01*
G01X287997Y466070D02*
X287705Y466361D01*
X287455Y466528D01*
X287122Y466611D01*
X286830Y466528D01*
X286622Y466361D01*
X286455Y466111D01*
X286413Y465820D01*
X286455Y465570D01*
X286622Y465320D01*
X286872Y465111D01*
X287163Y465028D01*
X287497Y465111D01*
X287788Y465361D01*
X287955Y465736D01*
X287997Y466153D01*
X287913Y466695D01*
X287788Y466986D01*
X287580Y467278D01*
X287288Y467486D01*
X286997Y467528D01*
X286705Y467445D01*
X286497Y467236D01*
G01X302048Y463320D02*
X302298Y463445D01*
X302590Y463528D01*
X302923D01*
X303298Y463403D01*
X303590Y463195D01*
X303798Y462945D01*
X303965Y462528D01*
X304007Y462153D01*
X303923Y461778D01*
X303798Y461528D01*
X303548Y461278D01*
X303257Y461111D01*
X302965Y461028D01*
X302673D01*
X302382Y461111D01*
X302132Y461236D01*
X301923Y461403D01*
G01X299865Y461028D02*
X299573Y461070D01*
X299240Y461195D01*
X299032Y461403D01*
X298948Y461695D01*
X299032Y461986D01*
X299282Y462236D01*
X299657Y462361D01*
X300073D01*
X300323Y462445D01*
X300532Y462653D01*
X300615Y462945D01*
X300490Y463236D01*
X300198Y463445D01*
X299865Y463528D01*
X299532Y463445D01*
X299240Y463236D01*
X299115Y462945D01*
X299198Y462653D01*
X299407Y462445D01*
X299657Y462361D01*
X300073D01*
X300448Y462236D01*
X300698Y461986D01*
X300782Y461695D01*
X300698Y461403D01*
X300490Y461195D01*
X300157Y461070D01*
X299865Y461028D01*
G01X297598Y463528D02*
Y461028D01*
X295932D01*
G01X293665D02*
Y463528D01*
X294165Y463028D01*
G01Y461028D02*
X293165D01*
G01X290565D02*
Y463528D01*
X291065Y463028D01*
G01Y461028D02*
X290065D01*
G01X281160Y459300D02*
X281410Y459425D01*
X281702Y459508D01*
X282035D01*
X282410Y459383D01*
X282702Y459175D01*
X282910Y458925D01*
X283077Y458508D01*
X283119Y458133D01*
X283035Y457758D01*
X282910Y457508D01*
X282660Y457258D01*
X282369Y457091D01*
X282077Y457008D01*
X281785D01*
X281494Y457091D01*
X281244Y457216D01*
X281035Y457383D01*
G01X279894D02*
X279644Y457175D01*
X279352Y457050D01*
X278977Y457008D01*
X278602Y457091D01*
X278310Y457258D01*
X278102Y457550D01*
X278060Y457883D01*
X278144Y458216D01*
X278352Y458425D01*
X278644Y458591D01*
X278935Y458633D01*
X279227Y458591D01*
X279602Y458425D01*
X279477Y459508D01*
X278352D01*
G01X275627Y458258D02*
X274794D01*
Y457508D01*
X275044Y457258D01*
X275335Y457091D01*
X275752Y457008D01*
X276169Y457091D01*
X276460Y457258D01*
X276710Y457508D01*
X276877Y457800D01*
X276960Y458133D01*
Y458425D01*
X276877Y458675D01*
X276710Y458966D01*
X276460Y459216D01*
X276210Y459383D01*
X275877Y459508D01*
X275585D01*
X275252Y459425D01*
X275002Y459258D01*
G01X272777Y457008D02*
Y459508D01*
X273277Y459008D01*
G01Y457008D02*
X272277D01*
G01X269677D02*
Y459508D01*
X270177Y459008D01*
G01Y457008D02*
X269177D01*
G01X266577Y459508D02*
X266910Y459425D01*
X267160Y459216D01*
X267327Y458966D01*
X267452Y458633D01*
X267494Y458258D01*
X267452Y457883D01*
X267327Y457550D01*
X267160Y457300D01*
X266910Y457091D01*
X266577Y457008D01*
X266244Y457091D01*
X265994Y457300D01*
X265827Y457550D01*
X265702Y457883D01*
X265660Y458258D01*
X265702Y458633D01*
X265827Y458966D01*
X265994Y459216D01*
X266244Y459425D01*
X266577Y459508D01*
G01X261490Y459537D02*
X261740Y459662D01*
X262032Y459745D01*
X262365D01*
X262740Y459620D01*
X263032Y459412D01*
X263240Y459162D01*
X263407Y458745D01*
X263449Y458370D01*
X263365Y457995D01*
X263240Y457745D01*
X262990Y457495D01*
X262699Y457328D01*
X262407Y457245D01*
X262115D01*
X261824Y457328D01*
X261574Y457453D01*
X261365Y457620D01*
G01X260224D02*
X259974Y457412D01*
X259682Y457287D01*
X259307Y457245D01*
X258932Y457328D01*
X258640Y457495D01*
X258432Y457787D01*
X258390Y458120D01*
X258474Y458453D01*
X258682Y458662D01*
X258974Y458828D01*
X259265Y458870D01*
X259557Y458828D01*
X259932Y458662D01*
X259807Y459745D01*
X258682D01*
G01X255957Y458495D02*
X255124D01*
Y457745D01*
X255374Y457495D01*
X255665Y457328D01*
X256082Y457245D01*
X256499Y457328D01*
X256790Y457495D01*
X257040Y457745D01*
X257207Y458037D01*
X257290Y458370D01*
Y458662D01*
X257207Y458912D01*
X257040Y459203D01*
X256790Y459453D01*
X256540Y459620D01*
X256207Y459745D01*
X255915D01*
X255582Y459662D01*
X255332Y459495D01*
G01X253107Y457245D02*
Y459745D01*
X253607Y459245D01*
G01Y457245D02*
X252607D01*
G01X250007D02*
Y459745D01*
X250507Y459245D01*
G01Y457245D02*
X249507D01*
G01X246907D02*
Y459745D01*
X247407Y459245D01*
G01Y457245D02*
X246407D01*
G01X281160Y467300D02*
X281410Y467425D01*
X281702Y467508D01*
X282035D01*
X282410Y467383D01*
X282702Y467175D01*
X282910Y466925D01*
X283077Y466508D01*
X283119Y466133D01*
X283035Y465758D01*
X282910Y465508D01*
X282660Y465258D01*
X282369Y465091D01*
X282077Y465008D01*
X281785D01*
X281494Y465091D01*
X281244Y465216D01*
X281035Y465383D01*
G01X279894D02*
X279644Y465175D01*
X279352Y465050D01*
X278977Y465008D01*
X278602Y465091D01*
X278310Y465258D01*
X278102Y465550D01*
X278060Y465883D01*
X278144Y466216D01*
X278352Y466425D01*
X278644Y466591D01*
X278935Y466633D01*
X279227Y466591D01*
X279602Y466425D01*
X279477Y467508D01*
X278352D01*
G01X275627Y466258D02*
X274794D01*
Y465508D01*
X275044Y465258D01*
X275335Y465091D01*
X275752Y465008D01*
X276169Y465091D01*
X276460Y465258D01*
X276710Y465508D01*
X276877Y465800D01*
X276960Y466133D01*
Y466425D01*
X276877Y466675D01*
X276710Y466966D01*
X276460Y467216D01*
X276210Y467383D01*
X275877Y467508D01*
X275585D01*
X275252Y467425D01*
X275002Y467258D01*
G01X273485Y465300D02*
X273194Y465091D01*
X272860Y465008D01*
X272527Y465091D01*
X272235Y465341D01*
X272027Y465716D01*
X271944Y466091D01*
Y466550D01*
X272027Y466925D01*
X272235Y467258D01*
X272485Y467425D01*
X272777Y467508D01*
X273110Y467425D01*
X273360Y467258D01*
X273527Y467008D01*
X273610Y466675D01*
X273527Y466383D01*
X273319Y466091D01*
X273069Y465925D01*
X272777Y465883D01*
X272444Y465966D01*
X272194Y466175D01*
X271944Y466550D01*
G01X269760Y465008D02*
X269677Y465550D01*
X269552Y466008D01*
X269385Y466425D01*
X269177Y466883D01*
X268844Y467508D01*
X270510D01*
G01X261490Y467537D02*
X261740Y467662D01*
X262032Y467745D01*
X262365D01*
X262740Y467620D01*
X263032Y467412D01*
X263240Y467162D01*
X263407Y466745D01*
X263449Y466370D01*
X263365Y465995D01*
X263240Y465745D01*
X262990Y465495D01*
X262699Y465328D01*
X262407Y465245D01*
X262115D01*
X261824Y465328D01*
X261574Y465453D01*
X261365Y465620D01*
G01X260224D02*
X259974Y465412D01*
X259682Y465287D01*
X259307Y465245D01*
X258932Y465328D01*
X258640Y465495D01*
X258432Y465787D01*
X258390Y466120D01*
X258474Y466453D01*
X258682Y466662D01*
X258974Y466828D01*
X259265Y466870D01*
X259557Y466828D01*
X259932Y466662D01*
X259807Y467745D01*
X258682D01*
G01X255957Y466495D02*
X255124D01*
Y465745D01*
X255374Y465495D01*
X255665Y465328D01*
X256082Y465245D01*
X256499Y465328D01*
X256790Y465495D01*
X257040Y465745D01*
X257207Y466037D01*
X257290Y466370D01*
Y466662D01*
X257207Y466912D01*
X257040Y467203D01*
X256790Y467453D01*
X256540Y467620D01*
X256207Y467745D01*
X255915D01*
X255582Y467662D01*
X255332Y467495D01*
G01X253815Y465537D02*
X253524Y465328D01*
X253190Y465245D01*
X252857Y465328D01*
X252565Y465578D01*
X252357Y465953D01*
X252274Y466328D01*
Y466787D01*
X252357Y467162D01*
X252565Y467495D01*
X252815Y467662D01*
X253107Y467745D01*
X253440Y467662D01*
X253690Y467495D01*
X253857Y467245D01*
X253940Y466912D01*
X253857Y466620D01*
X253649Y466328D01*
X253399Y466162D01*
X253107Y466120D01*
X252774Y466203D01*
X252524Y466412D01*
X252274Y466787D01*
G01X250007Y465245D02*
X249715Y465287D01*
X249382Y465412D01*
X249174Y465620D01*
X249090Y465912D01*
X249174Y466203D01*
X249424Y466453D01*
X249799Y466578D01*
X250215D01*
X250465Y466662D01*
X250674Y466870D01*
X250757Y467162D01*
X250632Y467453D01*
X250340Y467662D01*
X250007Y467745D01*
X249674Y467662D01*
X249382Y467453D01*
X249257Y467162D01*
X249340Y466870D01*
X249549Y466662D01*
X249799Y466578D01*
X250215D01*
X250590Y466453D01*
X250840Y466203D01*
X250924Y465912D01*
X250840Y465620D01*
X250632Y465412D01*
X250299Y465287D01*
X250007Y465245D01*
G01X281160Y455300D02*
X281410Y455425D01*
X281702Y455508D01*
X282035D01*
X282410Y455383D01*
X282702Y455175D01*
X282910Y454925D01*
X283077Y454508D01*
X283119Y454133D01*
X283035Y453758D01*
X282910Y453508D01*
X282660Y453258D01*
X282369Y453091D01*
X282077Y453008D01*
X281785D01*
X281494Y453091D01*
X281244Y453216D01*
X281035Y453383D01*
G01X278977Y453008D02*
X278685Y453050D01*
X278352Y453175D01*
X278144Y453383D01*
X278060Y453675D01*
X278144Y453966D01*
X278394Y454216D01*
X278769Y454341D01*
X279185D01*
X279435Y454425D01*
X279644Y454633D01*
X279727Y454925D01*
X279602Y455216D01*
X279310Y455425D01*
X278977Y455508D01*
X278644Y455425D01*
X278352Y455216D01*
X278227Y454925D01*
X278310Y454633D01*
X278519Y454425D01*
X278769Y454341D01*
X279185D01*
X279560Y454216D01*
X279810Y453966D01*
X279894Y453675D01*
X279810Y453383D01*
X279602Y453175D01*
X279269Y453050D01*
X278977Y453008D01*
G01X276960D02*
Y455508D01*
X275877Y453425D01*
X274794Y455508D01*
Y453008D01*
G01X272777D02*
X272485Y453050D01*
X272152Y453175D01*
X271944Y453383D01*
X271860Y453675D01*
X271944Y453966D01*
X272194Y454216D01*
X272569Y454341D01*
X272985D01*
X273235Y454425D01*
X273444Y454633D01*
X273527Y454925D01*
X273402Y455216D01*
X273110Y455425D01*
X272777Y455508D01*
X272444Y455425D01*
X272152Y455216D01*
X272027Y454925D01*
X272110Y454633D01*
X272319Y454425D01*
X272569Y454341D01*
X272985D01*
X273360Y454216D01*
X273610Y453966D01*
X273694Y453675D01*
X273610Y453383D01*
X273402Y453175D01*
X273069Y453050D01*
X272777Y453008D01*
G01X281160Y463300D02*
X281410Y463425D01*
X281702Y463508D01*
X282035D01*
X282410Y463383D01*
X282702Y463175D01*
X282910Y462925D01*
X283077Y462508D01*
X283119Y462133D01*
X283035Y461758D01*
X282910Y461508D01*
X282660Y461258D01*
X282369Y461091D01*
X282077Y461008D01*
X281785D01*
X281494Y461091D01*
X281244Y461216D01*
X281035Y461383D01*
G01X278977Y461008D02*
X278685Y461050D01*
X278352Y461175D01*
X278144Y461383D01*
X278060Y461675D01*
X278144Y461966D01*
X278394Y462216D01*
X278769Y462341D01*
X279185D01*
X279435Y462425D01*
X279644Y462633D01*
X279727Y462925D01*
X279602Y463216D01*
X279310Y463425D01*
X278977Y463508D01*
X278644Y463425D01*
X278352Y463216D01*
X278227Y462925D01*
X278310Y462633D01*
X278519Y462425D01*
X278769Y462341D01*
X279185D01*
X279560Y462216D01*
X279810Y461966D01*
X279894Y461675D01*
X279810Y461383D01*
X279602Y461175D01*
X279269Y461050D01*
X278977Y461008D01*
G01X276710Y463508D02*
Y461008D01*
X275044D01*
G01X272777D02*
Y463508D01*
X273277Y463008D01*
G01Y461008D02*
X272277D01*
G01X270469Y463091D02*
X270219Y463341D01*
X269927Y463466D01*
X269594Y463508D01*
X269177Y463425D01*
X268885Y463216D01*
X268802Y462966D01*
X268844Y462716D01*
X269010Y462508D01*
X269844Y462091D01*
X270219Y461800D01*
X270469Y461383D01*
X270552Y461008D01*
X268802D01*
G01X243244Y455775D02*
X243494Y455900D01*
X243786Y455983D01*
X244119D01*
X244494Y455858D01*
X244786Y455650D01*
X244994Y455400D01*
X245161Y454983D01*
X245203Y454608D01*
X245119Y454233D01*
X244994Y453983D01*
X244744Y453733D01*
X244453Y453566D01*
X244161Y453483D01*
X243869D01*
X243578Y453566D01*
X243328Y453691D01*
X243119Y453858D01*
G01X241061Y453483D02*
X240769Y453525D01*
X240436Y453650D01*
X240228Y453858D01*
X240144Y454150D01*
X240228Y454441D01*
X240478Y454691D01*
X240853Y454816D01*
X241269D01*
X241519Y454900D01*
X241728Y455108D01*
X241811Y455400D01*
X241686Y455691D01*
X241394Y455900D01*
X241061Y455983D01*
X240728Y455900D01*
X240436Y455691D01*
X240311Y455400D01*
X240394Y455108D01*
X240603Y454900D01*
X240853Y454816D01*
X241269D01*
X241644Y454691D01*
X241894Y454441D01*
X241978Y454150D01*
X241894Y453858D01*
X241686Y453650D01*
X241353Y453525D01*
X241061Y453483D01*
G01X239044D02*
Y455983D01*
X237961Y453900D01*
X236878Y455983D01*
Y453483D01*
G01X234361D02*
Y455983D01*
X235903Y454191D01*
X233819D01*
G01X261490Y455537D02*
X261740Y455662D01*
X262032Y455745D01*
X262365D01*
X262740Y455620D01*
X263032Y455412D01*
X263240Y455162D01*
X263407Y454745D01*
X263449Y454370D01*
X263365Y453995D01*
X263240Y453745D01*
X262990Y453495D01*
X262699Y453328D01*
X262407Y453245D01*
X262115D01*
X261824Y453328D01*
X261574Y453453D01*
X261365Y453620D01*
G01X259307Y453245D02*
X259015Y453287D01*
X258682Y453412D01*
X258474Y453620D01*
X258390Y453912D01*
X258474Y454203D01*
X258724Y454453D01*
X259099Y454578D01*
X259515D01*
X259765Y454662D01*
X259974Y454870D01*
X260057Y455162D01*
X259932Y455453D01*
X259640Y455662D01*
X259307Y455745D01*
X258974Y455662D01*
X258682Y455453D01*
X258557Y455162D01*
X258640Y454870D01*
X258849Y454662D01*
X259099Y454578D01*
X259515D01*
X259890Y454453D01*
X260140Y454203D01*
X260224Y453912D01*
X260140Y453620D01*
X259932Y453412D01*
X259599Y453287D01*
X259307Y453245D01*
G01X257290D02*
Y455745D01*
X256207Y453662D01*
X255124Y455745D01*
Y453245D01*
G01X254024Y453745D02*
X253774Y453453D01*
X253440Y453287D01*
X253065Y453245D01*
X252732Y453287D01*
X252399Y453495D01*
X252190Y453745D01*
X252149Y453995D01*
X252232Y454287D01*
X252524Y454495D01*
X252815Y454578D01*
X253190D01*
G01X252815D02*
X252565Y454703D01*
X252357Y454912D01*
X252274Y455162D01*
X252357Y455412D01*
X252565Y455620D01*
X252940Y455745D01*
X253315Y455703D01*
X253690Y455537D01*
G01X243244Y463775D02*
X243494Y463900D01*
X243786Y463983D01*
X244119D01*
X244494Y463858D01*
X244786Y463650D01*
X244994Y463400D01*
X245161Y462983D01*
X245203Y462608D01*
X245119Y462233D01*
X244994Y461983D01*
X244744Y461733D01*
X244453Y461566D01*
X244161Y461483D01*
X243869D01*
X243578Y461566D01*
X243328Y461691D01*
X243119Y461858D01*
G01X241061Y461483D02*
X240769Y461525D01*
X240436Y461650D01*
X240228Y461858D01*
X240144Y462150D01*
X240228Y462441D01*
X240478Y462691D01*
X240853Y462816D01*
X241269D01*
X241519Y462900D01*
X241728Y463108D01*
X241811Y463400D01*
X241686Y463691D01*
X241394Y463900D01*
X241061Y463983D01*
X240728Y463900D01*
X240436Y463691D01*
X240311Y463400D01*
X240394Y463108D01*
X240603Y462900D01*
X240853Y462816D01*
X241269D01*
X241644Y462691D01*
X241894Y462441D01*
X241978Y462150D01*
X241894Y461858D01*
X241686Y461650D01*
X241353Y461525D01*
X241061Y461483D01*
G01X238794Y463983D02*
Y461483D01*
X237128D01*
G01X234861D02*
X234569Y461525D01*
X234236Y461650D01*
X234028Y461858D01*
X233944Y462150D01*
X234028Y462441D01*
X234278Y462691D01*
X234653Y462816D01*
X235069D01*
X235319Y462900D01*
X235528Y463108D01*
X235611Y463400D01*
X235486Y463691D01*
X235194Y463900D01*
X234861Y463983D01*
X234528Y463900D01*
X234236Y463691D01*
X234111Y463400D01*
X234194Y463108D01*
X234403Y462900D01*
X234653Y462816D01*
X235069D01*
X235444Y462691D01*
X235694Y462441D01*
X235778Y462150D01*
X235694Y461858D01*
X235486Y461650D01*
X235153Y461525D01*
X234861Y461483D01*
G01X261490Y463537D02*
X261740Y463662D01*
X262032Y463745D01*
X262365D01*
X262740Y463620D01*
X263032Y463412D01*
X263240Y463162D01*
X263407Y462745D01*
X263449Y462370D01*
X263365Y461995D01*
X263240Y461745D01*
X262990Y461495D01*
X262699Y461328D01*
X262407Y461245D01*
X262115D01*
X261824Y461328D01*
X261574Y461453D01*
X261365Y461620D01*
G01X259307Y461245D02*
X259015Y461287D01*
X258682Y461412D01*
X258474Y461620D01*
X258390Y461912D01*
X258474Y462203D01*
X258724Y462453D01*
X259099Y462578D01*
X259515D01*
X259765Y462662D01*
X259974Y462870D01*
X260057Y463162D01*
X259932Y463453D01*
X259640Y463662D01*
X259307Y463745D01*
X258974Y463662D01*
X258682Y463453D01*
X258557Y463162D01*
X258640Y462870D01*
X258849Y462662D01*
X259099Y462578D01*
X259515D01*
X259890Y462453D01*
X260140Y462203D01*
X260224Y461912D01*
X260140Y461620D01*
X259932Y461412D01*
X259599Y461287D01*
X259307Y461245D01*
G01X257040Y463745D02*
Y461245D01*
X255374D01*
G01X253190D02*
X253107Y461787D01*
X252982Y462245D01*
X252815Y462662D01*
X252607Y463120D01*
X252274Y463745D01*
X253940D01*
G01X367141Y-3548D02*
X367391Y-3423D01*
X367683Y-3340D01*
X368016D01*
X368391Y-3465D01*
X368683Y-3673D01*
X368891Y-3923D01*
X369058Y-4340D01*
X369100Y-4715D01*
X369016Y-5090D01*
X368891Y-5340D01*
X368641Y-5590D01*
X368350Y-5757D01*
X368058Y-5840D01*
X367766D01*
X367475Y-5757D01*
X367225Y-5632D01*
X367016Y-5465D01*
G01X364958Y-5840D02*
X364666Y-5798D01*
X364333Y-5673D01*
X364125Y-5465D01*
X364041Y-5173D01*
X364125Y-4882D01*
X364375Y-4632D01*
X364750Y-4507D01*
X365166D01*
X365416Y-4423D01*
X365625Y-4215D01*
X365708Y-3923D01*
X365583Y-3632D01*
X365291Y-3423D01*
X364958Y-3340D01*
X364625Y-3423D01*
X364333Y-3632D01*
X364208Y-3923D01*
X364291Y-4215D01*
X364500Y-4423D01*
X364750Y-4507D01*
X365166D01*
X365541Y-4632D01*
X365791Y-4882D01*
X365875Y-5173D01*
X365791Y-5465D01*
X365583Y-5673D01*
X365250Y-5798D01*
X364958Y-5840D01*
G01X362775Y-3340D02*
Y-5132D01*
X362608Y-5507D01*
X362275Y-5757D01*
X361858Y-5840D01*
X361441Y-5757D01*
X361108Y-5507D01*
X360941Y-5132D01*
Y-3340D01*
G01X358758Y-5840D02*
Y-3340D01*
X359258Y-3840D01*
G01Y-5840D02*
X358258D01*
G01X355658Y-3340D02*
X355991Y-3423D01*
X356241Y-3632D01*
X356408Y-3882D01*
X356533Y-4215D01*
X356575Y-4590D01*
X356533Y-4965D01*
X356408Y-5298D01*
X356241Y-5548D01*
X355991Y-5757D01*
X355658Y-5840D01*
X355325Y-5757D01*
X355075Y-5548D01*
X354908Y-5298D01*
X354783Y-4965D01*
X354741Y-4590D01*
X354783Y-4215D01*
X354908Y-3882D01*
X355075Y-3632D01*
X355325Y-3423D01*
X355658Y-3340D01*
G01X318605Y113056D02*
X317105Y114556D01*
X320105D01*
X318605Y113056D01*
X318600Y113061D01*
Y127100D01*
X379800D01*
Y153300D01*
X320000D01*
G01X308405Y147235D02*
X308655Y147360D01*
X308947Y147443D01*
X309280D01*
X309655Y147318D01*
X309947Y147110D01*
X310155Y146860D01*
X310322Y146443D01*
X310364Y146068D01*
X310280Y145693D01*
X310155Y145443D01*
X309905Y145193D01*
X309614Y145026D01*
X309322Y144943D01*
X309030D01*
X308739Y145026D01*
X308489Y145151D01*
X308280Y145318D01*
G01X306222Y144943D02*
X305930Y144985D01*
X305597Y145110D01*
X305389Y145318D01*
X305305Y145610D01*
X305389Y145901D01*
X305639Y146151D01*
X306014Y146276D01*
X306430D01*
X306680Y146360D01*
X306889Y146568D01*
X306972Y146860D01*
X306847Y147151D01*
X306555Y147360D01*
X306222Y147443D01*
X305889Y147360D01*
X305597Y147151D01*
X305472Y146860D01*
X305555Y146568D01*
X305764Y146360D01*
X306014Y146276D01*
X306430D01*
X306805Y146151D01*
X307055Y145901D01*
X307139Y145610D01*
X307055Y145318D01*
X306847Y145110D01*
X306514Y144985D01*
X306222Y144943D01*
G01X304039Y147443D02*
Y145651D01*
X303872Y145276D01*
X303539Y145026D01*
X303122Y144943D01*
X302705Y145026D01*
X302372Y145276D01*
X302205Y145651D01*
Y147443D01*
G01X300022Y144943D02*
Y147443D01*
X300522Y146943D01*
G01Y144943D02*
X299522D01*
G01X308405Y139235D02*
X308655Y139360D01*
X308947Y139443D01*
X309280D01*
X309655Y139318D01*
X309947Y139110D01*
X310155Y138860D01*
X310322Y138443D01*
X310364Y138068D01*
X310280Y137693D01*
X310155Y137443D01*
X309905Y137193D01*
X309614Y137026D01*
X309322Y136943D01*
X309030D01*
X308739Y137026D01*
X308489Y137151D01*
X308280Y137318D01*
G01X306222Y136943D02*
X305930Y136985D01*
X305597Y137110D01*
X305389Y137318D01*
X305305Y137610D01*
X305389Y137901D01*
X305639Y138151D01*
X306014Y138276D01*
X306430D01*
X306680Y138360D01*
X306889Y138568D01*
X306972Y138860D01*
X306847Y139151D01*
X306555Y139360D01*
X306222Y139443D01*
X305889Y139360D01*
X305597Y139151D01*
X305472Y138860D01*
X305555Y138568D01*
X305764Y138360D01*
X306014Y138276D01*
X306430D01*
X306805Y138151D01*
X307055Y137901D01*
X307139Y137610D01*
X307055Y137318D01*
X306847Y137110D01*
X306514Y136985D01*
X306222Y136943D01*
G01X304039Y139443D02*
Y137651D01*
X303872Y137276D01*
X303539Y137026D01*
X303122Y136943D01*
X302705Y137026D01*
X302372Y137276D01*
X302205Y137651D01*
Y139443D01*
G01X300022Y136943D02*
X299730Y136985D01*
X299397Y137110D01*
X299189Y137318D01*
X299105Y137610D01*
X299189Y137901D01*
X299439Y138151D01*
X299814Y138276D01*
X300230D01*
X300480Y138360D01*
X300689Y138568D01*
X300772Y138860D01*
X300647Y139151D01*
X300355Y139360D01*
X300022Y139443D01*
X299689Y139360D01*
X299397Y139151D01*
X299272Y138860D01*
X299355Y138568D01*
X299564Y138360D01*
X299814Y138276D01*
X300230D01*
X300605Y138151D01*
X300855Y137901D01*
X300939Y137610D01*
X300855Y137318D01*
X300647Y137110D01*
X300314Y136985D01*
X300022Y136943D01*
G01X359354Y142996D02*
X359604Y143121D01*
X359896Y143204D01*
X360229D01*
X360604Y143079D01*
X360896Y142871D01*
X361104Y142621D01*
X361271Y142204D01*
X361313Y141829D01*
X361229Y141454D01*
X361104Y141204D01*
X360854Y140954D01*
X360563Y140787D01*
X360271Y140704D01*
X359979D01*
X359688Y140787D01*
X359438Y140912D01*
X359229Y141079D01*
G01X358088D02*
X357838Y140871D01*
X357546Y140746D01*
X357171Y140704D01*
X356796Y140787D01*
X356504Y140954D01*
X356296Y141246D01*
X356254Y141579D01*
X356338Y141912D01*
X356546Y142121D01*
X356838Y142287D01*
X357129Y142329D01*
X357421Y142287D01*
X357796Y142121D01*
X357671Y143204D01*
X356546D01*
G01X353821Y141954D02*
X352988D01*
Y141204D01*
X353238Y140954D01*
X353529Y140787D01*
X353946Y140704D01*
X354363Y140787D01*
X354654Y140954D01*
X354904Y141204D01*
X355071Y141496D01*
X355154Y141829D01*
Y142121D01*
X355071Y142371D01*
X354904Y142662D01*
X354654Y142912D01*
X354404Y143079D01*
X354071Y143204D01*
X353779D01*
X353446Y143121D01*
X353196Y142954D01*
G01X351679Y140996D02*
X351388Y140787D01*
X351054Y140704D01*
X350721Y140787D01*
X350429Y141037D01*
X350221Y141412D01*
X350138Y141787D01*
Y142246D01*
X350221Y142621D01*
X350429Y142954D01*
X350679Y143121D01*
X350971Y143204D01*
X351304Y143121D01*
X351554Y142954D01*
X351721Y142704D01*
X351804Y142371D01*
X351721Y142079D01*
X351513Y141787D01*
X351263Y141621D01*
X350971Y141579D01*
X350638Y141662D01*
X350388Y141871D01*
X350138Y142246D01*
G01X348788Y141079D02*
X348538Y140871D01*
X348246Y140746D01*
X347871Y140704D01*
X347496Y140787D01*
X347204Y140954D01*
X346996Y141246D01*
X346954Y141579D01*
X347038Y141912D01*
X347246Y142121D01*
X347538Y142287D01*
X347829Y142329D01*
X348121Y142287D01*
X348496Y142121D01*
X348371Y143204D01*
X347246D01*
G01X343120Y135235D02*
X343370Y135360D01*
X343662Y135443D01*
X343995D01*
X344370Y135318D01*
X344662Y135110D01*
X344870Y134860D01*
X345037Y134443D01*
X345079Y134068D01*
X344995Y133693D01*
X344870Y133443D01*
X344620Y133193D01*
X344329Y133026D01*
X344037Y132943D01*
X343745D01*
X343454Y133026D01*
X343204Y133151D01*
X342995Y133318D01*
G01X341854D02*
X341604Y133110D01*
X341312Y132985D01*
X340937Y132943D01*
X340562Y133026D01*
X340270Y133193D01*
X340062Y133485D01*
X340020Y133818D01*
X340104Y134151D01*
X340312Y134360D01*
X340604Y134526D01*
X340895Y134568D01*
X341187Y134526D01*
X341562Y134360D01*
X341437Y135443D01*
X340312D01*
G01X337587Y134193D02*
X336754D01*
Y133443D01*
X337004Y133193D01*
X337295Y133026D01*
X337712Y132943D01*
X338129Y133026D01*
X338420Y133193D01*
X338670Y133443D01*
X338837Y133735D01*
X338920Y134068D01*
Y134360D01*
X338837Y134610D01*
X338670Y134901D01*
X338420Y135151D01*
X338170Y135318D01*
X337837Y135443D01*
X337545D01*
X337212Y135360D01*
X336962Y135193D01*
G01X335445Y133235D02*
X335154Y133026D01*
X334820Y132943D01*
X334487Y133026D01*
X334195Y133276D01*
X333987Y133651D01*
X333904Y134026D01*
Y134485D01*
X333987Y134860D01*
X334195Y135193D01*
X334445Y135360D01*
X334737Y135443D01*
X335070Y135360D01*
X335320Y135193D01*
X335487Y134943D01*
X335570Y134610D01*
X335487Y134318D01*
X335279Y134026D01*
X335029Y133860D01*
X334737Y133818D01*
X334404Y133901D01*
X334154Y134110D01*
X333904Y134485D01*
G01X331637Y135443D02*
X331970Y135360D01*
X332220Y135151D01*
X332387Y134901D01*
X332512Y134568D01*
X332554Y134193D01*
X332512Y133818D01*
X332387Y133485D01*
X332220Y133235D01*
X331970Y133026D01*
X331637Y132943D01*
X331304Y133026D01*
X331054Y133235D01*
X330887Y133485D01*
X330762Y133818D01*
X330720Y134193D01*
X330762Y134568D01*
X330887Y134901D01*
X331054Y135151D01*
X331304Y135360D01*
X331637Y135443D01*
G01X343120Y143235D02*
X343370Y143360D01*
X343662Y143443D01*
X343995D01*
X344370Y143318D01*
X344662Y143110D01*
X344870Y142860D01*
X345037Y142443D01*
X345079Y142068D01*
X344995Y141693D01*
X344870Y141443D01*
X344620Y141193D01*
X344329Y141026D01*
X344037Y140943D01*
X343745D01*
X343454Y141026D01*
X343204Y141151D01*
X342995Y141318D01*
G01X341854D02*
X341604Y141110D01*
X341312Y140985D01*
X340937Y140943D01*
X340562Y141026D01*
X340270Y141193D01*
X340062Y141485D01*
X340020Y141818D01*
X340104Y142151D01*
X340312Y142360D01*
X340604Y142526D01*
X340895Y142568D01*
X341187Y142526D01*
X341562Y142360D01*
X341437Y143443D01*
X340312D01*
G01X337587Y142193D02*
X336754D01*
Y141443D01*
X337004Y141193D01*
X337295Y141026D01*
X337712Y140943D01*
X338129Y141026D01*
X338420Y141193D01*
X338670Y141443D01*
X338837Y141735D01*
X338920Y142068D01*
Y142360D01*
X338837Y142610D01*
X338670Y142901D01*
X338420Y143151D01*
X338170Y143318D01*
X337837Y143443D01*
X337545D01*
X337212Y143360D01*
X336962Y143193D01*
G01X335445Y141235D02*
X335154Y141026D01*
X334820Y140943D01*
X334487Y141026D01*
X334195Y141276D01*
X333987Y141651D01*
X333904Y142026D01*
Y142485D01*
X333987Y142860D01*
X334195Y143193D01*
X334445Y143360D01*
X334737Y143443D01*
X335070Y143360D01*
X335320Y143193D01*
X335487Y142943D01*
X335570Y142610D01*
X335487Y142318D01*
X335279Y142026D01*
X335029Y141860D01*
X334737Y141818D01*
X334404Y141901D01*
X334154Y142110D01*
X333904Y142485D01*
G01X331137Y140943D02*
Y143443D01*
X332679Y141651D01*
X330595D01*
G01X359354Y134996D02*
X359604Y135121D01*
X359896Y135204D01*
X360229D01*
X360604Y135079D01*
X360896Y134871D01*
X361104Y134621D01*
X361271Y134204D01*
X361313Y133829D01*
X361229Y133454D01*
X361104Y133204D01*
X360854Y132954D01*
X360563Y132787D01*
X360271Y132704D01*
X359979D01*
X359688Y132787D01*
X359438Y132912D01*
X359229Y133079D01*
G01X358088D02*
X357838Y132871D01*
X357546Y132746D01*
X357171Y132704D01*
X356796Y132787D01*
X356504Y132954D01*
X356296Y133246D01*
X356254Y133579D01*
X356338Y133912D01*
X356546Y134121D01*
X356838Y134287D01*
X357129Y134329D01*
X357421Y134287D01*
X357796Y134121D01*
X357671Y135204D01*
X356546D01*
G01X353821Y133954D02*
X352988D01*
Y133204D01*
X353238Y132954D01*
X353529Y132787D01*
X353946Y132704D01*
X354363Y132787D01*
X354654Y132954D01*
X354904Y133204D01*
X355071Y133496D01*
X355154Y133829D01*
Y134121D01*
X355071Y134371D01*
X354904Y134662D01*
X354654Y134912D01*
X354404Y135079D01*
X354071Y135204D01*
X353779D01*
X353446Y135121D01*
X353196Y134954D01*
G01X351679Y132996D02*
X351388Y132787D01*
X351054Y132704D01*
X350721Y132787D01*
X350429Y133037D01*
X350221Y133412D01*
X350138Y133787D01*
Y134246D01*
X350221Y134621D01*
X350429Y134954D01*
X350679Y135121D01*
X350971Y135204D01*
X351304Y135121D01*
X351554Y134954D01*
X351721Y134704D01*
X351804Y134371D01*
X351721Y134079D01*
X351513Y133787D01*
X351263Y133621D01*
X350971Y133579D01*
X350638Y133662D01*
X350388Y133871D01*
X350138Y134246D01*
G01X347871Y132704D02*
Y135204D01*
X348371Y134704D01*
G01Y132704D02*
X347371D01*
G01X325823Y135234D02*
X326073Y135359D01*
X326365Y135442D01*
X326698D01*
X327073Y135317D01*
X327365Y135109D01*
X327573Y134859D01*
X327740Y134442D01*
X327782Y134067D01*
X327698Y133692D01*
X327573Y133442D01*
X327323Y133192D01*
X327032Y133025D01*
X326740Y132942D01*
X326448D01*
X326157Y133025D01*
X325907Y133150D01*
X325698Y133317D01*
G01X324557D02*
X324307Y133109D01*
X324015Y132984D01*
X323640Y132942D01*
X323265Y133025D01*
X322973Y133192D01*
X322765Y133484D01*
X322723Y133817D01*
X322807Y134150D01*
X323015Y134359D01*
X323307Y134525D01*
X323598Y134567D01*
X323890Y134525D01*
X324265Y134359D01*
X324140Y135442D01*
X323015D01*
G01X320290Y134192D02*
X319457D01*
Y133442D01*
X319707Y133192D01*
X319998Y133025D01*
X320415Y132942D01*
X320832Y133025D01*
X321123Y133192D01*
X321373Y133442D01*
X321540Y133734D01*
X321623Y134067D01*
Y134359D01*
X321540Y134609D01*
X321373Y134900D01*
X321123Y135150D01*
X320873Y135317D01*
X320540Y135442D01*
X320248D01*
X319915Y135359D01*
X319665Y135192D01*
G01X317440Y132942D02*
X317148Y132984D01*
X316815Y133109D01*
X316607Y133317D01*
X316523Y133609D01*
X316607Y133900D01*
X316857Y134150D01*
X317232Y134275D01*
X317648D01*
X317898Y134359D01*
X318107Y134567D01*
X318190Y134859D01*
X318065Y135150D01*
X317773Y135359D01*
X317440Y135442D01*
X317107Y135359D01*
X316815Y135150D01*
X316690Y134859D01*
X316773Y134567D01*
X316982Y134359D01*
X317232Y134275D01*
X317648D01*
X318023Y134150D01*
X318273Y133900D01*
X318357Y133609D01*
X318273Y133317D01*
X318065Y133109D01*
X317732Y132984D01*
X317440Y132942D01*
G01X315048Y133234D02*
X314757Y133025D01*
X314423Y132942D01*
X314090Y133025D01*
X313798Y133275D01*
X313590Y133650D01*
X313507Y134025D01*
Y134484D01*
X313590Y134859D01*
X313798Y135192D01*
X314048Y135359D01*
X314340Y135442D01*
X314673Y135359D01*
X314923Y135192D01*
X315090Y134942D01*
X315173Y134609D01*
X315090Y134317D01*
X314882Y134025D01*
X314632Y133859D01*
X314340Y133817D01*
X314007Y133900D01*
X313757Y134109D01*
X313507Y134484D01*
G01X325823Y143234D02*
X326073Y143359D01*
X326365Y143442D01*
X326698D01*
X327073Y143317D01*
X327365Y143109D01*
X327573Y142859D01*
X327740Y142442D01*
X327782Y142067D01*
X327698Y141692D01*
X327573Y141442D01*
X327323Y141192D01*
X327032Y141025D01*
X326740Y140942D01*
X326448D01*
X326157Y141025D01*
X325907Y141150D01*
X325698Y141317D01*
G01X324557D02*
X324307Y141109D01*
X324015Y140984D01*
X323640Y140942D01*
X323265Y141025D01*
X322973Y141192D01*
X322765Y141484D01*
X322723Y141817D01*
X322807Y142150D01*
X323015Y142359D01*
X323307Y142525D01*
X323598Y142567D01*
X323890Y142525D01*
X324265Y142359D01*
X324140Y143442D01*
X323015D01*
G01X320290Y142192D02*
X319457D01*
Y141442D01*
X319707Y141192D01*
X319998Y141025D01*
X320415Y140942D01*
X320832Y141025D01*
X321123Y141192D01*
X321373Y141442D01*
X321540Y141734D01*
X321623Y142067D01*
Y142359D01*
X321540Y142609D01*
X321373Y142900D01*
X321123Y143150D01*
X320873Y143317D01*
X320540Y143442D01*
X320248D01*
X319915Y143359D01*
X319665Y143192D01*
G01X318148Y141234D02*
X317857Y141025D01*
X317523Y140942D01*
X317190Y141025D01*
X316898Y141275D01*
X316690Y141650D01*
X316607Y142025D01*
Y142484D01*
X316690Y142859D01*
X316898Y143192D01*
X317148Y143359D01*
X317440Y143442D01*
X317773Y143359D01*
X318023Y143192D01*
X318190Y142942D01*
X318273Y142609D01*
X318190Y142317D01*
X317982Y142025D01*
X317732Y141859D01*
X317440Y141817D01*
X317107Y141900D01*
X316857Y142109D01*
X316607Y142484D01*
G01X315257Y141442D02*
X315007Y141150D01*
X314673Y140984D01*
X314298Y140942D01*
X313965Y140984D01*
X313632Y141192D01*
X313423Y141442D01*
X313382Y141692D01*
X313465Y141984D01*
X313757Y142192D01*
X314048Y142275D01*
X314423D01*
G01X314048D02*
X313798Y142400D01*
X313590Y142609D01*
X313507Y142859D01*
X313590Y143109D01*
X313798Y143317D01*
X314173Y143442D01*
X314548Y143400D01*
X314923Y143234D01*
G01X312907Y115718D02*
X313157Y115843D01*
X313449Y115926D01*
X313782D01*
X314157Y115801D01*
X314449Y115593D01*
X314657Y115343D01*
X314824Y114926D01*
X314866Y114551D01*
X314782Y114176D01*
X314657Y113926D01*
X314407Y113676D01*
X314116Y113509D01*
X313824Y113426D01*
X313532D01*
X313241Y113509D01*
X312991Y113634D01*
X312782Y113801D01*
G01X310724Y113426D02*
X310432Y113468D01*
X310099Y113593D01*
X309891Y113801D01*
X309807Y114093D01*
X309891Y114384D01*
X310141Y114634D01*
X310516Y114759D01*
X310932D01*
X311182Y114843D01*
X311391Y115051D01*
X311474Y115343D01*
X311349Y115634D01*
X311057Y115843D01*
X310724Y115926D01*
X310391Y115843D01*
X310099Y115634D01*
X309974Y115343D01*
X310057Y115051D01*
X310266Y114843D01*
X310516Y114759D01*
X310932D01*
X311307Y114634D01*
X311557Y114384D01*
X311641Y114093D01*
X311557Y113801D01*
X311349Y113593D01*
X311016Y113468D01*
X310724Y113426D01*
G01X307624Y115926D02*
Y113426D01*
G01X308582Y115926D02*
X306666D01*
G01X304524Y113426D02*
Y115926D01*
X305024Y115426D01*
G01Y113426D02*
X304024D01*
G01X336130Y110149D02*
X336380Y110274D01*
X336672Y110357D01*
X337005D01*
X337380Y110232D01*
X337672Y110024D01*
X337880Y109774D01*
X338047Y109357D01*
X338089Y108982D01*
X338005Y108607D01*
X337880Y108357D01*
X337630Y108107D01*
X337339Y107940D01*
X337047Y107857D01*
X336755D01*
X336464Y107940D01*
X336214Y108065D01*
X336005Y108232D01*
G01X333947Y107857D02*
X333655Y107899D01*
X333322Y108024D01*
X333114Y108232D01*
X333030Y108524D01*
X333114Y108815D01*
X333364Y109065D01*
X333739Y109190D01*
X334155D01*
X334405Y109274D01*
X334614Y109482D01*
X334697Y109774D01*
X334572Y110065D01*
X334280Y110274D01*
X333947Y110357D01*
X333614Y110274D01*
X333322Y110065D01*
X333197Y109774D01*
X333280Y109482D01*
X333489Y109274D01*
X333739Y109190D01*
X334155D01*
X334530Y109065D01*
X334780Y108815D01*
X334864Y108524D01*
X334780Y108232D01*
X334572Y108024D01*
X334239Y107899D01*
X333947Y107857D01*
G01X330847Y110357D02*
Y107857D01*
G01X331805Y110357D02*
X329889D01*
G01X328539Y109940D02*
X328289Y110190D01*
X327997Y110315D01*
X327664Y110357D01*
X327247Y110274D01*
X326955Y110065D01*
X326872Y109815D01*
X326914Y109565D01*
X327080Y109357D01*
X327914Y108940D01*
X328289Y108649D01*
X328539Y108232D01*
X328622Y107857D01*
X326872D01*
G01X325823Y139234D02*
X326073Y139359D01*
X326365Y139442D01*
X326698D01*
X327073Y139317D01*
X327365Y139109D01*
X327573Y138859D01*
X327740Y138442D01*
X327782Y138067D01*
X327698Y137692D01*
X327573Y137442D01*
X327323Y137192D01*
X327032Y137025D01*
X326740Y136942D01*
X326448D01*
X326157Y137025D01*
X325907Y137150D01*
X325698Y137317D01*
G01X323640Y136942D02*
X323348Y136984D01*
X323015Y137109D01*
X322807Y137317D01*
X322723Y137609D01*
X322807Y137900D01*
X323057Y138150D01*
X323432Y138275D01*
X323848D01*
X324098Y138359D01*
X324307Y138567D01*
X324390Y138859D01*
X324265Y139150D01*
X323973Y139359D01*
X323640Y139442D01*
X323307Y139359D01*
X323015Y139150D01*
X322890Y138859D01*
X322973Y138567D01*
X323182Y138359D01*
X323432Y138275D01*
X323848D01*
X324223Y138150D01*
X324473Y137900D01*
X324557Y137609D01*
X324473Y137317D01*
X324265Y137109D01*
X323932Y136984D01*
X323640Y136942D01*
G01X321457Y139442D02*
Y137650D01*
X321290Y137275D01*
X320957Y137025D01*
X320540Y136942D01*
X320123Y137025D01*
X319790Y137275D01*
X319623Y137650D01*
Y139442D01*
G01X318357Y137442D02*
X318107Y137150D01*
X317773Y136984D01*
X317398Y136942D01*
X317065Y136984D01*
X316732Y137192D01*
X316523Y137442D01*
X316482Y137692D01*
X316565Y137984D01*
X316857Y138192D01*
X317148Y138275D01*
X317523D01*
G01X317148D02*
X316898Y138400D01*
X316690Y138609D01*
X316607Y138859D01*
X316690Y139109D01*
X316898Y139317D01*
X317273Y139442D01*
X317648Y139400D01*
X318023Y139234D01*
G01X343120Y139235D02*
X343370Y139360D01*
X343662Y139443D01*
X343995D01*
X344370Y139318D01*
X344662Y139110D01*
X344870Y138860D01*
X345037Y138443D01*
X345079Y138068D01*
X344995Y137693D01*
X344870Y137443D01*
X344620Y137193D01*
X344329Y137026D01*
X344037Y136943D01*
X343745D01*
X343454Y137026D01*
X343204Y137151D01*
X342995Y137318D01*
G01X340937Y136943D02*
X340645Y136985D01*
X340312Y137110D01*
X340104Y137318D01*
X340020Y137610D01*
X340104Y137901D01*
X340354Y138151D01*
X340729Y138276D01*
X341145D01*
X341395Y138360D01*
X341604Y138568D01*
X341687Y138860D01*
X341562Y139151D01*
X341270Y139360D01*
X340937Y139443D01*
X340604Y139360D01*
X340312Y139151D01*
X340187Y138860D01*
X340270Y138568D01*
X340479Y138360D01*
X340729Y138276D01*
X341145D01*
X341520Y138151D01*
X341770Y137901D01*
X341854Y137610D01*
X341770Y137318D01*
X341562Y137110D01*
X341229Y136985D01*
X340937Y136943D01*
G01X338754Y139443D02*
Y137651D01*
X338587Y137276D01*
X338254Y137026D01*
X337837Y136943D01*
X337420Y137026D01*
X337087Y137276D01*
X336920Y137651D01*
Y139443D01*
G01X335529Y139026D02*
X335279Y139276D01*
X334987Y139401D01*
X334654Y139443D01*
X334237Y139360D01*
X333945Y139151D01*
X333862Y138901D01*
X333904Y138651D01*
X334070Y138443D01*
X334904Y138026D01*
X335279Y137735D01*
X335529Y137318D01*
X335612Y136943D01*
X333862D01*
G01X325823Y147234D02*
X326073Y147359D01*
X326365Y147442D01*
X326698D01*
X327073Y147317D01*
X327365Y147109D01*
X327573Y146859D01*
X327740Y146442D01*
X327782Y146067D01*
X327698Y145692D01*
X327573Y145442D01*
X327323Y145192D01*
X327032Y145025D01*
X326740Y144942D01*
X326448D01*
X326157Y145025D01*
X325907Y145150D01*
X325698Y145317D01*
G01X323640Y144942D02*
X323348Y144984D01*
X323015Y145109D01*
X322807Y145317D01*
X322723Y145609D01*
X322807Y145900D01*
X323057Y146150D01*
X323432Y146275D01*
X323848D01*
X324098Y146359D01*
X324307Y146567D01*
X324390Y146859D01*
X324265Y147150D01*
X323973Y147359D01*
X323640Y147442D01*
X323307Y147359D01*
X323015Y147150D01*
X322890Y146859D01*
X322973Y146567D01*
X323182Y146359D01*
X323432Y146275D01*
X323848D01*
X324223Y146150D01*
X324473Y145900D01*
X324557Y145609D01*
X324473Y145317D01*
X324265Y145109D01*
X323932Y144984D01*
X323640Y144942D01*
G01X320540Y147442D02*
Y144942D01*
G01X321498Y147442D02*
X319582D01*
G01X318232Y145984D02*
X317940Y146275D01*
X317690Y146442D01*
X317357Y146525D01*
X317065Y146442D01*
X316857Y146275D01*
X316690Y146025D01*
X316648Y145734D01*
X316690Y145484D01*
X316857Y145234D01*
X317107Y145025D01*
X317398Y144942D01*
X317732Y145025D01*
X318023Y145275D01*
X318190Y145650D01*
X318232Y146067D01*
X318148Y146609D01*
X318023Y146900D01*
X317815Y147192D01*
X317523Y147400D01*
X317232Y147442D01*
X316940Y147359D01*
X316732Y147150D01*
G01X343120Y147235D02*
X343370Y147360D01*
X343662Y147443D01*
X343995D01*
X344370Y147318D01*
X344662Y147110D01*
X344870Y146860D01*
X345037Y146443D01*
X345079Y146068D01*
X344995Y145693D01*
X344870Y145443D01*
X344620Y145193D01*
X344329Y145026D01*
X344037Y144943D01*
X343745D01*
X343454Y145026D01*
X343204Y145151D01*
X342995Y145318D01*
G01X340937Y144943D02*
X340645Y144985D01*
X340312Y145110D01*
X340104Y145318D01*
X340020Y145610D01*
X340104Y145901D01*
X340354Y146151D01*
X340729Y146276D01*
X341145D01*
X341395Y146360D01*
X341604Y146568D01*
X341687Y146860D01*
X341562Y147151D01*
X341270Y147360D01*
X340937Y147443D01*
X340604Y147360D01*
X340312Y147151D01*
X340187Y146860D01*
X340270Y146568D01*
X340479Y146360D01*
X340729Y146276D01*
X341145D01*
X341520Y146151D01*
X341770Y145901D01*
X341854Y145610D01*
X341770Y145318D01*
X341562Y145110D01*
X341229Y144985D01*
X340937Y144943D01*
G01X337837Y147443D02*
Y144943D01*
G01X338795Y147443D02*
X336879D01*
G01X335654Y145318D02*
X335404Y145110D01*
X335112Y144985D01*
X334737Y144943D01*
X334362Y145026D01*
X334070Y145193D01*
X333862Y145485D01*
X333820Y145818D01*
X333904Y146151D01*
X334112Y146360D01*
X334404Y146526D01*
X334695Y146568D01*
X334987Y146526D01*
X335362Y146360D01*
X335237Y147443D01*
X334112D01*
G01X359354Y138996D02*
X359604Y139121D01*
X359896Y139204D01*
X360229D01*
X360604Y139079D01*
X360896Y138871D01*
X361104Y138621D01*
X361271Y138204D01*
X361313Y137829D01*
X361229Y137454D01*
X361104Y137204D01*
X360854Y136954D01*
X360563Y136787D01*
X360271Y136704D01*
X359979D01*
X359688Y136787D01*
X359438Y136912D01*
X359229Y137079D01*
G01X357254Y136704D02*
X357171Y137246D01*
X357046Y137704D01*
X356879Y138121D01*
X356671Y138579D01*
X356338Y139204D01*
X358004D01*
G01X354988D02*
Y137412D01*
X354821Y137037D01*
X354488Y136787D01*
X354071Y136704D01*
X353654Y136787D01*
X353321Y137037D01*
X353154Y137412D01*
Y139204D01*
G01X351763Y138787D02*
X351513Y139037D01*
X351221Y139162D01*
X350888Y139204D01*
X350471Y139121D01*
X350179Y138912D01*
X350096Y138662D01*
X350138Y138412D01*
X350304Y138204D01*
X351138Y137787D01*
X351513Y137496D01*
X351763Y137079D01*
X351846Y136704D01*
X350096D01*
G01X359354Y146996D02*
X359604Y147121D01*
X359896Y147204D01*
X360229D01*
X360604Y147079D01*
X360896Y146871D01*
X361104Y146621D01*
X361271Y146204D01*
X361313Y145829D01*
X361229Y145454D01*
X361104Y145204D01*
X360854Y144954D01*
X360563Y144787D01*
X360271Y144704D01*
X359979D01*
X359688Y144787D01*
X359438Y144912D01*
X359229Y145079D01*
G01X357254Y144704D02*
X357171Y145246D01*
X357046Y145704D01*
X356879Y146121D01*
X356671Y146579D01*
X356338Y147204D01*
X358004D01*
G01X354071D02*
Y144704D01*
G01X355029Y147204D02*
X353113D01*
G01X351888Y145079D02*
X351638Y144871D01*
X351346Y144746D01*
X350971Y144704D01*
X350596Y144787D01*
X350304Y144954D01*
X350096Y145246D01*
X350054Y145579D01*
X350138Y145912D01*
X350346Y146121D01*
X350638Y146287D01*
X350929Y146329D01*
X351221Y146287D01*
X351596Y146121D01*
X351471Y147204D01*
X350346D01*
G01X342662Y466352D02*
X342912Y466477D01*
X343204Y466560D01*
X343537D01*
X343912Y466435D01*
X344204Y466227D01*
X344412Y465977D01*
X344579Y465560D01*
X344621Y465185D01*
X344537Y464810D01*
X344412Y464560D01*
X344162Y464310D01*
X343871Y464143D01*
X343579Y464060D01*
X343287D01*
X342996Y464143D01*
X342746Y464268D01*
X342537Y464435D01*
G01X341396D02*
X341146Y464227D01*
X340854Y464102D01*
X340479Y464060D01*
X340104Y464143D01*
X339812Y464310D01*
X339604Y464602D01*
X339562Y464935D01*
X339646Y465268D01*
X339854Y465477D01*
X340146Y465643D01*
X340437Y465685D01*
X340729Y465643D01*
X341104Y465477D01*
X340979Y466560D01*
X339854D01*
G01X337129Y465310D02*
X336296D01*
Y464560D01*
X336546Y464310D01*
X336837Y464143D01*
X337254Y464060D01*
X337671Y464143D01*
X337962Y464310D01*
X338212Y464560D01*
X338379Y464852D01*
X338462Y465185D01*
Y465477D01*
X338379Y465727D01*
X338212Y466018D01*
X337962Y466268D01*
X337712Y466435D01*
X337379Y466560D01*
X337087D01*
X336754Y466477D01*
X336504Y466310D01*
G01X334279Y464060D02*
Y466560D01*
X334779Y466060D01*
G01Y464060D02*
X333779D01*
G01X331179Y466560D02*
X331512Y466477D01*
X331762Y466268D01*
X331929Y466018D01*
X332054Y465685D01*
X332096Y465310D01*
X332054Y464935D01*
X331929Y464602D01*
X331762Y464352D01*
X331512Y464143D01*
X331179Y464060D01*
X330846Y464143D01*
X330596Y464352D01*
X330429Y464602D01*
X330304Y464935D01*
X330262Y465310D01*
X330304Y465685D01*
X330429Y466018D01*
X330596Y466268D01*
X330846Y466477D01*
X331179Y466560D01*
G01X328996Y464560D02*
X328746Y464268D01*
X328412Y464102D01*
X328037Y464060D01*
X327704Y464102D01*
X327371Y464310D01*
X327162Y464560D01*
X327121Y464810D01*
X327204Y465102D01*
X327496Y465310D01*
X327787Y465393D01*
X328162D01*
G01X327787D02*
X327537Y465518D01*
X327329Y465727D01*
X327246Y465977D01*
X327329Y466227D01*
X327537Y466435D01*
X327912Y466560D01*
X328287Y466518D01*
X328662Y466352D01*
G01X342662Y458352D02*
X342912Y458477D01*
X343204Y458560D01*
X343537D01*
X343912Y458435D01*
X344204Y458227D01*
X344412Y457977D01*
X344579Y457560D01*
X344621Y457185D01*
X344537Y456810D01*
X344412Y456560D01*
X344162Y456310D01*
X343871Y456143D01*
X343579Y456060D01*
X343287D01*
X342996Y456143D01*
X342746Y456268D01*
X342537Y456435D01*
G01X341396D02*
X341146Y456227D01*
X340854Y456102D01*
X340479Y456060D01*
X340104Y456143D01*
X339812Y456310D01*
X339604Y456602D01*
X339562Y456935D01*
X339646Y457268D01*
X339854Y457477D01*
X340146Y457643D01*
X340437Y457685D01*
X340729Y457643D01*
X341104Y457477D01*
X340979Y458560D01*
X339854D01*
G01X337129Y457310D02*
X336296D01*
Y456560D01*
X336546Y456310D01*
X336837Y456143D01*
X337254Y456060D01*
X337671Y456143D01*
X337962Y456310D01*
X338212Y456560D01*
X338379Y456852D01*
X338462Y457185D01*
Y457477D01*
X338379Y457727D01*
X338212Y458018D01*
X337962Y458268D01*
X337712Y458435D01*
X337379Y458560D01*
X337087D01*
X336754Y458477D01*
X336504Y458310D01*
G01X334279Y456060D02*
Y458560D01*
X334779Y458060D01*
G01Y456060D02*
X333779D01*
G01X331179Y458560D02*
X331512Y458477D01*
X331762Y458268D01*
X331929Y458018D01*
X332054Y457685D01*
X332096Y457310D01*
X332054Y456935D01*
X331929Y456602D01*
X331762Y456352D01*
X331512Y456143D01*
X331179Y456060D01*
X330846Y456143D01*
X330596Y456352D01*
X330429Y456602D01*
X330304Y456935D01*
X330262Y457310D01*
X330304Y457685D01*
X330429Y458018D01*
X330596Y458268D01*
X330846Y458477D01*
X331179Y458560D01*
G01X328162Y456060D02*
X328079Y456602D01*
X327954Y457060D01*
X327787Y457477D01*
X327579Y457935D01*
X327246Y458560D01*
X328912D01*
G01X362213Y457759D02*
X362463Y457884D01*
X362755Y457967D01*
X363088D01*
X363463Y457842D01*
X363755Y457634D01*
X363963Y457384D01*
X364130Y456967D01*
X364172Y456592D01*
X364088Y456217D01*
X363963Y455967D01*
X363713Y455717D01*
X363422Y455550D01*
X363130Y455467D01*
X362838D01*
X362547Y455550D01*
X362297Y455675D01*
X362088Y455842D01*
G01X360947D02*
X360697Y455634D01*
X360405Y455509D01*
X360030Y455467D01*
X359655Y455550D01*
X359363Y455717D01*
X359155Y456009D01*
X359113Y456342D01*
X359197Y456675D01*
X359405Y456884D01*
X359697Y457050D01*
X359988Y457092D01*
X360280Y457050D01*
X360655Y456884D01*
X360530Y457967D01*
X359405D01*
G01X356680Y456717D02*
X355847D01*
Y455967D01*
X356097Y455717D01*
X356388Y455550D01*
X356805Y455467D01*
X357222Y455550D01*
X357513Y455717D01*
X357763Y455967D01*
X357930Y456259D01*
X358013Y456592D01*
Y456884D01*
X357930Y457134D01*
X357763Y457425D01*
X357513Y457675D01*
X357263Y457842D01*
X356930Y457967D01*
X356638D01*
X356305Y457884D01*
X356055Y457717D01*
G01X353830Y455467D02*
Y457967D01*
X354330Y457467D01*
G01Y455467D02*
X353330D01*
G01X350730Y457967D02*
X351063Y457884D01*
X351313Y457675D01*
X351480Y457425D01*
X351605Y457092D01*
X351647Y456717D01*
X351605Y456342D01*
X351480Y456009D01*
X351313Y455759D01*
X351063Y455550D01*
X350730Y455467D01*
X350397Y455550D01*
X350147Y455759D01*
X349980Y456009D01*
X349855Y456342D01*
X349813Y456717D01*
X349855Y457092D01*
X349980Y457425D01*
X350147Y457675D01*
X350397Y457884D01*
X350730Y457967D01*
G01X347630Y455467D02*
X347338Y455509D01*
X347005Y455634D01*
X346797Y455842D01*
X346713Y456134D01*
X346797Y456425D01*
X347047Y456675D01*
X347422Y456800D01*
X347838D01*
X348088Y456884D01*
X348297Y457092D01*
X348380Y457384D01*
X348255Y457675D01*
X347963Y457884D01*
X347630Y457967D01*
X347297Y457884D01*
X347005Y457675D01*
X346880Y457384D01*
X346963Y457092D01*
X347172Y456884D01*
X347422Y456800D01*
X347838D01*
X348213Y456675D01*
X348463Y456425D01*
X348547Y456134D01*
X348463Y455842D01*
X348255Y455634D01*
X347922Y455509D01*
X347630Y455467D01*
G01X362213Y465759D02*
X362463Y465884D01*
X362755Y465967D01*
X363088D01*
X363463Y465842D01*
X363755Y465634D01*
X363963Y465384D01*
X364130Y464967D01*
X364172Y464592D01*
X364088Y464217D01*
X363963Y463967D01*
X363713Y463717D01*
X363422Y463550D01*
X363130Y463467D01*
X362838D01*
X362547Y463550D01*
X362297Y463675D01*
X362088Y463842D01*
G01X360947D02*
X360697Y463634D01*
X360405Y463509D01*
X360030Y463467D01*
X359655Y463550D01*
X359363Y463717D01*
X359155Y464009D01*
X359113Y464342D01*
X359197Y464675D01*
X359405Y464884D01*
X359697Y465050D01*
X359988Y465092D01*
X360280Y465050D01*
X360655Y464884D01*
X360530Y465967D01*
X359405D01*
G01X356680Y464717D02*
X355847D01*
Y463967D01*
X356097Y463717D01*
X356388Y463550D01*
X356805Y463467D01*
X357222Y463550D01*
X357513Y463717D01*
X357763Y463967D01*
X357930Y464259D01*
X358013Y464592D01*
Y464884D01*
X357930Y465134D01*
X357763Y465425D01*
X357513Y465675D01*
X357263Y465842D01*
X356930Y465967D01*
X356638D01*
X356305Y465884D01*
X356055Y465717D01*
G01X353830Y463467D02*
Y465967D01*
X354330Y465467D01*
G01Y463467D02*
X353330D01*
G01X350730Y465967D02*
X351063Y465884D01*
X351313Y465675D01*
X351480Y465425D01*
X351605Y465092D01*
X351647Y464717D01*
X351605Y464342D01*
X351480Y464009D01*
X351313Y463759D01*
X351063Y463550D01*
X350730Y463467D01*
X350397Y463550D01*
X350147Y463759D01*
X349980Y464009D01*
X349855Y464342D01*
X349813Y464717D01*
X349855Y465092D01*
X349980Y465425D01*
X350147Y465675D01*
X350397Y465884D01*
X350730Y465967D01*
G01X347130Y463467D02*
Y465967D01*
X348672Y464175D01*
X346588D01*
G01X322047Y458827D02*
X322297Y458952D01*
X322589Y459035D01*
X322922D01*
X323297Y458910D01*
X323589Y458702D01*
X323797Y458452D01*
X323964Y458035D01*
X324006Y457660D01*
X323922Y457285D01*
X323797Y457035D01*
X323547Y456785D01*
X323256Y456618D01*
X322964Y456535D01*
X322672D01*
X322381Y456618D01*
X322131Y456743D01*
X321922Y456910D01*
G01X320781D02*
X320531Y456702D01*
X320239Y456577D01*
X319864Y456535D01*
X319489Y456618D01*
X319197Y456785D01*
X318989Y457077D01*
X318947Y457410D01*
X319031Y457743D01*
X319239Y457952D01*
X319531Y458118D01*
X319822Y458160D01*
X320114Y458118D01*
X320489Y457952D01*
X320364Y459035D01*
X319239D01*
G01X316514Y457785D02*
X315681D01*
Y457035D01*
X315931Y456785D01*
X316222Y456618D01*
X316639Y456535D01*
X317056Y456618D01*
X317347Y456785D01*
X317597Y457035D01*
X317764Y457327D01*
X317847Y457660D01*
Y457952D01*
X317764Y458202D01*
X317597Y458493D01*
X317347Y458743D01*
X317097Y458910D01*
X316764Y459035D01*
X316472D01*
X316139Y458952D01*
X315889Y458785D01*
G01X313664Y456535D02*
Y459035D01*
X314164Y458535D01*
G01Y456535D02*
X313164D01*
G01X310564Y459035D02*
X310897Y458952D01*
X311147Y458743D01*
X311314Y458493D01*
X311439Y458160D01*
X311481Y457785D01*
X311439Y457410D01*
X311314Y457077D01*
X311147Y456827D01*
X310897Y456618D01*
X310564Y456535D01*
X310231Y456618D01*
X309981Y456827D01*
X309814Y457077D01*
X309689Y457410D01*
X309647Y457785D01*
X309689Y458160D01*
X309814Y458493D01*
X309981Y458743D01*
X310231Y458952D01*
X310564Y459035D01*
G01X308256Y457577D02*
X307964Y457868D01*
X307714Y458035D01*
X307381Y458118D01*
X307089Y458035D01*
X306881Y457868D01*
X306714Y457618D01*
X306672Y457327D01*
X306714Y457077D01*
X306881Y456827D01*
X307131Y456618D01*
X307422Y456535D01*
X307756Y456618D01*
X308047Y456868D01*
X308214Y457243D01*
X308256Y457660D01*
X308172Y458202D01*
X308047Y458493D01*
X307839Y458785D01*
X307547Y458993D01*
X307256Y459035D01*
X306964Y458952D01*
X306756Y458743D01*
G01X322047Y466827D02*
X322297Y466952D01*
X322589Y467035D01*
X322922D01*
X323297Y466910D01*
X323589Y466702D01*
X323797Y466452D01*
X323964Y466035D01*
X324006Y465660D01*
X323922Y465285D01*
X323797Y465035D01*
X323547Y464785D01*
X323256Y464618D01*
X322964Y464535D01*
X322672D01*
X322381Y464618D01*
X322131Y464743D01*
X321922Y464910D01*
G01X320781D02*
X320531Y464702D01*
X320239Y464577D01*
X319864Y464535D01*
X319489Y464618D01*
X319197Y464785D01*
X318989Y465077D01*
X318947Y465410D01*
X319031Y465743D01*
X319239Y465952D01*
X319531Y466118D01*
X319822Y466160D01*
X320114Y466118D01*
X320489Y465952D01*
X320364Y467035D01*
X319239D01*
G01X316514Y465785D02*
X315681D01*
Y465035D01*
X315931Y464785D01*
X316222Y464618D01*
X316639Y464535D01*
X317056Y464618D01*
X317347Y464785D01*
X317597Y465035D01*
X317764Y465327D01*
X317847Y465660D01*
Y465952D01*
X317764Y466202D01*
X317597Y466493D01*
X317347Y466743D01*
X317097Y466910D01*
X316764Y467035D01*
X316472D01*
X316139Y466952D01*
X315889Y466785D01*
G01X313664Y464535D02*
Y467035D01*
X314164Y466535D01*
G01Y464535D02*
X313164D01*
G01X310564Y467035D02*
X310897Y466952D01*
X311147Y466743D01*
X311314Y466493D01*
X311439Y466160D01*
X311481Y465785D01*
X311439Y465410D01*
X311314Y465077D01*
X311147Y464827D01*
X310897Y464618D01*
X310564Y464535D01*
X310231Y464618D01*
X309981Y464827D01*
X309814Y465077D01*
X309689Y465410D01*
X309647Y465785D01*
X309689Y466160D01*
X309814Y466493D01*
X309981Y466743D01*
X310231Y466952D01*
X310564Y467035D01*
G01X308256Y466618D02*
X308006Y466868D01*
X307714Y466993D01*
X307381Y467035D01*
X306964Y466952D01*
X306672Y466743D01*
X306589Y466493D01*
X306631Y466243D01*
X306797Y466035D01*
X307631Y465618D01*
X308006Y465327D01*
X308256Y464910D01*
X308339Y464535D01*
X306589D01*
G01X322047Y454827D02*
X322297Y454952D01*
X322589Y455035D01*
X322922D01*
X323297Y454910D01*
X323589Y454702D01*
X323797Y454452D01*
X323964Y454035D01*
X324006Y453660D01*
X323922Y453285D01*
X323797Y453035D01*
X323547Y452785D01*
X323256Y452618D01*
X322964Y452535D01*
X322672D01*
X322381Y452618D01*
X322131Y452743D01*
X321922Y452910D01*
G01X319864Y452535D02*
X319572Y452577D01*
X319239Y452702D01*
X319031Y452910D01*
X318947Y453202D01*
X319031Y453493D01*
X319281Y453743D01*
X319656Y453868D01*
X320072D01*
X320322Y453952D01*
X320531Y454160D01*
X320614Y454452D01*
X320489Y454743D01*
X320197Y454952D01*
X319864Y455035D01*
X319531Y454952D01*
X319239Y454743D01*
X319114Y454452D01*
X319197Y454160D01*
X319406Y453952D01*
X319656Y453868D01*
X320072D01*
X320447Y453743D01*
X320697Y453493D01*
X320781Y453202D01*
X320697Y452910D01*
X320489Y452702D01*
X320156Y452577D01*
X319864Y452535D01*
G01X317847D02*
Y455035D01*
X316764Y452952D01*
X315681Y455035D01*
Y452535D01*
G01X314456Y454618D02*
X314206Y454868D01*
X313914Y454993D01*
X313581Y455035D01*
X313164Y454952D01*
X312872Y454743D01*
X312789Y454493D01*
X312831Y454243D01*
X312997Y454035D01*
X313831Y453618D01*
X314206Y453327D01*
X314456Y452910D01*
X314539Y452535D01*
X312789D01*
G01X342662Y454352D02*
X342912Y454477D01*
X343204Y454560D01*
X343537D01*
X343912Y454435D01*
X344204Y454227D01*
X344412Y453977D01*
X344579Y453560D01*
X344621Y453185D01*
X344537Y452810D01*
X344412Y452560D01*
X344162Y452310D01*
X343871Y452143D01*
X343579Y452060D01*
X343287D01*
X342996Y452143D01*
X342746Y452268D01*
X342537Y452435D01*
G01X340479Y452060D02*
X340187Y452102D01*
X339854Y452227D01*
X339646Y452435D01*
X339562Y452727D01*
X339646Y453018D01*
X339896Y453268D01*
X340271Y453393D01*
X340687D01*
X340937Y453477D01*
X341146Y453685D01*
X341229Y453977D01*
X341104Y454268D01*
X340812Y454477D01*
X340479Y454560D01*
X340146Y454477D01*
X339854Y454268D01*
X339729Y453977D01*
X339812Y453685D01*
X340021Y453477D01*
X340271Y453393D01*
X340687D01*
X341062Y453268D01*
X341312Y453018D01*
X341396Y452727D01*
X341312Y452435D01*
X341104Y452227D01*
X340771Y452102D01*
X340479Y452060D01*
G01X338462D02*
Y454560D01*
X337379Y452477D01*
X336296Y454560D01*
Y452060D01*
G01X334279D02*
Y454560D01*
X334779Y454060D01*
G01Y452060D02*
X333779D01*
G01X322047Y462827D02*
X322297Y462952D01*
X322589Y463035D01*
X322922D01*
X323297Y462910D01*
X323589Y462702D01*
X323797Y462452D01*
X323964Y462035D01*
X324006Y461660D01*
X323922Y461285D01*
X323797Y461035D01*
X323547Y460785D01*
X323256Y460618D01*
X322964Y460535D01*
X322672D01*
X322381Y460618D01*
X322131Y460743D01*
X321922Y460910D01*
G01X319864Y460535D02*
X319572Y460577D01*
X319239Y460702D01*
X319031Y460910D01*
X318947Y461202D01*
X319031Y461493D01*
X319281Y461743D01*
X319656Y461868D01*
X320072D01*
X320322Y461952D01*
X320531Y462160D01*
X320614Y462452D01*
X320489Y462743D01*
X320197Y462952D01*
X319864Y463035D01*
X319531Y462952D01*
X319239Y462743D01*
X319114Y462452D01*
X319197Y462160D01*
X319406Y461952D01*
X319656Y461868D01*
X320072D01*
X320447Y461743D01*
X320697Y461493D01*
X320781Y461202D01*
X320697Y460910D01*
X320489Y460702D01*
X320156Y460577D01*
X319864Y460535D01*
G01X317597Y463035D02*
Y460535D01*
X315931D01*
G01X314456Y461577D02*
X314164Y461868D01*
X313914Y462035D01*
X313581Y462118D01*
X313289Y462035D01*
X313081Y461868D01*
X312914Y461618D01*
X312872Y461327D01*
X312914Y461077D01*
X313081Y460827D01*
X313331Y460618D01*
X313622Y460535D01*
X313956Y460618D01*
X314247Y460868D01*
X314414Y461243D01*
X314456Y461660D01*
X314372Y462202D01*
X314247Y462493D01*
X314039Y462785D01*
X313747Y462993D01*
X313456Y463035D01*
X313164Y462952D01*
X312956Y462743D01*
G01X342662Y462352D02*
X342912Y462477D01*
X343204Y462560D01*
X343537D01*
X343912Y462435D01*
X344204Y462227D01*
X344412Y461977D01*
X344579Y461560D01*
X344621Y461185D01*
X344537Y460810D01*
X344412Y460560D01*
X344162Y460310D01*
X343871Y460143D01*
X343579Y460060D01*
X343287D01*
X342996Y460143D01*
X342746Y460268D01*
X342537Y460435D01*
G01X340479Y460060D02*
X340187Y460102D01*
X339854Y460227D01*
X339646Y460435D01*
X339562Y460727D01*
X339646Y461018D01*
X339896Y461268D01*
X340271Y461393D01*
X340687D01*
X340937Y461477D01*
X341146Y461685D01*
X341229Y461977D01*
X341104Y462268D01*
X340812Y462477D01*
X340479Y462560D01*
X340146Y462477D01*
X339854Y462268D01*
X339729Y461977D01*
X339812Y461685D01*
X340021Y461477D01*
X340271Y461393D01*
X340687D01*
X341062Y461268D01*
X341312Y461018D01*
X341396Y460727D01*
X341312Y460435D01*
X341104Y460227D01*
X340771Y460102D01*
X340479Y460060D01*
G01X338212Y462560D02*
Y460060D01*
X336546D01*
G01X335196Y460435D02*
X334946Y460227D01*
X334654Y460102D01*
X334279Y460060D01*
X333904Y460143D01*
X333612Y460310D01*
X333404Y460602D01*
X333362Y460935D01*
X333446Y461268D01*
X333654Y461477D01*
X333946Y461643D01*
X334237Y461685D01*
X334529Y461643D01*
X334904Y461477D01*
X334779Y462560D01*
X333654D01*
G01X362213Y453759D02*
X362463Y453884D01*
X362755Y453967D01*
X363088D01*
X363463Y453842D01*
X363755Y453634D01*
X363963Y453384D01*
X364130Y452967D01*
X364172Y452592D01*
X364088Y452217D01*
X363963Y451967D01*
X363713Y451717D01*
X363422Y451550D01*
X363130Y451467D01*
X362838D01*
X362547Y451550D01*
X362297Y451675D01*
X362088Y451842D01*
G01X360113Y451467D02*
X360030Y452009D01*
X359905Y452467D01*
X359738Y452884D01*
X359530Y453342D01*
X359197Y453967D01*
X360863D01*
G01X358013Y451467D02*
Y453967D01*
X356930Y451884D01*
X355847Y453967D01*
Y451467D01*
G01X354622Y453550D02*
X354372Y453800D01*
X354080Y453925D01*
X353747Y453967D01*
X353330Y453884D01*
X353038Y453675D01*
X352955Y453425D01*
X352997Y453175D01*
X353163Y452967D01*
X353997Y452550D01*
X354372Y452259D01*
X354622Y451842D01*
X354705Y451467D01*
X352955D01*
G01X362213Y461759D02*
X362463Y461884D01*
X362755Y461967D01*
X363088D01*
X363463Y461842D01*
X363755Y461634D01*
X363963Y461384D01*
X364130Y460967D01*
X364172Y460592D01*
X364088Y460217D01*
X363963Y459967D01*
X363713Y459717D01*
X363422Y459550D01*
X363130Y459467D01*
X362838D01*
X362547Y459550D01*
X362297Y459675D01*
X362088Y459842D01*
G01X360113Y459467D02*
X360030Y460009D01*
X359905Y460467D01*
X359738Y460884D01*
X359530Y461342D01*
X359197Y461967D01*
X360863D01*
G01X357763D02*
Y459467D01*
X356097D01*
G01X354747Y459842D02*
X354497Y459634D01*
X354205Y459509D01*
X353830Y459467D01*
X353455Y459550D01*
X353163Y459717D01*
X352955Y460009D01*
X352913Y460342D01*
X352997Y460675D01*
X353205Y460884D01*
X353497Y461050D01*
X353788Y461092D01*
X354080Y461050D01*
X354455Y460884D01*
X354330Y461967D01*
X353205D01*
G01X346125Y485840D02*
Y488340D01*
X345084D01*
X344750Y488215D01*
X344542Y488048D01*
X344459Y487715D01*
X344542Y487382D01*
X344792Y487173D01*
X345084Y487048D01*
X346125D01*
G01X345084D02*
X344459Y485840D01*
G01X342275D02*
X342192Y486382D01*
X342067Y486840D01*
X341900Y487257D01*
X341692Y487715D01*
X341359Y488340D01*
X343025D01*
G01X339925D02*
Y485840D01*
X338259D01*
G01X336784Y487923D02*
X336534Y488173D01*
X336242Y488298D01*
X335909Y488340D01*
X335492Y488257D01*
X335200Y488048D01*
X335117Y487798D01*
X335159Y487548D01*
X335325Y487340D01*
X336159Y486923D01*
X336534Y486632D01*
X336784Y486215D01*
X336867Y485840D01*
X335117D01*
G01X312244Y492009D02*
X312494Y492134D01*
X312786Y492217D01*
X313119D01*
X313494Y492092D01*
X313786Y491884D01*
X313994Y491634D01*
X314161Y491217D01*
X314203Y490842D01*
X314119Y490467D01*
X313994Y490217D01*
X313744Y489967D01*
X313453Y489800D01*
X313161Y489717D01*
X312869D01*
X312578Y489800D01*
X312328Y489925D01*
X312119Y490092D01*
G01X310061Y489717D02*
X309769Y489759D01*
X309436Y489884D01*
X309228Y490092D01*
X309144Y490384D01*
X309228Y490675D01*
X309478Y490925D01*
X309853Y491050D01*
X310269D01*
X310519Y491134D01*
X310728Y491342D01*
X310811Y491634D01*
X310686Y491925D01*
X310394Y492134D01*
X310061Y492217D01*
X309728Y492134D01*
X309436Y491925D01*
X309311Y491634D01*
X309394Y491342D01*
X309603Y491134D01*
X309853Y491050D01*
X310269D01*
X310644Y490925D01*
X310894Y490675D01*
X310978Y490384D01*
X310894Y490092D01*
X310686Y489884D01*
X310353Y489759D01*
X310061Y489717D01*
G01X308044D02*
Y492217D01*
X306961Y490134D01*
X305878Y492217D01*
Y489717D01*
G01X304569Y490009D02*
X304278Y489800D01*
X303944Y489717D01*
X303611Y489800D01*
X303319Y490050D01*
X303111Y490425D01*
X303028Y490800D01*
Y491259D01*
X303111Y491634D01*
X303319Y491967D01*
X303569Y492134D01*
X303861Y492217D01*
X304194Y492134D01*
X304444Y491967D01*
X304611Y491717D01*
X304694Y491384D01*
X304611Y491092D01*
X304403Y490800D01*
X304153Y490634D01*
X303861Y490592D01*
X303528Y490675D01*
X303278Y490884D01*
X303028Y491259D01*
G01X323839Y487779D02*
X324089Y487904D01*
X324381Y487987D01*
X324714D01*
X325089Y487862D01*
X325381Y487654D01*
X325589Y487404D01*
X325756Y486987D01*
X325798Y486612D01*
X325714Y486237D01*
X325589Y485987D01*
X325339Y485737D01*
X325048Y485570D01*
X324756Y485487D01*
X324464D01*
X324173Y485570D01*
X323923Y485695D01*
X323714Y485862D01*
G01X321656Y485487D02*
X321364Y485529D01*
X321031Y485654D01*
X320823Y485862D01*
X320739Y486154D01*
X320823Y486445D01*
X321073Y486695D01*
X321448Y486820D01*
X321864D01*
X322114Y486904D01*
X322323Y487112D01*
X322406Y487404D01*
X322281Y487695D01*
X321989Y487904D01*
X321656Y487987D01*
X321323Y487904D01*
X321031Y487695D01*
X320906Y487404D01*
X320989Y487112D01*
X321198Y486904D01*
X321448Y486820D01*
X321864D01*
X322239Y486695D01*
X322489Y486445D01*
X322573Y486154D01*
X322489Y485862D01*
X322281Y485654D01*
X321948Y485529D01*
X321656Y485487D01*
G01X319639D02*
Y487987D01*
X318556Y485904D01*
X317473Y487987D01*
Y485487D01*
G01X315456D02*
Y487987D01*
X315956Y487487D01*
G01Y485487D02*
X314956D01*
G01X312356Y487987D02*
X312689Y487904D01*
X312939Y487695D01*
X313106Y487445D01*
X313231Y487112D01*
X313273Y486737D01*
X313231Y486362D01*
X313106Y486029D01*
X312939Y485779D01*
X312689Y485570D01*
X312356Y485487D01*
X312023Y485570D01*
X311773Y485779D01*
X311606Y486029D01*
X311481Y486362D01*
X311439Y486737D01*
X311481Y487112D01*
X311606Y487445D01*
X311773Y487695D01*
X312023Y487904D01*
X312356Y487987D01*
G01X341014Y491037D02*
X340681Y490829D01*
X340306Y490704D01*
X339972D01*
X339639Y490829D01*
X339389Y491037D01*
X339264Y491329D01*
X339347Y491621D01*
X339556Y491871D01*
X339931Y492037D01*
X340431Y492121D01*
X340722Y492287D01*
X340847Y492579D01*
X340764Y492871D01*
X340556Y493079D01*
X340264Y493204D01*
X339972D01*
X339681Y493121D01*
X339431Y492912D01*
G01X337914Y490704D02*
Y493204D01*
G01X336164D02*
Y490704D01*
G01Y491954D02*
X337914D01*
G01X334022Y490704D02*
X333939Y491246D01*
X333814Y491704D01*
X333647Y492121D01*
X333439Y492579D01*
X333106Y493204D01*
X334772D01*
G01X331672D02*
Y490704D01*
X330006D01*
G01X328531Y492787D02*
X328281Y493037D01*
X327989Y493162D01*
X327656Y493204D01*
X327239Y493121D01*
X326947Y492912D01*
X326864Y492662D01*
X326906Y492412D01*
X327072Y492204D01*
X327906Y491787D01*
X328281Y491496D01*
X328531Y491079D01*
X328614Y490704D01*
X326864D01*
G01X362063Y490677D02*
X361730Y490469D01*
X361355Y490344D01*
X361021D01*
X360688Y490469D01*
X360438Y490677D01*
X360313Y490969D01*
X360396Y491261D01*
X360605Y491511D01*
X360980Y491677D01*
X361480Y491761D01*
X361771Y491927D01*
X361896Y492219D01*
X361813Y492511D01*
X361605Y492719D01*
X361313Y492844D01*
X361021D01*
X360730Y492761D01*
X360480Y492552D01*
G01X358963Y490344D02*
Y492844D01*
G01X357213D02*
Y490344D01*
G01Y491594D02*
X358963D01*
G01X355071Y490344D02*
X354988Y490886D01*
X354863Y491344D01*
X354696Y491761D01*
X354488Y492219D01*
X354155Y492844D01*
X355821D01*
G01X352721D02*
Y490344D01*
X351055D01*
G01X348788D02*
Y492844D01*
X349288Y492344D01*
G01Y490344D02*
X348288D01*
G01X354477Y619315D02*
X354727Y619440D01*
X355019Y619523D01*
X355352D01*
X355727Y619398D01*
X356019Y619190D01*
X356227Y618940D01*
X356394Y618523D01*
X356436Y618148D01*
X356352Y617773D01*
X356227Y617523D01*
X355977Y617273D01*
X355686Y617106D01*
X355394Y617023D01*
X355102D01*
X354811Y617106D01*
X354561Y617231D01*
X354352Y617398D01*
G01X352294Y617023D02*
X352002Y617065D01*
X351669Y617190D01*
X351461Y617398D01*
X351377Y617690D01*
X351461Y617981D01*
X351711Y618231D01*
X352086Y618356D01*
X352502D01*
X352752Y618440D01*
X352961Y618648D01*
X353044Y618940D01*
X352919Y619231D01*
X352627Y619440D01*
X352294Y619523D01*
X351961Y619440D01*
X351669Y619231D01*
X351544Y618940D01*
X351627Y618648D01*
X351836Y618440D01*
X352086Y618356D01*
X352502D01*
X352877Y618231D01*
X353127Y617981D01*
X353211Y617690D01*
X353127Y617398D01*
X352919Y617190D01*
X352586Y617065D01*
X352294Y617023D01*
G01X350027Y619523D02*
Y617023D01*
X348361D01*
G01X347011Y617523D02*
X346761Y617231D01*
X346427Y617065D01*
X346052Y617023D01*
X345719Y617065D01*
X345386Y617273D01*
X345177Y617523D01*
X345136Y617773D01*
X345219Y618065D01*
X345511Y618273D01*
X345802Y618356D01*
X346177D01*
G01X345802D02*
X345552Y618481D01*
X345344Y618690D01*
X345261Y618940D01*
X345344Y619190D01*
X345552Y619398D01*
X345927Y619523D01*
X346302Y619481D01*
X346677Y619315D01*
G01X353000Y657900D02*
Y660900D01*
X352000D01*
X351600Y660750D01*
X351300Y660550D01*
X351050Y660250D01*
X350850Y659900D01*
X350800Y659400D01*
X350850Y658900D01*
X351050Y658550D01*
X351300Y658250D01*
X351600Y658050D01*
X352000Y657900D01*
X353000D01*
G01X349050Y659250D02*
X347450D01*
X347600Y659600D01*
X347850Y659800D01*
X348200Y659900D01*
X348550Y659850D01*
X348850Y659700D01*
X349050Y659350D01*
X349150Y659050D01*
Y658750D01*
X349050Y658450D01*
X348800Y658150D01*
X348500Y657950D01*
X348150Y657900D01*
X347800Y658000D01*
X347450Y658300D01*
G01X344700Y657900D02*
Y660900D01*
G01X341100D02*
Y657900D01*
G01X341800Y659900D02*
X340400D01*
G01X336600Y657900D02*
Y659900D01*
G01Y659550D02*
X336800Y659750D01*
X337100Y659850D01*
X337450Y659900D01*
X337800Y659800D01*
X338100Y659600D01*
X338300Y659300D01*
X338400Y658900D01*
X338300Y658500D01*
X338100Y658200D01*
X337800Y658000D01*
X337450Y657900D01*
X337100Y657950D01*
X336800Y658100D01*
X336600Y658300D01*
G01X335400Y656900D02*
X332400D01*
G01X331300Y660900D02*
Y657900D01*
X329300D01*
G01X327800Y658500D02*
X327500Y658150D01*
X327100Y657950D01*
X326650Y657900D01*
X326250Y657950D01*
X325850Y658200D01*
X325600Y658500D01*
X325550Y658800D01*
X325650Y659150D01*
X326000Y659400D01*
X326350Y659500D01*
X326800D01*
G01X326350D02*
X326050Y659650D01*
X325800Y659900D01*
X325700Y660200D01*
X325800Y660500D01*
X326050Y660750D01*
X326500Y660900D01*
X326950Y660850D01*
X327400Y660650D01*
G01X324600Y656900D02*
X321600D01*
G01X320600Y658350D02*
X320300Y658100D01*
X319950Y657950D01*
X319500Y657900D01*
X319050Y658000D01*
X318700Y658200D01*
X318450Y658550D01*
X318400Y658950D01*
X318500Y659350D01*
X318750Y659600D01*
X319100Y659800D01*
X319450Y659850D01*
X319800Y659800D01*
X320250Y659600D01*
X320100Y660900D01*
X318750D01*
G01X315900Y659900D02*
Y657900D01*
G01Y660700D02*
X316000Y660750D01*
Y660850D01*
X315900Y660900D01*
X315800Y660850D01*
Y660750D01*
X315900Y660700D01*
G01X313150Y657900D02*
Y659900D01*
G01Y659400D02*
X312950Y659650D01*
X312650Y659850D01*
X312250Y659900D01*
X311900Y659850D01*
X311600Y659650D01*
X311450Y659300D01*
Y657900D01*
G01X307900Y659650D02*
X308250Y659850D01*
X308550Y659900D01*
X308950Y659800D01*
X309250Y659600D01*
X309450Y659250D01*
X309500Y658900D01*
X309450Y658550D01*
X309250Y658250D01*
X308950Y658000D01*
X308550Y657900D01*
X308200Y658000D01*
X307900Y658200D01*
G01X305950Y657900D02*
Y660900D01*
G01Y659450D02*
X305700Y659700D01*
X305450Y659850D01*
X305050Y659900D01*
X304750Y659850D01*
X304400Y659650D01*
X304250Y659350D01*
Y657900D01*
G01X379578Y-417D02*
X379348Y-107D01*
X379080Y48D01*
X378773Y100D01*
X378390Y-3D01*
X378122Y-262D01*
X378045Y-572D01*
X378083Y-882D01*
X378237Y-1140D01*
X379003Y-1657D01*
X379348Y-2018D01*
X379578Y-2535D01*
X379655Y-3000D01*
X378045D01*
G01X376478Y-417D02*
X376248Y-107D01*
X375980Y48D01*
X375673Y100D01*
X375290Y-3D01*
X375022Y-262D01*
X374945Y-572D01*
X374983Y-882D01*
X375137Y-1140D01*
X375903Y-1657D01*
X376248Y-2018D01*
X376478Y-2535D01*
X376555Y-3000D01*
X374945D01*
G01X372650D02*
Y100D01*
X373110Y-520D01*
G01Y-3000D02*
X372190D01*
G01X399578Y-1417D02*
X399348Y-1107D01*
X399080Y-952D01*
X398773Y-900D01*
X398390Y-1003D01*
X398122Y-1262D01*
X398045Y-1572D01*
X398083Y-1882D01*
X398237Y-2140D01*
X399003Y-2657D01*
X399348Y-3018D01*
X399578Y-3535D01*
X399655Y-4000D01*
X398045D01*
G01X396478Y-1417D02*
X396248Y-1107D01*
X395980Y-952D01*
X395673Y-900D01*
X395290Y-1003D01*
X395022Y-1262D01*
X394945Y-1572D01*
X394983Y-1882D01*
X395137Y-2140D01*
X395903Y-2657D01*
X396248Y-3018D01*
X396478Y-3535D01*
X396555Y-4000D01*
X394945D01*
G01X393378Y-1417D02*
X393148Y-1107D01*
X392880Y-952D01*
X392573Y-900D01*
X392190Y-1003D01*
X391922Y-1262D01*
X391845Y-1572D01*
X391883Y-1882D01*
X392037Y-2140D01*
X392803Y-2657D01*
X393148Y-3018D01*
X393378Y-3535D01*
X393455Y-4000D01*
X391845D01*
G01X376927Y25000D02*
X376850Y25672D01*
X376735Y26240D01*
X376582Y26757D01*
X376390Y27325D01*
X376083Y28100D01*
X377617D01*
G01X373827Y25000D02*
X373750Y25672D01*
X373635Y26240D01*
X373482Y26757D01*
X373290Y27325D01*
X372983Y28100D01*
X374517D01*
G01X396427Y27000D02*
X396350Y27672D01*
X396235Y28240D01*
X396082Y28757D01*
X395890Y29325D01*
X395583Y30100D01*
X397117D01*
G01X393250Y27000D02*
X392982Y27052D01*
X392675Y27207D01*
X392483Y27465D01*
X392407Y27827D01*
X392483Y28188D01*
X392713Y28498D01*
X393058Y28653D01*
X393442D01*
X393672Y28757D01*
X393863Y29015D01*
X393940Y29377D01*
X393825Y29738D01*
X393557Y29997D01*
X393250Y30100D01*
X392943Y29997D01*
X392675Y29738D01*
X392560Y29377D01*
X392637Y29015D01*
X392828Y28757D01*
X393058Y28653D01*
X393442D01*
X393787Y28498D01*
X394017Y28188D01*
X394093Y27827D01*
X394017Y27465D01*
X393825Y27207D01*
X393518Y27052D01*
X393250Y27000D01*
G01X371975Y-14767D02*
X371642Y-14975D01*
X371267Y-15100D01*
X370933D01*
X370600Y-14975D01*
X370350Y-14767D01*
X370225Y-14475D01*
X370308Y-14183D01*
X370517Y-13933D01*
X370892Y-13767D01*
X371392Y-13683D01*
X371683Y-13517D01*
X371808Y-13225D01*
X371725Y-12933D01*
X371517Y-12725D01*
X371225Y-12600D01*
X370933D01*
X370642Y-12683D01*
X370392Y-12892D01*
G01X368875Y-15100D02*
Y-12600D01*
G01X367125D02*
Y-15100D01*
G01Y-13850D02*
X368875D01*
G01X364900Y-15100D02*
X364608Y-15058D01*
X364275Y-14933D01*
X364067Y-14725D01*
X363983Y-14433D01*
X364067Y-14142D01*
X364317Y-13892D01*
X364692Y-13767D01*
X365108D01*
X365358Y-13683D01*
X365567Y-13475D01*
X365650Y-13183D01*
X365525Y-12892D01*
X365233Y-12683D01*
X364900Y-12600D01*
X364567Y-12683D01*
X364275Y-12892D01*
X364150Y-13183D01*
X364233Y-13475D01*
X364442Y-13683D01*
X364692Y-13767D01*
X365108D01*
X365483Y-13892D01*
X365733Y-14142D01*
X365817Y-14433D01*
X365733Y-14725D01*
X365525Y-14933D01*
X365192Y-15058D01*
X364900Y-15100D01*
G01X362717Y-12600D02*
Y-14392D01*
X362550Y-14767D01*
X362217Y-15017D01*
X361800Y-15100D01*
X361383Y-15017D01*
X361050Y-14767D01*
X360883Y-14392D01*
Y-12600D01*
G01X358700Y-15100D02*
Y-12600D01*
X359200Y-13100D01*
G01Y-15100D02*
X358200D01*
G01X381078Y39083D02*
X380848Y39393D01*
X380580Y39548D01*
X380273Y39600D01*
X379890Y39497D01*
X379622Y39238D01*
X379545Y38928D01*
X379583Y38618D01*
X379737Y38360D01*
X380503Y37843D01*
X380848Y37482D01*
X381078Y36965D01*
X381155Y36500D01*
X379545D01*
G01X377978Y39083D02*
X377748Y39393D01*
X377480Y39548D01*
X377173Y39600D01*
X376790Y39497D01*
X376522Y39238D01*
X376445Y38928D01*
X376483Y38618D01*
X376637Y38360D01*
X377403Y37843D01*
X377748Y37482D01*
X377978Y36965D01*
X378055Y36500D01*
X376445D01*
G01X374150D02*
Y39600D01*
X374610Y38980D01*
G01Y36500D02*
X373690D01*
G01X399578Y37083D02*
X399348Y37393D01*
X399080Y37548D01*
X398773Y37600D01*
X398390Y37497D01*
X398122Y37238D01*
X398045Y36928D01*
X398083Y36618D01*
X398237Y36360D01*
X399003Y35843D01*
X399348Y35482D01*
X399578Y34965D01*
X399655Y34500D01*
X398045D01*
G01X396478Y37083D02*
X396248Y37393D01*
X395980Y37548D01*
X395673Y37600D01*
X395290Y37497D01*
X395022Y37238D01*
X394945Y36928D01*
X394983Y36618D01*
X395137Y36360D01*
X395903Y35843D01*
X396248Y35482D01*
X396478Y34965D01*
X396555Y34500D01*
X394945D01*
G01X393378Y37083D02*
X393148Y37393D01*
X392880Y37548D01*
X392573Y37600D01*
X392190Y37497D01*
X391922Y37238D01*
X391845Y36928D01*
X391883Y36618D01*
X392037Y36360D01*
X392803Y35843D01*
X393148Y35482D01*
X393378Y34965D01*
X393455Y34500D01*
X391845D01*
G01X377427Y61500D02*
X377350Y62172D01*
X377235Y62740D01*
X377082Y63257D01*
X376890Y63825D01*
X376583Y64600D01*
X378117D01*
G01X374327Y61500D02*
X374250Y62172D01*
X374135Y62740D01*
X373982Y63257D01*
X373790Y63825D01*
X373483Y64600D01*
X375017D01*
G01X395927Y64500D02*
X395850Y65172D01*
X395735Y65740D01*
X395582Y66257D01*
X395390Y66825D01*
X395083Y67600D01*
X396617D01*
G01X392750Y64500D02*
X392482Y64552D01*
X392175Y64707D01*
X391983Y64965D01*
X391907Y65327D01*
X391983Y65688D01*
X392213Y65998D01*
X392558Y66153D01*
X392942D01*
X393172Y66257D01*
X393363Y66515D01*
X393440Y66877D01*
X393325Y67238D01*
X393057Y67497D01*
X392750Y67600D01*
X392443Y67497D01*
X392175Y67238D01*
X392060Y66877D01*
X392137Y66515D01*
X392328Y66257D01*
X392558Y66153D01*
X392942D01*
X393287Y65998D01*
X393517Y65688D01*
X393593Y65327D01*
X393517Y64965D01*
X393325Y64707D01*
X393018Y64552D01*
X392750Y64500D01*
G01X382578Y77583D02*
X382348Y77893D01*
X382080Y78048D01*
X381773Y78100D01*
X381390Y77997D01*
X381122Y77738D01*
X381045Y77428D01*
X381083Y77118D01*
X381237Y76860D01*
X382003Y76343D01*
X382348Y75982D01*
X382578Y75465D01*
X382655Y75000D01*
X381045D01*
G01X379478Y77583D02*
X379248Y77893D01*
X378980Y78048D01*
X378673Y78100D01*
X378290Y77997D01*
X378022Y77738D01*
X377945Y77428D01*
X377983Y77118D01*
X378137Y76860D01*
X378903Y76343D01*
X379248Y75982D01*
X379478Y75465D01*
X379555Y75000D01*
X377945D01*
G01X375650D02*
Y78100D01*
X376110Y77480D01*
G01Y75000D02*
X375190D01*
G01X399578Y75083D02*
X399348Y75393D01*
X399080Y75548D01*
X398773Y75600D01*
X398390Y75497D01*
X398122Y75238D01*
X398045Y74928D01*
X398083Y74618D01*
X398237Y74360D01*
X399003Y73843D01*
X399348Y73482D01*
X399578Y72965D01*
X399655Y72500D01*
X398045D01*
G01X396478Y75083D02*
X396248Y75393D01*
X395980Y75548D01*
X395673Y75600D01*
X395290Y75497D01*
X395022Y75238D01*
X394945Y74928D01*
X394983Y74618D01*
X395137Y74360D01*
X395903Y73843D01*
X396248Y73482D01*
X396478Y72965D01*
X396555Y72500D01*
X394945D01*
G01X393378Y75083D02*
X393148Y75393D01*
X392880Y75548D01*
X392573Y75600D01*
X392190Y75497D01*
X391922Y75238D01*
X391845Y74928D01*
X391883Y74618D01*
X392037Y74360D01*
X392803Y73843D01*
X393148Y73482D01*
X393378Y72965D01*
X393455Y72500D01*
X391845D01*
G01X411895Y259044D02*
X413395Y257544D01*
X410395D01*
X411895Y259044D01*
X411900Y259039D01*
Y197000D01*
X381200D01*
Y115501D01*
X381201Y115500D01*
X430859D01*
Y131555D01*
X436369D01*
Y135583D01*
X457500D01*
Y197000D01*
X411900D01*
G01X419092Y152617D02*
X419217Y152367D01*
X419300Y152075D01*
Y151742D01*
X419175Y151367D01*
X418967Y151075D01*
X418717Y150867D01*
X418300Y150700D01*
X417925Y150658D01*
X417550Y150742D01*
X417300Y150867D01*
X417050Y151117D01*
X416883Y151408D01*
X416800Y151700D01*
Y151992D01*
X416883Y152283D01*
X417008Y152533D01*
X417175Y152742D01*
G01X416800Y154717D02*
X417342Y154800D01*
X417800Y154925D01*
X418217Y155092D01*
X418675Y155300D01*
X419300Y155633D01*
Y153967D01*
G01X416800Y157067D02*
X419300D01*
Y158067D01*
X419175Y158400D01*
X418883Y158650D01*
X418550Y158733D01*
X418217Y158650D01*
X417967Y158442D01*
X417842Y158067D01*
Y157067D01*
G01X416800Y161000D02*
X419300D01*
X418800Y160500D01*
G01X416800D02*
Y161500D01*
G01X419300Y164100D02*
X419217Y163767D01*
X419008Y163517D01*
X418758Y163350D01*
X418425Y163225D01*
X418050Y163183D01*
X417675Y163225D01*
X417342Y163350D01*
X417092Y163517D01*
X416883Y163767D01*
X416800Y164100D01*
X416883Y164433D01*
X417092Y164683D01*
X417342Y164850D01*
X417675Y164975D01*
X418050Y165017D01*
X418425Y164975D01*
X418758Y164850D01*
X419008Y164683D01*
X419217Y164433D01*
X419300Y164100D01*
G01X418792Y135317D02*
X418917Y135067D01*
X419000Y134775D01*
Y134442D01*
X418875Y134067D01*
X418667Y133775D01*
X418417Y133567D01*
X418000Y133400D01*
X417625Y133358D01*
X417250Y133442D01*
X417000Y133567D01*
X416750Y133817D01*
X416583Y134108D01*
X416500Y134400D01*
Y134692D01*
X416583Y134983D01*
X416708Y135233D01*
X416875Y135442D01*
G01X416500Y137417D02*
X417042Y137500D01*
X417500Y137625D01*
X417917Y137792D01*
X418375Y138000D01*
X419000Y138333D01*
Y136667D01*
G01X416500Y139767D02*
X419000D01*
Y140767D01*
X418875Y141100D01*
X418583Y141350D01*
X418250Y141433D01*
X417917Y141350D01*
X417667Y141142D01*
X417542Y140767D01*
Y139767D01*
G01X416500Y143700D02*
X419000D01*
X418500Y143200D01*
G01X416500D02*
Y144200D01*
G01X416875Y145883D02*
X416667Y146133D01*
X416542Y146425D01*
X416500Y146800D01*
X416583Y147175D01*
X416750Y147467D01*
X417042Y147675D01*
X417375Y147717D01*
X417708Y147633D01*
X417917Y147425D01*
X418083Y147133D01*
X418125Y146842D01*
X418083Y146550D01*
X417917Y146175D01*
X419000Y146300D01*
Y147425D01*
G01X411092Y152617D02*
X411217Y152367D01*
X411300Y152075D01*
Y151742D01*
X411175Y151367D01*
X410967Y151075D01*
X410717Y150867D01*
X410300Y150700D01*
X409925Y150658D01*
X409550Y150742D01*
X409300Y150867D01*
X409050Y151117D01*
X408883Y151408D01*
X408800Y151700D01*
Y151992D01*
X408883Y152283D01*
X409008Y152533D01*
X409175Y152742D01*
G01X408800Y154800D02*
X408842Y155092D01*
X408967Y155425D01*
X409175Y155633D01*
X409467Y155717D01*
X409758Y155633D01*
X410008Y155383D01*
X410133Y155008D01*
Y154592D01*
X410217Y154342D01*
X410425Y154133D01*
X410717Y154050D01*
X411008Y154175D01*
X411217Y154467D01*
X411300Y154800D01*
X411217Y155133D01*
X411008Y155425D01*
X410717Y155550D01*
X410425Y155467D01*
X410217Y155258D01*
X410133Y155008D01*
Y154592D01*
X410008Y154217D01*
X409758Y153967D01*
X409467Y153883D01*
X409175Y153967D01*
X408967Y154175D01*
X408842Y154508D01*
X408800Y154800D01*
G01Y157067D02*
X411300D01*
Y158067D01*
X411175Y158400D01*
X410883Y158650D01*
X410550Y158733D01*
X410217Y158650D01*
X409967Y158442D01*
X409842Y158067D01*
Y157067D01*
G01X408800Y161000D02*
X411300D01*
X410800Y160500D01*
G01X408800D02*
Y161500D01*
G01X409175Y163183D02*
X408967Y163433D01*
X408842Y163725D01*
X408800Y164100D01*
X408883Y164475D01*
X409050Y164767D01*
X409342Y164975D01*
X409675Y165017D01*
X410008Y164933D01*
X410217Y164725D01*
X410383Y164433D01*
X410425Y164142D01*
X410383Y163850D01*
X410217Y163475D01*
X411300Y163600D01*
Y164725D01*
G01X415092Y152617D02*
X415217Y152367D01*
X415300Y152075D01*
Y151742D01*
X415175Y151367D01*
X414967Y151075D01*
X414717Y150867D01*
X414300Y150700D01*
X413925Y150658D01*
X413550Y150742D01*
X413300Y150867D01*
X413050Y151117D01*
X412883Y151408D01*
X412800Y151700D01*
Y151992D01*
X412883Y152283D01*
X413008Y152533D01*
X413175Y152742D01*
G01X412800Y154800D02*
X412842Y155092D01*
X412967Y155425D01*
X413175Y155633D01*
X413467Y155717D01*
X413758Y155633D01*
X414008Y155383D01*
X414133Y155008D01*
Y154592D01*
X414217Y154342D01*
X414425Y154133D01*
X414717Y154050D01*
X415008Y154175D01*
X415217Y154467D01*
X415300Y154800D01*
X415217Y155133D01*
X415008Y155425D01*
X414717Y155550D01*
X414425Y155467D01*
X414217Y155258D01*
X414133Y155008D01*
Y154592D01*
X414008Y154217D01*
X413758Y153967D01*
X413467Y153883D01*
X413175Y153967D01*
X412967Y154175D01*
X412842Y154508D01*
X412800Y154800D01*
G01Y157067D02*
X415300D01*
Y158067D01*
X415175Y158400D01*
X414883Y158650D01*
X414550Y158733D01*
X414217Y158650D01*
X413967Y158442D01*
X413842Y158067D01*
Y157067D01*
G01X412800Y161000D02*
X415300D01*
X414800Y160500D01*
G01X412800D02*
Y161500D01*
G01Y164600D02*
X415300D01*
X413508Y163058D01*
Y165142D01*
G01X410792Y135317D02*
X410917Y135067D01*
X411000Y134775D01*
Y134442D01*
X410875Y134067D01*
X410667Y133775D01*
X410417Y133567D01*
X410000Y133400D01*
X409625Y133358D01*
X409250Y133442D01*
X409000Y133567D01*
X408750Y133817D01*
X408583Y134108D01*
X408500Y134400D01*
Y134692D01*
X408583Y134983D01*
X408708Y135233D01*
X408875Y135442D01*
G01X408500Y137500D02*
X408542Y137792D01*
X408667Y138125D01*
X408875Y138333D01*
X409167Y138417D01*
X409458Y138333D01*
X409708Y138083D01*
X409833Y137708D01*
Y137292D01*
X409917Y137042D01*
X410125Y136833D01*
X410417Y136750D01*
X410708Y136875D01*
X410917Y137167D01*
X411000Y137500D01*
X410917Y137833D01*
X410708Y138125D01*
X410417Y138250D01*
X410125Y138167D01*
X409917Y137958D01*
X409833Y137708D01*
Y137292D01*
X409708Y136917D01*
X409458Y136667D01*
X409167Y136583D01*
X408875Y136667D01*
X408667Y136875D01*
X408542Y137208D01*
X408500Y137500D01*
G01Y139767D02*
X411000D01*
Y140767D01*
X410875Y141100D01*
X410583Y141350D01*
X410250Y141433D01*
X409917Y141350D01*
X409667Y141142D01*
X409542Y140767D01*
Y139767D01*
G01X410583Y142908D02*
X410833Y143158D01*
X410958Y143450D01*
X411000Y143783D01*
X410917Y144200D01*
X410708Y144492D01*
X410458Y144575D01*
X410208Y144533D01*
X410000Y144367D01*
X409583Y143533D01*
X409292Y143158D01*
X408875Y142908D01*
X408500Y142825D01*
Y144575D01*
G01X409000Y145883D02*
X408708Y146133D01*
X408542Y146467D01*
X408500Y146842D01*
X408542Y147175D01*
X408750Y147508D01*
X409000Y147717D01*
X409250Y147758D01*
X409542Y147675D01*
X409750Y147383D01*
X409833Y147092D01*
Y146717D01*
G01Y147092D02*
X409958Y147342D01*
X410167Y147550D01*
X410417Y147633D01*
X410667Y147550D01*
X410875Y147342D01*
X411000Y146967D01*
X410958Y146592D01*
X410792Y146217D01*
G01X414792Y135317D02*
X414917Y135067D01*
X415000Y134775D01*
Y134442D01*
X414875Y134067D01*
X414667Y133775D01*
X414417Y133567D01*
X414000Y133400D01*
X413625Y133358D01*
X413250Y133442D01*
X413000Y133567D01*
X412750Y133817D01*
X412583Y134108D01*
X412500Y134400D01*
Y134692D01*
X412583Y134983D01*
X412708Y135233D01*
X412875Y135442D01*
G01X412500Y137500D02*
X412542Y137792D01*
X412667Y138125D01*
X412875Y138333D01*
X413167Y138417D01*
X413458Y138333D01*
X413708Y138083D01*
X413833Y137708D01*
Y137292D01*
X413917Y137042D01*
X414125Y136833D01*
X414417Y136750D01*
X414708Y136875D01*
X414917Y137167D01*
X415000Y137500D01*
X414917Y137833D01*
X414708Y138125D01*
X414417Y138250D01*
X414125Y138167D01*
X413917Y137958D01*
X413833Y137708D01*
Y137292D01*
X413708Y136917D01*
X413458Y136667D01*
X413167Y136583D01*
X412875Y136667D01*
X412667Y136875D01*
X412542Y137208D01*
X412500Y137500D01*
G01Y139767D02*
X415000D01*
Y140767D01*
X414875Y141100D01*
X414583Y141350D01*
X414250Y141433D01*
X413917Y141350D01*
X413667Y141142D01*
X413542Y140767D01*
Y139767D01*
G01X414583Y142908D02*
X414833Y143158D01*
X414958Y143450D01*
X415000Y143783D01*
X414917Y144200D01*
X414708Y144492D01*
X414458Y144575D01*
X414208Y144533D01*
X414000Y144367D01*
X413583Y143533D01*
X413292Y143158D01*
X412875Y142908D01*
X412500Y142825D01*
Y144575D01*
G01X414583Y146008D02*
X414833Y146258D01*
X414958Y146550D01*
X415000Y146883D01*
X414917Y147300D01*
X414708Y147592D01*
X414458Y147675D01*
X414208Y147633D01*
X414000Y147467D01*
X413583Y146633D01*
X413292Y146258D01*
X412875Y146008D01*
X412500Y145925D01*
Y147675D01*
G01X410792Y119217D02*
X410917Y118967D01*
X411000Y118675D01*
Y118342D01*
X410875Y117967D01*
X410667Y117675D01*
X410417Y117467D01*
X410000Y117300D01*
X409625Y117258D01*
X409250Y117342D01*
X409000Y117467D01*
X408750Y117717D01*
X408583Y118008D01*
X408500Y118300D01*
Y118592D01*
X408583Y118883D01*
X408708Y119133D01*
X408875Y119342D01*
G01X408500Y121400D02*
X408542Y121692D01*
X408667Y122025D01*
X408875Y122233D01*
X409167Y122317D01*
X409458Y122233D01*
X409708Y121983D01*
X409833Y121608D01*
Y121192D01*
X409917Y120942D01*
X410125Y120733D01*
X410417Y120650D01*
X410708Y120775D01*
X410917Y121067D01*
X411000Y121400D01*
X410917Y121733D01*
X410708Y122025D01*
X410417Y122150D01*
X410125Y122067D01*
X409917Y121858D01*
X409833Y121608D01*
Y121192D01*
X409708Y120817D01*
X409458Y120567D01*
X409167Y120483D01*
X408875Y120567D01*
X408667Y120775D01*
X408542Y121108D01*
X408500Y121400D01*
G01Y123667D02*
X411000D01*
Y124667D01*
X410875Y125000D01*
X410583Y125250D01*
X410250Y125333D01*
X409917Y125250D01*
X409667Y125042D01*
X409542Y124667D01*
Y123667D01*
G01X409000Y126683D02*
X408708Y126933D01*
X408542Y127267D01*
X408500Y127642D01*
X408542Y127975D01*
X408750Y128308D01*
X409000Y128517D01*
X409250Y128558D01*
X409542Y128475D01*
X409750Y128183D01*
X409833Y127892D01*
Y127517D01*
G01Y127892D02*
X409958Y128142D01*
X410167Y128350D01*
X410417Y128433D01*
X410667Y128350D01*
X410875Y128142D01*
X411000Y127767D01*
X410958Y127392D01*
X410792Y127017D01*
G01X409000Y129783D02*
X408708Y130033D01*
X408542Y130367D01*
X408500Y130742D01*
X408542Y131075D01*
X408750Y131408D01*
X409000Y131617D01*
X409250Y131658D01*
X409542Y131575D01*
X409750Y131283D01*
X409833Y130992D01*
Y130617D01*
G01Y130992D02*
X409958Y131242D01*
X410167Y131450D01*
X410417Y131533D01*
X410667Y131450D01*
X410875Y131242D01*
X411000Y130867D01*
X410958Y130492D01*
X410792Y130117D01*
G01X414792Y119217D02*
X414917Y118967D01*
X415000Y118675D01*
Y118342D01*
X414875Y117967D01*
X414667Y117675D01*
X414417Y117467D01*
X414000Y117300D01*
X413625Y117258D01*
X413250Y117342D01*
X413000Y117467D01*
X412750Y117717D01*
X412583Y118008D01*
X412500Y118300D01*
Y118592D01*
X412583Y118883D01*
X412708Y119133D01*
X412875Y119342D01*
G01X412500Y121400D02*
X412542Y121692D01*
X412667Y122025D01*
X412875Y122233D01*
X413167Y122317D01*
X413458Y122233D01*
X413708Y121983D01*
X413833Y121608D01*
Y121192D01*
X413917Y120942D01*
X414125Y120733D01*
X414417Y120650D01*
X414708Y120775D01*
X414917Y121067D01*
X415000Y121400D01*
X414917Y121733D01*
X414708Y122025D01*
X414417Y122150D01*
X414125Y122067D01*
X413917Y121858D01*
X413833Y121608D01*
Y121192D01*
X413708Y120817D01*
X413458Y120567D01*
X413167Y120483D01*
X412875Y120567D01*
X412667Y120775D01*
X412542Y121108D01*
X412500Y121400D01*
G01Y123667D02*
X415000D01*
Y124667D01*
X414875Y125000D01*
X414583Y125250D01*
X414250Y125333D01*
X413917Y125250D01*
X413667Y125042D01*
X413542Y124667D01*
Y123667D01*
G01X413000Y126683D02*
X412708Y126933D01*
X412542Y127267D01*
X412500Y127642D01*
X412542Y127975D01*
X412750Y128308D01*
X413000Y128517D01*
X413250Y128558D01*
X413542Y128475D01*
X413750Y128183D01*
X413833Y127892D01*
Y127517D01*
G01Y127892D02*
X413958Y128142D01*
X414167Y128350D01*
X414417Y128433D01*
X414667Y128350D01*
X414875Y128142D01*
X415000Y127767D01*
X414958Y127392D01*
X414792Y127017D01*
G01X414583Y129908D02*
X414833Y130158D01*
X414958Y130450D01*
X415000Y130783D01*
X414917Y131200D01*
X414708Y131492D01*
X414458Y131575D01*
X414208Y131533D01*
X414000Y131367D01*
X413583Y130533D01*
X413292Y130158D01*
X412875Y129908D01*
X412500Y129825D01*
Y131575D01*
G01X394792Y135317D02*
X394917Y135067D01*
X395000Y134775D01*
Y134442D01*
X394875Y134067D01*
X394667Y133775D01*
X394417Y133567D01*
X394000Y133400D01*
X393625Y133358D01*
X393250Y133442D01*
X393000Y133567D01*
X392750Y133817D01*
X392583Y134108D01*
X392500Y134400D01*
Y134692D01*
X392583Y134983D01*
X392708Y135233D01*
X392875Y135442D01*
G01X392500Y137500D02*
X392542Y137792D01*
X392667Y138125D01*
X392875Y138333D01*
X393167Y138417D01*
X393458Y138333D01*
X393708Y138083D01*
X393833Y137708D01*
Y137292D01*
X393917Y137042D01*
X394125Y136833D01*
X394417Y136750D01*
X394708Y136875D01*
X394917Y137167D01*
X395000Y137500D01*
X394917Y137833D01*
X394708Y138125D01*
X394417Y138250D01*
X394125Y138167D01*
X393917Y137958D01*
X393833Y137708D01*
Y137292D01*
X393708Y136917D01*
X393458Y136667D01*
X393167Y136583D01*
X392875Y136667D01*
X392667Y136875D01*
X392542Y137208D01*
X392500Y137500D01*
G01Y139767D02*
X395000D01*
Y140767D01*
X394875Y141100D01*
X394583Y141350D01*
X394250Y141433D01*
X393917Y141350D01*
X393667Y141142D01*
X393542Y140767D01*
Y139767D01*
G01X394583Y142908D02*
X394833Y143158D01*
X394958Y143450D01*
X395000Y143783D01*
X394917Y144200D01*
X394708Y144492D01*
X394458Y144575D01*
X394208Y144533D01*
X394000Y144367D01*
X393583Y143533D01*
X393292Y143158D01*
X392875Y142908D01*
X392500Y142825D01*
Y144575D01*
G01Y146717D02*
X393042Y146800D01*
X393500Y146925D01*
X393917Y147092D01*
X394375Y147300D01*
X395000Y147633D01*
Y145967D01*
G01X390792Y135317D02*
X390917Y135067D01*
X391000Y134775D01*
Y134442D01*
X390875Y134067D01*
X390667Y133775D01*
X390417Y133567D01*
X390000Y133400D01*
X389625Y133358D01*
X389250Y133442D01*
X389000Y133567D01*
X388750Y133817D01*
X388583Y134108D01*
X388500Y134400D01*
Y134692D01*
X388583Y134983D01*
X388708Y135233D01*
X388875Y135442D01*
G01X388500Y137500D02*
X388542Y137792D01*
X388667Y138125D01*
X388875Y138333D01*
X389167Y138417D01*
X389458Y138333D01*
X389708Y138083D01*
X389833Y137708D01*
Y137292D01*
X389917Y137042D01*
X390125Y136833D01*
X390417Y136750D01*
X390708Y136875D01*
X390917Y137167D01*
X391000Y137500D01*
X390917Y137833D01*
X390708Y138125D01*
X390417Y138250D01*
X390125Y138167D01*
X389917Y137958D01*
X389833Y137708D01*
Y137292D01*
X389708Y136917D01*
X389458Y136667D01*
X389167Y136583D01*
X388875Y136667D01*
X388667Y136875D01*
X388542Y137208D01*
X388500Y137500D01*
G01Y139767D02*
X391000D01*
Y140767D01*
X390875Y141100D01*
X390583Y141350D01*
X390250Y141433D01*
X389917Y141350D01*
X389667Y141142D01*
X389542Y140767D01*
Y139767D01*
G01X390583Y142908D02*
X390833Y143158D01*
X390958Y143450D01*
X391000Y143783D01*
X390917Y144200D01*
X390708Y144492D01*
X390458Y144575D01*
X390208Y144533D01*
X390000Y144367D01*
X389583Y143533D01*
X389292Y143158D01*
X388875Y142908D01*
X388500Y142825D01*
Y144575D01*
G01Y146800D02*
X388542Y147092D01*
X388667Y147425D01*
X388875Y147633D01*
X389167Y147717D01*
X389458Y147633D01*
X389708Y147383D01*
X389833Y147008D01*
Y146592D01*
X389917Y146342D01*
X390125Y146133D01*
X390417Y146050D01*
X390708Y146175D01*
X390917Y146467D01*
X391000Y146800D01*
X390917Y147133D01*
X390708Y147425D01*
X390417Y147550D01*
X390125Y147467D01*
X389917Y147258D01*
X389833Y147008D01*
Y146592D01*
X389708Y146217D01*
X389458Y145967D01*
X389167Y145883D01*
X388875Y145967D01*
X388667Y146175D01*
X388542Y146508D01*
X388500Y146800D01*
G01X386792Y135317D02*
X386917Y135067D01*
X387000Y134775D01*
Y134442D01*
X386875Y134067D01*
X386667Y133775D01*
X386417Y133567D01*
X386000Y133400D01*
X385625Y133358D01*
X385250Y133442D01*
X385000Y133567D01*
X384750Y133817D01*
X384583Y134108D01*
X384500Y134400D01*
Y134692D01*
X384583Y134983D01*
X384708Y135233D01*
X384875Y135442D01*
G01X384500Y137500D02*
X384542Y137792D01*
X384667Y138125D01*
X384875Y138333D01*
X385167Y138417D01*
X385458Y138333D01*
X385708Y138083D01*
X385833Y137708D01*
Y137292D01*
X385917Y137042D01*
X386125Y136833D01*
X386417Y136750D01*
X386708Y136875D01*
X386917Y137167D01*
X387000Y137500D01*
X386917Y137833D01*
X386708Y138125D01*
X386417Y138250D01*
X386125Y138167D01*
X385917Y137958D01*
X385833Y137708D01*
Y137292D01*
X385708Y136917D01*
X385458Y136667D01*
X385167Y136583D01*
X384875Y136667D01*
X384667Y136875D01*
X384542Y137208D01*
X384500Y137500D01*
G01Y139767D02*
X387000D01*
Y140767D01*
X386875Y141100D01*
X386583Y141350D01*
X386250Y141433D01*
X385917Y141350D01*
X385667Y141142D01*
X385542Y140767D01*
Y139767D01*
G01X386583Y142908D02*
X386833Y143158D01*
X386958Y143450D01*
X387000Y143783D01*
X386917Y144200D01*
X386708Y144492D01*
X386458Y144575D01*
X386208Y144533D01*
X386000Y144367D01*
X385583Y143533D01*
X385292Y143158D01*
X384875Y142908D01*
X384500Y142825D01*
Y144575D01*
G01X384792Y146092D02*
X384583Y146383D01*
X384500Y146717D01*
X384583Y147050D01*
X384833Y147342D01*
X385208Y147550D01*
X385583Y147633D01*
X386042D01*
X386417Y147550D01*
X386750Y147342D01*
X386917Y147092D01*
X387000Y146800D01*
X386917Y146467D01*
X386750Y146217D01*
X386500Y146050D01*
X386167Y145967D01*
X385875Y146050D01*
X385583Y146258D01*
X385417Y146508D01*
X385375Y146800D01*
X385458Y147133D01*
X385667Y147383D01*
X386042Y147633D01*
G01X395092Y152617D02*
X395217Y152367D01*
X395300Y152075D01*
Y151742D01*
X395175Y151367D01*
X394967Y151075D01*
X394717Y150867D01*
X394300Y150700D01*
X393925Y150658D01*
X393550Y150742D01*
X393300Y150867D01*
X393050Y151117D01*
X392883Y151408D01*
X392800Y151700D01*
Y151992D01*
X392883Y152283D01*
X393008Y152533D01*
X393175Y152742D01*
G01X392800Y154800D02*
X392842Y155092D01*
X392967Y155425D01*
X393175Y155633D01*
X393467Y155717D01*
X393758Y155633D01*
X394008Y155383D01*
X394133Y155008D01*
Y154592D01*
X394217Y154342D01*
X394425Y154133D01*
X394717Y154050D01*
X395008Y154175D01*
X395217Y154467D01*
X395300Y154800D01*
X395217Y155133D01*
X395008Y155425D01*
X394717Y155550D01*
X394425Y155467D01*
X394217Y155258D01*
X394133Y155008D01*
Y154592D01*
X394008Y154217D01*
X393758Y153967D01*
X393467Y153883D01*
X393175Y153967D01*
X392967Y154175D01*
X392842Y154508D01*
X392800Y154800D01*
G01Y157067D02*
X395300D01*
Y158067D01*
X395175Y158400D01*
X394883Y158650D01*
X394550Y158733D01*
X394217Y158650D01*
X393967Y158442D01*
X393842Y158067D01*
Y157067D01*
G01X392800Y161000D02*
X395300D01*
X394800Y160500D01*
G01X392800D02*
Y161500D01*
G01X393092Y163392D02*
X392883Y163683D01*
X392800Y164017D01*
X392883Y164350D01*
X393133Y164642D01*
X393508Y164850D01*
X393883Y164933D01*
X394342D01*
X394717Y164850D01*
X395050Y164642D01*
X395217Y164392D01*
X395300Y164100D01*
X395217Y163767D01*
X395050Y163517D01*
X394800Y163350D01*
X394467Y163267D01*
X394175Y163350D01*
X393883Y163558D01*
X393717Y163808D01*
X393675Y164100D01*
X393758Y164433D01*
X393967Y164683D01*
X394342Y164933D01*
G01X396283Y120459D02*
X396533Y120584D01*
X396825Y120667D01*
X397158D01*
X397533Y120542D01*
X397825Y120334D01*
X398033Y120084D01*
X398200Y119667D01*
X398242Y119292D01*
X398158Y118917D01*
X398033Y118667D01*
X397783Y118417D01*
X397492Y118250D01*
X397200Y118167D01*
X396908D01*
X396617Y118250D01*
X396367Y118375D01*
X396158Y118542D01*
G01X394100Y118167D02*
X393808Y118209D01*
X393475Y118334D01*
X393267Y118542D01*
X393183Y118834D01*
X393267Y119125D01*
X393517Y119375D01*
X393892Y119500D01*
X394308D01*
X394558Y119584D01*
X394767Y119792D01*
X394850Y120084D01*
X394725Y120375D01*
X394433Y120584D01*
X394100Y120667D01*
X393767Y120584D01*
X393475Y120375D01*
X393350Y120084D01*
X393433Y119792D01*
X393642Y119584D01*
X393892Y119500D01*
X394308D01*
X394683Y119375D01*
X394933Y119125D01*
X395017Y118834D01*
X394933Y118542D01*
X394725Y118334D01*
X394392Y118209D01*
X394100Y118167D01*
G01X391833D02*
Y120667D01*
X390833D01*
X390500Y120542D01*
X390250Y120250D01*
X390167Y119917D01*
X390250Y119584D01*
X390458Y119334D01*
X390833Y119209D01*
X391833D01*
G01X388817Y118667D02*
X388567Y118375D01*
X388233Y118209D01*
X387858Y118167D01*
X387525Y118209D01*
X387192Y118417D01*
X386983Y118667D01*
X386942Y118917D01*
X387025Y119209D01*
X387317Y119417D01*
X387608Y119500D01*
X387983D01*
G01X387608D02*
X387358Y119625D01*
X387150Y119834D01*
X387067Y120084D01*
X387150Y120334D01*
X387358Y120542D01*
X387733Y120667D01*
X388108Y120625D01*
X388483Y120459D01*
G01X384800Y120667D02*
X385133Y120584D01*
X385383Y120375D01*
X385550Y120125D01*
X385675Y119792D01*
X385717Y119417D01*
X385675Y119042D01*
X385550Y118709D01*
X385383Y118459D01*
X385133Y118250D01*
X384800Y118167D01*
X384467Y118250D01*
X384217Y118459D01*
X384050Y118709D01*
X383925Y119042D01*
X383883Y119417D01*
X383925Y119792D01*
X384050Y120125D01*
X384217Y120375D01*
X384467Y120584D01*
X384800Y120667D01*
G01X398792Y135317D02*
X398917Y135067D01*
X399000Y134775D01*
Y134442D01*
X398875Y134067D01*
X398667Y133775D01*
X398417Y133567D01*
X398000Y133400D01*
X397625Y133358D01*
X397250Y133442D01*
X397000Y133567D01*
X396750Y133817D01*
X396583Y134108D01*
X396500Y134400D01*
Y134692D01*
X396583Y134983D01*
X396708Y135233D01*
X396875Y135442D01*
G01X396500Y137500D02*
X396542Y137792D01*
X396667Y138125D01*
X396875Y138333D01*
X397167Y138417D01*
X397458Y138333D01*
X397708Y138083D01*
X397833Y137708D01*
Y137292D01*
X397917Y137042D01*
X398125Y136833D01*
X398417Y136750D01*
X398708Y136875D01*
X398917Y137167D01*
X399000Y137500D01*
X398917Y137833D01*
X398708Y138125D01*
X398417Y138250D01*
X398125Y138167D01*
X397917Y137958D01*
X397833Y137708D01*
Y137292D01*
X397708Y136917D01*
X397458Y136667D01*
X397167Y136583D01*
X396875Y136667D01*
X396667Y136875D01*
X396542Y137208D01*
X396500Y137500D01*
G01Y139767D02*
X399000D01*
Y140767D01*
X398875Y141100D01*
X398583Y141350D01*
X398250Y141433D01*
X397917Y141350D01*
X397667Y141142D01*
X397542Y140767D01*
Y139767D01*
G01X398583Y142908D02*
X398833Y143158D01*
X398958Y143450D01*
X399000Y143783D01*
X398917Y144200D01*
X398708Y144492D01*
X398458Y144575D01*
X398208Y144533D01*
X398000Y144367D01*
X397583Y143533D01*
X397292Y143158D01*
X396875Y142908D01*
X396500Y142825D01*
Y144575D01*
G01X397542Y146008D02*
X397833Y146300D01*
X398000Y146550D01*
X398083Y146883D01*
X398000Y147175D01*
X397833Y147383D01*
X397583Y147550D01*
X397292Y147592D01*
X397042Y147550D01*
X396792Y147383D01*
X396583Y147133D01*
X396500Y146842D01*
X396583Y146508D01*
X396833Y146217D01*
X397208Y146050D01*
X397625Y146008D01*
X398167Y146092D01*
X398458Y146217D01*
X398750Y146425D01*
X398958Y146717D01*
X399000Y147008D01*
X398917Y147300D01*
X398708Y147508D01*
G01X399092Y152617D02*
X399217Y152367D01*
X399300Y152075D01*
Y151742D01*
X399175Y151367D01*
X398967Y151075D01*
X398717Y150867D01*
X398300Y150700D01*
X397925Y150658D01*
X397550Y150742D01*
X397300Y150867D01*
X397050Y151117D01*
X396883Y151408D01*
X396800Y151700D01*
Y151992D01*
X396883Y152283D01*
X397008Y152533D01*
X397175Y152742D01*
G01X396800Y154800D02*
X396842Y155092D01*
X396967Y155425D01*
X397175Y155633D01*
X397467Y155717D01*
X397758Y155633D01*
X398008Y155383D01*
X398133Y155008D01*
Y154592D01*
X398217Y154342D01*
X398425Y154133D01*
X398717Y154050D01*
X399008Y154175D01*
X399217Y154467D01*
X399300Y154800D01*
X399217Y155133D01*
X399008Y155425D01*
X398717Y155550D01*
X398425Y155467D01*
X398217Y155258D01*
X398133Y155008D01*
Y154592D01*
X398008Y154217D01*
X397758Y153967D01*
X397467Y153883D01*
X397175Y153967D01*
X396967Y154175D01*
X396842Y154508D01*
X396800Y154800D01*
G01Y157067D02*
X399300D01*
Y158067D01*
X399175Y158400D01*
X398883Y158650D01*
X398550Y158733D01*
X398217Y158650D01*
X397967Y158442D01*
X397842Y158067D01*
Y157067D01*
G01X396800Y161000D02*
X399300D01*
X398800Y160500D01*
G01X396800D02*
Y161500D01*
G01Y164100D02*
X396842Y164392D01*
X396967Y164725D01*
X397175Y164933D01*
X397467Y165017D01*
X397758Y164933D01*
X398008Y164683D01*
X398133Y164308D01*
Y163892D01*
X398217Y163642D01*
X398425Y163433D01*
X398717Y163350D01*
X399008Y163475D01*
X399217Y163767D01*
X399300Y164100D01*
X399217Y164433D01*
X399008Y164725D01*
X398717Y164850D01*
X398425Y164767D01*
X398217Y164558D01*
X398133Y164308D01*
Y163892D01*
X398008Y163517D01*
X397758Y163267D01*
X397467Y163183D01*
X397175Y163267D01*
X396967Y163475D01*
X396842Y163808D01*
X396800Y164100D01*
G01X391092Y152617D02*
X391217Y152367D01*
X391300Y152075D01*
Y151742D01*
X391175Y151367D01*
X390967Y151075D01*
X390717Y150867D01*
X390300Y150700D01*
X389925Y150658D01*
X389550Y150742D01*
X389300Y150867D01*
X389050Y151117D01*
X388883Y151408D01*
X388800Y151700D01*
Y151992D01*
X388883Y152283D01*
X389008Y152533D01*
X389175Y152742D01*
G01X388800Y154800D02*
X388842Y155092D01*
X388967Y155425D01*
X389175Y155633D01*
X389467Y155717D01*
X389758Y155633D01*
X390008Y155383D01*
X390133Y155008D01*
Y154592D01*
X390217Y154342D01*
X390425Y154133D01*
X390717Y154050D01*
X391008Y154175D01*
X391217Y154467D01*
X391300Y154800D01*
X391217Y155133D01*
X391008Y155425D01*
X390717Y155550D01*
X390425Y155467D01*
X390217Y155258D01*
X390133Y155008D01*
Y154592D01*
X390008Y154217D01*
X389758Y153967D01*
X389467Y153883D01*
X389175Y153967D01*
X388967Y154175D01*
X388842Y154508D01*
X388800Y154800D01*
G01Y157067D02*
X391300D01*
Y158067D01*
X391175Y158400D01*
X390883Y158650D01*
X390550Y158733D01*
X390217Y158650D01*
X389967Y158442D01*
X389842Y158067D01*
Y157067D01*
G01X390883Y160208D02*
X391133Y160458D01*
X391258Y160750D01*
X391300Y161083D01*
X391217Y161500D01*
X391008Y161792D01*
X390758Y161875D01*
X390508Y161833D01*
X390300Y161667D01*
X389883Y160833D01*
X389592Y160458D01*
X389175Y160208D01*
X388800Y160125D01*
Y161875D01*
G01X391300Y164100D02*
X391217Y163767D01*
X391008Y163517D01*
X390758Y163350D01*
X390425Y163225D01*
X390050Y163183D01*
X389675Y163225D01*
X389342Y163350D01*
X389092Y163517D01*
X388883Y163767D01*
X388800Y164100D01*
X388883Y164433D01*
X389092Y164683D01*
X389342Y164850D01*
X389675Y164975D01*
X390050Y165017D01*
X390425Y164975D01*
X390758Y164850D01*
X391008Y164683D01*
X391217Y164433D01*
X391300Y164100D01*
G01X387092Y152617D02*
X387217Y152367D01*
X387300Y152075D01*
Y151742D01*
X387175Y151367D01*
X386967Y151075D01*
X386717Y150867D01*
X386300Y150700D01*
X385925Y150658D01*
X385550Y150742D01*
X385300Y150867D01*
X385050Y151117D01*
X384883Y151408D01*
X384800Y151700D01*
Y151992D01*
X384883Y152283D01*
X385008Y152533D01*
X385175Y152742D01*
G01X384800Y154800D02*
X384842Y155092D01*
X384967Y155425D01*
X385175Y155633D01*
X385467Y155717D01*
X385758Y155633D01*
X386008Y155383D01*
X386133Y155008D01*
Y154592D01*
X386217Y154342D01*
X386425Y154133D01*
X386717Y154050D01*
X387008Y154175D01*
X387217Y154467D01*
X387300Y154800D01*
X387217Y155133D01*
X387008Y155425D01*
X386717Y155550D01*
X386425Y155467D01*
X386217Y155258D01*
X386133Y155008D01*
Y154592D01*
X386008Y154217D01*
X385758Y153967D01*
X385467Y153883D01*
X385175Y153967D01*
X384967Y154175D01*
X384842Y154508D01*
X384800Y154800D01*
G01Y157067D02*
X387300D01*
Y158067D01*
X387175Y158400D01*
X386883Y158650D01*
X386550Y158733D01*
X386217Y158650D01*
X385967Y158442D01*
X385842Y158067D01*
Y157067D01*
G01X386883Y160208D02*
X387133Y160458D01*
X387258Y160750D01*
X387300Y161083D01*
X387217Y161500D01*
X387008Y161792D01*
X386758Y161875D01*
X386508Y161833D01*
X386300Y161667D01*
X385883Y160833D01*
X385592Y160458D01*
X385175Y160208D01*
X384800Y160125D01*
Y161875D01*
G01Y164100D02*
X387300D01*
X386800Y163600D01*
G01X384800D02*
Y164600D01*
G01X407092Y152617D02*
X407217Y152367D01*
X407300Y152075D01*
Y151742D01*
X407175Y151367D01*
X406967Y151075D01*
X406717Y150867D01*
X406300Y150700D01*
X405925Y150658D01*
X405550Y150742D01*
X405300Y150867D01*
X405050Y151117D01*
X404883Y151408D01*
X404800Y151700D01*
Y151992D01*
X404883Y152283D01*
X405008Y152533D01*
X405175Y152742D01*
G01X404800Y154800D02*
X404842Y155092D01*
X404967Y155425D01*
X405175Y155633D01*
X405467Y155717D01*
X405758Y155633D01*
X406008Y155383D01*
X406133Y155008D01*
Y154592D01*
X406217Y154342D01*
X406425Y154133D01*
X406717Y154050D01*
X407008Y154175D01*
X407217Y154467D01*
X407300Y154800D01*
X407217Y155133D01*
X407008Y155425D01*
X406717Y155550D01*
X406425Y155467D01*
X406217Y155258D01*
X406133Y155008D01*
Y154592D01*
X406008Y154217D01*
X405758Y153967D01*
X405467Y153883D01*
X405175Y153967D01*
X404967Y154175D01*
X404842Y154508D01*
X404800Y154800D01*
G01Y157067D02*
X407300D01*
Y158067D01*
X407175Y158400D01*
X406883Y158650D01*
X406550Y158733D01*
X406217Y158650D01*
X405967Y158442D01*
X405842Y158067D01*
Y157067D01*
G01X404800Y161000D02*
X407300D01*
X406800Y160500D01*
G01X404800D02*
Y161500D01*
G01X405842Y163308D02*
X406133Y163600D01*
X406300Y163850D01*
X406383Y164183D01*
X406300Y164475D01*
X406133Y164683D01*
X405883Y164850D01*
X405592Y164892D01*
X405342Y164850D01*
X405092Y164683D01*
X404883Y164433D01*
X404800Y164142D01*
X404883Y163808D01*
X405133Y163517D01*
X405508Y163350D01*
X405925Y163308D01*
X406467Y163392D01*
X406758Y163517D01*
X407050Y163725D01*
X407258Y164017D01*
X407300Y164308D01*
X407217Y164600D01*
X407008Y164808D01*
G01X406792Y135317D02*
X406917Y135067D01*
X407000Y134775D01*
Y134442D01*
X406875Y134067D01*
X406667Y133775D01*
X406417Y133567D01*
X406000Y133400D01*
X405625Y133358D01*
X405250Y133442D01*
X405000Y133567D01*
X404750Y133817D01*
X404583Y134108D01*
X404500Y134400D01*
Y134692D01*
X404583Y134983D01*
X404708Y135233D01*
X404875Y135442D01*
G01X404500Y137500D02*
X404542Y137792D01*
X404667Y138125D01*
X404875Y138333D01*
X405167Y138417D01*
X405458Y138333D01*
X405708Y138083D01*
X405833Y137708D01*
Y137292D01*
X405917Y137042D01*
X406125Y136833D01*
X406417Y136750D01*
X406708Y136875D01*
X406917Y137167D01*
X407000Y137500D01*
X406917Y137833D01*
X406708Y138125D01*
X406417Y138250D01*
X406125Y138167D01*
X405917Y137958D01*
X405833Y137708D01*
Y137292D01*
X405708Y136917D01*
X405458Y136667D01*
X405167Y136583D01*
X404875Y136667D01*
X404667Y136875D01*
X404542Y137208D01*
X404500Y137500D01*
G01Y139767D02*
X407000D01*
Y140767D01*
X406875Y141100D01*
X406583Y141350D01*
X406250Y141433D01*
X405917Y141350D01*
X405667Y141142D01*
X405542Y140767D01*
Y139767D01*
G01X406583Y142908D02*
X406833Y143158D01*
X406958Y143450D01*
X407000Y143783D01*
X406917Y144200D01*
X406708Y144492D01*
X406458Y144575D01*
X406208Y144533D01*
X406000Y144367D01*
X405583Y143533D01*
X405292Y143158D01*
X404875Y142908D01*
X404500Y142825D01*
Y144575D01*
G01Y147300D02*
X407000D01*
X405208Y145758D01*
Y147842D01*
G01X402792Y119217D02*
X402917Y118967D01*
X403000Y118675D01*
Y118342D01*
X402875Y117967D01*
X402667Y117675D01*
X402417Y117467D01*
X402000Y117300D01*
X401625Y117258D01*
X401250Y117342D01*
X401000Y117467D01*
X400750Y117717D01*
X400583Y118008D01*
X400500Y118300D01*
Y118592D01*
X400583Y118883D01*
X400708Y119133D01*
X400875Y119342D01*
G01X400500Y121400D02*
X400542Y121692D01*
X400667Y122025D01*
X400875Y122233D01*
X401167Y122317D01*
X401458Y122233D01*
X401708Y121983D01*
X401833Y121608D01*
Y121192D01*
X401917Y120942D01*
X402125Y120733D01*
X402417Y120650D01*
X402708Y120775D01*
X402917Y121067D01*
X403000Y121400D01*
X402917Y121733D01*
X402708Y122025D01*
X402417Y122150D01*
X402125Y122067D01*
X401917Y121858D01*
X401833Y121608D01*
Y121192D01*
X401708Y120817D01*
X401458Y120567D01*
X401167Y120483D01*
X400875Y120567D01*
X400667Y120775D01*
X400542Y121108D01*
X400500Y121400D01*
G01Y123667D02*
X403000D01*
Y124667D01*
X402875Y125000D01*
X402583Y125250D01*
X402250Y125333D01*
X401917Y125250D01*
X401667Y125042D01*
X401542Y124667D01*
Y123667D01*
G01X401000Y126683D02*
X400708Y126933D01*
X400542Y127267D01*
X400500Y127642D01*
X400542Y127975D01*
X400750Y128308D01*
X401000Y128517D01*
X401250Y128558D01*
X401542Y128475D01*
X401750Y128183D01*
X401833Y127892D01*
Y127517D01*
G01Y127892D02*
X401958Y128142D01*
X402167Y128350D01*
X402417Y128433D01*
X402667Y128350D01*
X402875Y128142D01*
X403000Y127767D01*
X402958Y127392D01*
X402792Y127017D01*
G01X400500Y130700D02*
X403000D01*
X402500Y130200D01*
G01X400500D02*
Y131200D01*
G01X406792Y119217D02*
X406917Y118967D01*
X407000Y118675D01*
Y118342D01*
X406875Y117967D01*
X406667Y117675D01*
X406417Y117467D01*
X406000Y117300D01*
X405625Y117258D01*
X405250Y117342D01*
X405000Y117467D01*
X404750Y117717D01*
X404583Y118008D01*
X404500Y118300D01*
Y118592D01*
X404583Y118883D01*
X404708Y119133D01*
X404875Y119342D01*
G01X404500Y121400D02*
X404542Y121692D01*
X404667Y122025D01*
X404875Y122233D01*
X405167Y122317D01*
X405458Y122233D01*
X405708Y121983D01*
X405833Y121608D01*
Y121192D01*
X405917Y120942D01*
X406125Y120733D01*
X406417Y120650D01*
X406708Y120775D01*
X406917Y121067D01*
X407000Y121400D01*
X406917Y121733D01*
X406708Y122025D01*
X406417Y122150D01*
X406125Y122067D01*
X405917Y121858D01*
X405833Y121608D01*
Y121192D01*
X405708Y120817D01*
X405458Y120567D01*
X405167Y120483D01*
X404875Y120567D01*
X404667Y120775D01*
X404542Y121108D01*
X404500Y121400D01*
G01Y123667D02*
X407000D01*
Y124667D01*
X406875Y125000D01*
X406583Y125250D01*
X406250Y125333D01*
X405917Y125250D01*
X405667Y125042D01*
X405542Y124667D01*
Y123667D01*
G01X405000Y126683D02*
X404708Y126933D01*
X404542Y127267D01*
X404500Y127642D01*
X404542Y127975D01*
X404750Y128308D01*
X405000Y128517D01*
X405250Y128558D01*
X405542Y128475D01*
X405750Y128183D01*
X405833Y127892D01*
Y127517D01*
G01Y127892D02*
X405958Y128142D01*
X406167Y128350D01*
X406417Y128433D01*
X406667Y128350D01*
X406875Y128142D01*
X407000Y127767D01*
X406958Y127392D01*
X406792Y127017D01*
G01X404500Y131200D02*
X407000D01*
X405208Y129658D01*
Y131742D01*
G01X403092Y152617D02*
X403217Y152367D01*
X403300Y152075D01*
Y151742D01*
X403175Y151367D01*
X402967Y151075D01*
X402717Y150867D01*
X402300Y150700D01*
X401925Y150658D01*
X401550Y150742D01*
X401300Y150867D01*
X401050Y151117D01*
X400883Y151408D01*
X400800Y151700D01*
Y151992D01*
X400883Y152283D01*
X401008Y152533D01*
X401175Y152742D01*
G01X400800Y154800D02*
X400842Y155092D01*
X400967Y155425D01*
X401175Y155633D01*
X401467Y155717D01*
X401758Y155633D01*
X402008Y155383D01*
X402133Y155008D01*
Y154592D01*
X402217Y154342D01*
X402425Y154133D01*
X402717Y154050D01*
X403008Y154175D01*
X403217Y154467D01*
X403300Y154800D01*
X403217Y155133D01*
X403008Y155425D01*
X402717Y155550D01*
X402425Y155467D01*
X402217Y155258D01*
X402133Y155008D01*
Y154592D01*
X402008Y154217D01*
X401758Y153967D01*
X401467Y153883D01*
X401175Y153967D01*
X400967Y154175D01*
X400842Y154508D01*
X400800Y154800D01*
G01Y157067D02*
X403300D01*
Y158067D01*
X403175Y158400D01*
X402883Y158650D01*
X402550Y158733D01*
X402217Y158650D01*
X401967Y158442D01*
X401842Y158067D01*
Y157067D01*
G01X400800Y161000D02*
X403300D01*
X402800Y160500D01*
G01X400800D02*
Y161500D01*
G01Y164017D02*
X401342Y164100D01*
X401800Y164225D01*
X402217Y164392D01*
X402675Y164600D01*
X403300Y164933D01*
Y163267D01*
G01X402792Y135317D02*
X402917Y135067D01*
X403000Y134775D01*
Y134442D01*
X402875Y134067D01*
X402667Y133775D01*
X402417Y133567D01*
X402000Y133400D01*
X401625Y133358D01*
X401250Y133442D01*
X401000Y133567D01*
X400750Y133817D01*
X400583Y134108D01*
X400500Y134400D01*
Y134692D01*
X400583Y134983D01*
X400708Y135233D01*
X400875Y135442D01*
G01X400500Y137500D02*
X400542Y137792D01*
X400667Y138125D01*
X400875Y138333D01*
X401167Y138417D01*
X401458Y138333D01*
X401708Y138083D01*
X401833Y137708D01*
Y137292D01*
X401917Y137042D01*
X402125Y136833D01*
X402417Y136750D01*
X402708Y136875D01*
X402917Y137167D01*
X403000Y137500D01*
X402917Y137833D01*
X402708Y138125D01*
X402417Y138250D01*
X402125Y138167D01*
X401917Y137958D01*
X401833Y137708D01*
Y137292D01*
X401708Y136917D01*
X401458Y136667D01*
X401167Y136583D01*
X400875Y136667D01*
X400667Y136875D01*
X400542Y137208D01*
X400500Y137500D01*
G01Y139767D02*
X403000D01*
Y140767D01*
X402875Y141100D01*
X402583Y141350D01*
X402250Y141433D01*
X401917Y141350D01*
X401667Y141142D01*
X401542Y140767D01*
Y139767D01*
G01X402583Y142908D02*
X402833Y143158D01*
X402958Y143450D01*
X403000Y143783D01*
X402917Y144200D01*
X402708Y144492D01*
X402458Y144575D01*
X402208Y144533D01*
X402000Y144367D01*
X401583Y143533D01*
X401292Y143158D01*
X400875Y142908D01*
X400500Y142825D01*
Y144575D01*
G01X400875Y145883D02*
X400667Y146133D01*
X400542Y146425D01*
X400500Y146800D01*
X400583Y147175D01*
X400750Y147467D01*
X401042Y147675D01*
X401375Y147717D01*
X401708Y147633D01*
X401917Y147425D01*
X402083Y147133D01*
X402125Y146842D01*
X402083Y146550D01*
X401917Y146175D01*
X403000Y146300D01*
Y147425D01*
G01X368491Y107442D02*
X368741Y107567D01*
X369033Y107650D01*
X369366D01*
X369741Y107525D01*
X370033Y107317D01*
X370241Y107067D01*
X370408Y106650D01*
X370450Y106275D01*
X370366Y105900D01*
X370241Y105650D01*
X369991Y105400D01*
X369700Y105233D01*
X369408Y105150D01*
X369116D01*
X368825Y105233D01*
X368575Y105358D01*
X368366Y105525D01*
G01X366308Y105150D02*
X366016Y105192D01*
X365683Y105317D01*
X365475Y105525D01*
X365391Y105817D01*
X365475Y106108D01*
X365725Y106358D01*
X366100Y106483D01*
X366516D01*
X366766Y106567D01*
X366975Y106775D01*
X367058Y107067D01*
X366933Y107358D01*
X366641Y107567D01*
X366308Y107650D01*
X365975Y107567D01*
X365683Y107358D01*
X365558Y107067D01*
X365641Y106775D01*
X365850Y106567D01*
X366100Y106483D01*
X366516D01*
X366891Y106358D01*
X367141Y106108D01*
X367225Y105817D01*
X367141Y105525D01*
X366933Y105317D01*
X366600Y105192D01*
X366308Y105150D01*
G01X363208Y107650D02*
Y105150D01*
G01X364166Y107650D02*
X362250D01*
G01X361025Y105650D02*
X360775Y105358D01*
X360441Y105192D01*
X360066Y105150D01*
X359733Y105192D01*
X359400Y105400D01*
X359191Y105650D01*
X359150Y105900D01*
X359233Y106192D01*
X359525Y106400D01*
X359816Y106483D01*
X360191D01*
G01X359816D02*
X359566Y106608D01*
X359358Y106817D01*
X359275Y107067D01*
X359358Y107317D01*
X359566Y107525D01*
X359941Y107650D01*
X360316Y107608D01*
X360691Y107442D01*
G01X375823Y143116D02*
X376073Y143241D01*
X376365Y143324D01*
X376698D01*
X377073Y143199D01*
X377365Y142991D01*
X377573Y142741D01*
X377740Y142324D01*
X377782Y141949D01*
X377698Y141574D01*
X377573Y141324D01*
X377323Y141074D01*
X377032Y140907D01*
X376740Y140824D01*
X376448D01*
X376157Y140907D01*
X375907Y141032D01*
X375698Y141199D01*
G01X374557D02*
X374307Y140991D01*
X374015Y140866D01*
X373640Y140824D01*
X373265Y140907D01*
X372973Y141074D01*
X372765Y141366D01*
X372723Y141699D01*
X372807Y142032D01*
X373015Y142241D01*
X373307Y142407D01*
X373598Y142449D01*
X373890Y142407D01*
X374265Y142241D01*
X374140Y143324D01*
X373015D01*
G01X370290Y142074D02*
X369457D01*
Y141324D01*
X369707Y141074D01*
X369998Y140907D01*
X370415Y140824D01*
X370832Y140907D01*
X371123Y141074D01*
X371373Y141324D01*
X371540Y141616D01*
X371623Y141949D01*
Y142241D01*
X371540Y142491D01*
X371373Y142782D01*
X371123Y143032D01*
X370873Y143199D01*
X370540Y143324D01*
X370248D01*
X369915Y143241D01*
X369665Y143074D01*
G01X368148Y141116D02*
X367857Y140907D01*
X367523Y140824D01*
X367190Y140907D01*
X366898Y141157D01*
X366690Y141532D01*
X366607Y141907D01*
Y142366D01*
X366690Y142741D01*
X366898Y143074D01*
X367148Y143241D01*
X367440Y143324D01*
X367773Y143241D01*
X368023Y143074D01*
X368190Y142824D01*
X368273Y142491D01*
X368190Y142199D01*
X367982Y141907D01*
X367732Y141741D01*
X367440Y141699D01*
X367107Y141782D01*
X366857Y141991D01*
X366607Y142366D01*
G01X365132Y141866D02*
X364840Y142157D01*
X364590Y142324D01*
X364257Y142407D01*
X363965Y142324D01*
X363757Y142157D01*
X363590Y141907D01*
X363548Y141616D01*
X363590Y141366D01*
X363757Y141116D01*
X364007Y140907D01*
X364298Y140824D01*
X364632Y140907D01*
X364923Y141157D01*
X365090Y141532D01*
X365132Y141949D01*
X365048Y142491D01*
X364923Y142782D01*
X364715Y143074D01*
X364423Y143282D01*
X364132Y143324D01*
X363840Y143241D01*
X363632Y143032D01*
G01X375823Y135116D02*
X376073Y135241D01*
X376365Y135324D01*
X376698D01*
X377073Y135199D01*
X377365Y134991D01*
X377573Y134741D01*
X377740Y134324D01*
X377782Y133949D01*
X377698Y133574D01*
X377573Y133324D01*
X377323Y133074D01*
X377032Y132907D01*
X376740Y132824D01*
X376448D01*
X376157Y132907D01*
X375907Y133032D01*
X375698Y133199D01*
G01X374557D02*
X374307Y132991D01*
X374015Y132866D01*
X373640Y132824D01*
X373265Y132907D01*
X372973Y133074D01*
X372765Y133366D01*
X372723Y133699D01*
X372807Y134032D01*
X373015Y134241D01*
X373307Y134407D01*
X373598Y134449D01*
X373890Y134407D01*
X374265Y134241D01*
X374140Y135324D01*
X373015D01*
G01X370290Y134074D02*
X369457D01*
Y133324D01*
X369707Y133074D01*
X369998Y132907D01*
X370415Y132824D01*
X370832Y132907D01*
X371123Y133074D01*
X371373Y133324D01*
X371540Y133616D01*
X371623Y133949D01*
Y134241D01*
X371540Y134491D01*
X371373Y134782D01*
X371123Y135032D01*
X370873Y135199D01*
X370540Y135324D01*
X370248D01*
X369915Y135241D01*
X369665Y135074D01*
G01X368148Y133116D02*
X367857Y132907D01*
X367523Y132824D01*
X367190Y132907D01*
X366898Y133157D01*
X366690Y133532D01*
X366607Y133907D01*
Y134366D01*
X366690Y134741D01*
X366898Y135074D01*
X367148Y135241D01*
X367440Y135324D01*
X367773Y135241D01*
X368023Y135074D01*
X368190Y134824D01*
X368273Y134491D01*
X368190Y134199D01*
X367982Y133907D01*
X367732Y133741D01*
X367440Y133699D01*
X367107Y133782D01*
X366857Y133991D01*
X366607Y134366D01*
G01X365132Y134907D02*
X364882Y135157D01*
X364590Y135282D01*
X364257Y135324D01*
X363840Y135241D01*
X363548Y135032D01*
X363465Y134782D01*
X363507Y134532D01*
X363673Y134324D01*
X364507Y133907D01*
X364882Y133616D01*
X365132Y133199D01*
X365215Y132824D01*
X363465D01*
G01X377427Y100000D02*
X377350Y100672D01*
X377235Y101240D01*
X377082Y101757D01*
X376890Y102325D01*
X376583Y103100D01*
X378117D01*
G01X374327Y100000D02*
X374250Y100672D01*
X374135Y101240D01*
X373982Y101757D01*
X373790Y102325D01*
X373483Y103100D01*
X375017D01*
G01X391927Y100000D02*
X391850Y100672D01*
X391735Y101240D01*
X391582Y101757D01*
X391390Y102325D01*
X391083Y103100D01*
X392617D01*
G01X388750Y100000D02*
X388482Y100052D01*
X388175Y100207D01*
X387983Y100465D01*
X387907Y100827D01*
X387983Y101188D01*
X388213Y101498D01*
X388558Y101653D01*
X388942D01*
X389172Y101757D01*
X389363Y102015D01*
X389440Y102377D01*
X389325Y102738D01*
X389057Y102997D01*
X388750Y103100D01*
X388443Y102997D01*
X388175Y102738D01*
X388060Y102377D01*
X388137Y102015D01*
X388328Y101757D01*
X388558Y101653D01*
X388942D01*
X389287Y101498D01*
X389517Y101188D01*
X389593Y100827D01*
X389517Y100465D01*
X389325Y100207D01*
X389018Y100052D01*
X388750Y100000D01*
G01X375823Y139116D02*
X376073Y139241D01*
X376365Y139324D01*
X376698D01*
X377073Y139199D01*
X377365Y138991D01*
X377573Y138741D01*
X377740Y138324D01*
X377782Y137949D01*
X377698Y137574D01*
X377573Y137324D01*
X377323Y137074D01*
X377032Y136907D01*
X376740Y136824D01*
X376448D01*
X376157Y136907D01*
X375907Y137032D01*
X375698Y137199D01*
G01X373723Y136824D02*
X373640Y137366D01*
X373515Y137824D01*
X373348Y138241D01*
X373140Y138699D01*
X372807Y139324D01*
X374473D01*
G01X371457D02*
Y137532D01*
X371290Y137157D01*
X370957Y136907D01*
X370540Y136824D01*
X370123Y136907D01*
X369790Y137157D01*
X369623Y137532D01*
Y139324D01*
G01X367440Y136824D02*
Y139324D01*
X367940Y138824D01*
G01Y136824D02*
X366940D01*
G01X375823Y147116D02*
X376073Y147241D01*
X376365Y147324D01*
X376698D01*
X377073Y147199D01*
X377365Y146991D01*
X377573Y146741D01*
X377740Y146324D01*
X377782Y145949D01*
X377698Y145574D01*
X377573Y145324D01*
X377323Y145074D01*
X377032Y144907D01*
X376740Y144824D01*
X376448D01*
X376157Y144907D01*
X375907Y145032D01*
X375698Y145199D01*
G01X373723Y144824D02*
X373640Y145366D01*
X373515Y145824D01*
X373348Y146241D01*
X373140Y146699D01*
X372807Y147324D01*
X374473D01*
G01X370540D02*
Y144824D01*
G01X371498Y147324D02*
X369582D01*
G01X366940Y144824D02*
Y147324D01*
X368482Y145532D01*
X366398D01*
G01X413292Y185467D02*
X413417Y185217D01*
X413500Y184925D01*
Y184592D01*
X413375Y184217D01*
X413167Y183925D01*
X412917Y183717D01*
X412500Y183550D01*
X412125Y183508D01*
X411750Y183592D01*
X411500Y183717D01*
X411250Y183967D01*
X411083Y184258D01*
X411000Y184550D01*
Y184842D01*
X411083Y185133D01*
X411208Y185383D01*
X411375Y185592D01*
G01X411000Y187650D02*
X411042Y187942D01*
X411167Y188275D01*
X411375Y188483D01*
X411667Y188567D01*
X411958Y188483D01*
X412208Y188233D01*
X412333Y187858D01*
Y187442D01*
X412417Y187192D01*
X412625Y186983D01*
X412917Y186900D01*
X413208Y187025D01*
X413417Y187317D01*
X413500Y187650D01*
X413417Y187983D01*
X413208Y188275D01*
X412917Y188400D01*
X412625Y188317D01*
X412417Y188108D01*
X412333Y187858D01*
Y187442D01*
X412208Y187067D01*
X411958Y186817D01*
X411667Y186733D01*
X411375Y186817D01*
X411167Y187025D01*
X411042Y187358D01*
X411000Y187650D01*
G01Y189917D02*
X413500D01*
Y190917D01*
X413375Y191250D01*
X413083Y191500D01*
X412750Y191583D01*
X412417Y191500D01*
X412167Y191292D01*
X412042Y190917D01*
Y189917D01*
G01X411000Y194350D02*
X413500D01*
X411708Y192808D01*
Y194892D01*
G01X417292Y185467D02*
X417417Y185217D01*
X417500Y184925D01*
Y184592D01*
X417375Y184217D01*
X417167Y183925D01*
X416917Y183717D01*
X416500Y183550D01*
X416125Y183508D01*
X415750Y183592D01*
X415500Y183717D01*
X415250Y183967D01*
X415083Y184258D01*
X415000Y184550D01*
Y184842D01*
X415083Y185133D01*
X415208Y185383D01*
X415375Y185592D01*
G01X415000Y187650D02*
X415042Y187942D01*
X415167Y188275D01*
X415375Y188483D01*
X415667Y188567D01*
X415958Y188483D01*
X416208Y188233D01*
X416333Y187858D01*
Y187442D01*
X416417Y187192D01*
X416625Y186983D01*
X416917Y186900D01*
X417208Y187025D01*
X417417Y187317D01*
X417500Y187650D01*
X417417Y187983D01*
X417208Y188275D01*
X416917Y188400D01*
X416625Y188317D01*
X416417Y188108D01*
X416333Y187858D01*
Y187442D01*
X416208Y187067D01*
X415958Y186817D01*
X415667Y186733D01*
X415375Y186817D01*
X415167Y187025D01*
X415042Y187358D01*
X415000Y187650D01*
G01Y189917D02*
X417500D01*
Y190917D01*
X417375Y191250D01*
X417083Y191500D01*
X416750Y191583D01*
X416417Y191500D01*
X416167Y191292D01*
X416042Y190917D01*
Y189917D01*
G01X415500Y192933D02*
X415208Y193183D01*
X415042Y193517D01*
X415000Y193892D01*
X415042Y194225D01*
X415250Y194558D01*
X415500Y194767D01*
X415750Y194808D01*
X416042Y194725D01*
X416250Y194433D01*
X416333Y194142D01*
Y193767D01*
G01Y194142D02*
X416458Y194392D01*
X416667Y194600D01*
X416917Y194683D01*
X417167Y194600D01*
X417375Y194392D01*
X417500Y194017D01*
X417458Y193642D01*
X417292Y193267D01*
G01X411192Y169767D02*
X411317Y169517D01*
X411400Y169225D01*
Y168892D01*
X411275Y168517D01*
X411067Y168225D01*
X410817Y168017D01*
X410400Y167850D01*
X410025Y167808D01*
X409650Y167892D01*
X409400Y168017D01*
X409150Y168267D01*
X408983Y168558D01*
X408900Y168850D01*
Y169142D01*
X408983Y169433D01*
X409108Y169683D01*
X409275Y169892D01*
G01X408900Y171950D02*
X408942Y172242D01*
X409067Y172575D01*
X409275Y172783D01*
X409567Y172867D01*
X409858Y172783D01*
X410108Y172533D01*
X410233Y172158D01*
Y171742D01*
X410317Y171492D01*
X410525Y171283D01*
X410817Y171200D01*
X411108Y171325D01*
X411317Y171617D01*
X411400Y171950D01*
X411317Y172283D01*
X411108Y172575D01*
X410817Y172700D01*
X410525Y172617D01*
X410317Y172408D01*
X410233Y172158D01*
Y171742D01*
X410108Y171367D01*
X409858Y171117D01*
X409567Y171033D01*
X409275Y171117D01*
X409067Y171325D01*
X408942Y171658D01*
X408900Y171950D01*
G01Y174217D02*
X411400D01*
Y175217D01*
X411275Y175550D01*
X410983Y175800D01*
X410650Y175883D01*
X410317Y175800D01*
X410067Y175592D01*
X409942Y175217D01*
Y174217D01*
G01X409192Y177442D02*
X408983Y177733D01*
X408900Y178067D01*
X408983Y178400D01*
X409233Y178692D01*
X409608Y178900D01*
X409983Y178983D01*
X410442D01*
X410817Y178900D01*
X411150Y178692D01*
X411317Y178442D01*
X411400Y178150D01*
X411317Y177817D01*
X411150Y177567D01*
X410900Y177400D01*
X410567Y177317D01*
X410275Y177400D01*
X409983Y177608D01*
X409817Y177858D01*
X409775Y178150D01*
X409858Y178483D01*
X410067Y178733D01*
X410442Y178983D01*
G01X415192Y169767D02*
X415317Y169517D01*
X415400Y169225D01*
Y168892D01*
X415275Y168517D01*
X415067Y168225D01*
X414817Y168017D01*
X414400Y167850D01*
X414025Y167808D01*
X413650Y167892D01*
X413400Y168017D01*
X413150Y168267D01*
X412983Y168558D01*
X412900Y168850D01*
Y169142D01*
X412983Y169433D01*
X413108Y169683D01*
X413275Y169892D01*
G01X412900Y171950D02*
X412942Y172242D01*
X413067Y172575D01*
X413275Y172783D01*
X413567Y172867D01*
X413858Y172783D01*
X414108Y172533D01*
X414233Y172158D01*
Y171742D01*
X414317Y171492D01*
X414525Y171283D01*
X414817Y171200D01*
X415108Y171325D01*
X415317Y171617D01*
X415400Y171950D01*
X415317Y172283D01*
X415108Y172575D01*
X414817Y172700D01*
X414525Y172617D01*
X414317Y172408D01*
X414233Y172158D01*
Y171742D01*
X414108Y171367D01*
X413858Y171117D01*
X413567Y171033D01*
X413275Y171117D01*
X413067Y171325D01*
X412942Y171658D01*
X412900Y171950D01*
G01Y174217D02*
X415400D01*
Y175217D01*
X415275Y175550D01*
X414983Y175800D01*
X414650Y175883D01*
X414317Y175800D01*
X414067Y175592D01*
X413942Y175217D01*
Y174217D01*
G01X412900Y178150D02*
X412942Y178442D01*
X413067Y178775D01*
X413275Y178983D01*
X413567Y179067D01*
X413858Y178983D01*
X414108Y178733D01*
X414233Y178358D01*
Y177942D01*
X414317Y177692D01*
X414525Y177483D01*
X414817Y177400D01*
X415108Y177525D01*
X415317Y177817D01*
X415400Y178150D01*
X415317Y178483D01*
X415108Y178775D01*
X414817Y178900D01*
X414525Y178817D01*
X414317Y178608D01*
X414233Y178358D01*
Y177942D01*
X414108Y177567D01*
X413858Y177317D01*
X413567Y177233D01*
X413275Y177317D01*
X413067Y177525D01*
X412942Y177858D01*
X412900Y178150D01*
G01X419192Y169767D02*
X419317Y169517D01*
X419400Y169225D01*
Y168892D01*
X419275Y168517D01*
X419067Y168225D01*
X418817Y168017D01*
X418400Y167850D01*
X418025Y167808D01*
X417650Y167892D01*
X417400Y168017D01*
X417150Y168267D01*
X416983Y168558D01*
X416900Y168850D01*
Y169142D01*
X416983Y169433D01*
X417108Y169683D01*
X417275Y169892D01*
G01X416900Y171867D02*
X417442Y171950D01*
X417900Y172075D01*
X418317Y172242D01*
X418775Y172450D01*
X419400Y172783D01*
Y171117D01*
G01X416900Y174217D02*
X419400D01*
Y175217D01*
X419275Y175550D01*
X418983Y175800D01*
X418650Y175883D01*
X418317Y175800D01*
X418067Y175592D01*
X417942Y175217D01*
Y174217D01*
G01X416900Y178067D02*
X417442Y178150D01*
X417900Y178275D01*
X418317Y178442D01*
X418775Y178650D01*
X419400Y178983D01*
Y177317D01*
G01X391192Y169767D02*
X391317Y169517D01*
X391400Y169225D01*
Y168892D01*
X391275Y168517D01*
X391067Y168225D01*
X390817Y168017D01*
X390400Y167850D01*
X390025Y167808D01*
X389650Y167892D01*
X389400Y168017D01*
X389150Y168267D01*
X388983Y168558D01*
X388900Y168850D01*
Y169142D01*
X388983Y169433D01*
X389108Y169683D01*
X389275Y169892D01*
G01X388900Y171950D02*
X388942Y172242D01*
X389067Y172575D01*
X389275Y172783D01*
X389567Y172867D01*
X389858Y172783D01*
X390108Y172533D01*
X390233Y172158D01*
Y171742D01*
X390317Y171492D01*
X390525Y171283D01*
X390817Y171200D01*
X391108Y171325D01*
X391317Y171617D01*
X391400Y171950D01*
X391317Y172283D01*
X391108Y172575D01*
X390817Y172700D01*
X390525Y172617D01*
X390317Y172408D01*
X390233Y172158D01*
Y171742D01*
X390108Y171367D01*
X389858Y171117D01*
X389567Y171033D01*
X389275Y171117D01*
X389067Y171325D01*
X388942Y171658D01*
X388900Y171950D01*
G01Y174217D02*
X391400D01*
Y175217D01*
X391275Y175550D01*
X390983Y175800D01*
X390650Y175883D01*
X390317Y175800D01*
X390067Y175592D01*
X389942Y175217D01*
Y174217D01*
G01Y177358D02*
X390233Y177650D01*
X390400Y177900D01*
X390483Y178233D01*
X390400Y178525D01*
X390233Y178733D01*
X389983Y178900D01*
X389692Y178942D01*
X389442Y178900D01*
X389192Y178733D01*
X388983Y178483D01*
X388900Y178192D01*
X388983Y177858D01*
X389233Y177567D01*
X389608Y177400D01*
X390025Y177358D01*
X390567Y177442D01*
X390858Y177567D01*
X391150Y177775D01*
X391358Y178067D01*
X391400Y178358D01*
X391317Y178650D01*
X391108Y178858D01*
G01X405292Y185467D02*
X405417Y185217D01*
X405500Y184925D01*
Y184592D01*
X405375Y184217D01*
X405167Y183925D01*
X404917Y183717D01*
X404500Y183550D01*
X404125Y183508D01*
X403750Y183592D01*
X403500Y183717D01*
X403250Y183967D01*
X403083Y184258D01*
X403000Y184550D01*
Y184842D01*
X403083Y185133D01*
X403208Y185383D01*
X403375Y185592D01*
G01X403000Y187650D02*
X403042Y187942D01*
X403167Y188275D01*
X403375Y188483D01*
X403667Y188567D01*
X403958Y188483D01*
X404208Y188233D01*
X404333Y187858D01*
Y187442D01*
X404417Y187192D01*
X404625Y186983D01*
X404917Y186900D01*
X405208Y187025D01*
X405417Y187317D01*
X405500Y187650D01*
X405417Y187983D01*
X405208Y188275D01*
X404917Y188400D01*
X404625Y188317D01*
X404417Y188108D01*
X404333Y187858D01*
Y187442D01*
X404208Y187067D01*
X403958Y186817D01*
X403667Y186733D01*
X403375Y186817D01*
X403167Y187025D01*
X403042Y187358D01*
X403000Y187650D01*
G01Y189917D02*
X405500D01*
Y190917D01*
X405375Y191250D01*
X405083Y191500D01*
X404750Y191583D01*
X404417Y191500D01*
X404167Y191292D01*
X404042Y190917D01*
Y189917D01*
G01X405083Y193058D02*
X405333Y193308D01*
X405458Y193600D01*
X405500Y193933D01*
X405417Y194350D01*
X405208Y194642D01*
X404958Y194725D01*
X404708Y194683D01*
X404500Y194517D01*
X404083Y193683D01*
X403792Y193308D01*
X403375Y193058D01*
X403000Y192975D01*
Y194725D01*
G01X409292Y185467D02*
X409417Y185217D01*
X409500Y184925D01*
Y184592D01*
X409375Y184217D01*
X409167Y183925D01*
X408917Y183717D01*
X408500Y183550D01*
X408125Y183508D01*
X407750Y183592D01*
X407500Y183717D01*
X407250Y183967D01*
X407083Y184258D01*
X407000Y184550D01*
Y184842D01*
X407083Y185133D01*
X407208Y185383D01*
X407375Y185592D01*
G01X407000Y187650D02*
X407042Y187942D01*
X407167Y188275D01*
X407375Y188483D01*
X407667Y188567D01*
X407958Y188483D01*
X408208Y188233D01*
X408333Y187858D01*
Y187442D01*
X408417Y187192D01*
X408625Y186983D01*
X408917Y186900D01*
X409208Y187025D01*
X409417Y187317D01*
X409500Y187650D01*
X409417Y187983D01*
X409208Y188275D01*
X408917Y188400D01*
X408625Y188317D01*
X408417Y188108D01*
X408333Y187858D01*
Y187442D01*
X408208Y187067D01*
X407958Y186817D01*
X407667Y186733D01*
X407375Y186817D01*
X407167Y187025D01*
X407042Y187358D01*
X407000Y187650D01*
G01Y189917D02*
X409500D01*
Y190917D01*
X409375Y191250D01*
X409083Y191500D01*
X408750Y191583D01*
X408417Y191500D01*
X408167Y191292D01*
X408042Y190917D01*
Y189917D01*
G01X407000Y193850D02*
X409500D01*
X409000Y193350D01*
G01X407000D02*
Y194350D01*
G01X399192Y169767D02*
X399317Y169517D01*
X399400Y169225D01*
Y168892D01*
X399275Y168517D01*
X399067Y168225D01*
X398817Y168017D01*
X398400Y167850D01*
X398025Y167808D01*
X397650Y167892D01*
X397400Y168017D01*
X397150Y168267D01*
X396983Y168558D01*
X396900Y168850D01*
Y169142D01*
X396983Y169433D01*
X397108Y169683D01*
X397275Y169892D01*
G01X396900Y171950D02*
X396942Y172242D01*
X397067Y172575D01*
X397275Y172783D01*
X397567Y172867D01*
X397858Y172783D01*
X398108Y172533D01*
X398233Y172158D01*
Y171742D01*
X398317Y171492D01*
X398525Y171283D01*
X398817Y171200D01*
X399108Y171325D01*
X399317Y171617D01*
X399400Y171950D01*
X399317Y172283D01*
X399108Y172575D01*
X398817Y172700D01*
X398525Y172617D01*
X398317Y172408D01*
X398233Y172158D01*
Y171742D01*
X398108Y171367D01*
X397858Y171117D01*
X397567Y171033D01*
X397275Y171117D01*
X397067Y171325D01*
X396942Y171658D01*
X396900Y171950D01*
G01Y174217D02*
X399400D01*
Y175217D01*
X399275Y175550D01*
X398983Y175800D01*
X398650Y175883D01*
X398317Y175800D01*
X398067Y175592D01*
X397942Y175217D01*
Y174217D01*
G01X396900Y178150D02*
X399400D01*
X398900Y177650D01*
G01X396900D02*
Y178650D01*
G01X398983Y180458D02*
X399233Y180708D01*
X399358Y181000D01*
X399400Y181333D01*
X399317Y181750D01*
X399108Y182042D01*
X398858Y182125D01*
X398608Y182083D01*
X398400Y181917D01*
X397983Y181083D01*
X397692Y180708D01*
X397275Y180458D01*
X396900Y180375D01*
Y182125D01*
G01X395192Y169767D02*
X395317Y169517D01*
X395400Y169225D01*
Y168892D01*
X395275Y168517D01*
X395067Y168225D01*
X394817Y168017D01*
X394400Y167850D01*
X394025Y167808D01*
X393650Y167892D01*
X393400Y168017D01*
X393150Y168267D01*
X392983Y168558D01*
X392900Y168850D01*
Y169142D01*
X392983Y169433D01*
X393108Y169683D01*
X393275Y169892D01*
G01X392900Y171950D02*
X392942Y172242D01*
X393067Y172575D01*
X393275Y172783D01*
X393567Y172867D01*
X393858Y172783D01*
X394108Y172533D01*
X394233Y172158D01*
Y171742D01*
X394317Y171492D01*
X394525Y171283D01*
X394817Y171200D01*
X395108Y171325D01*
X395317Y171617D01*
X395400Y171950D01*
X395317Y172283D01*
X395108Y172575D01*
X394817Y172700D01*
X394525Y172617D01*
X394317Y172408D01*
X394233Y172158D01*
Y171742D01*
X394108Y171367D01*
X393858Y171117D01*
X393567Y171033D01*
X393275Y171117D01*
X393067Y171325D01*
X392942Y171658D01*
X392900Y171950D01*
G01Y174217D02*
X395400D01*
Y175217D01*
X395275Y175550D01*
X394983Y175800D01*
X394650Y175883D01*
X394317Y175800D01*
X394067Y175592D01*
X393942Y175217D01*
Y174217D01*
G01X392900Y178150D02*
X395400D01*
X394900Y177650D01*
G01X392900D02*
Y178650D01*
G01X393400Y180333D02*
X393108Y180583D01*
X392942Y180917D01*
X392900Y181292D01*
X392942Y181625D01*
X393150Y181958D01*
X393400Y182167D01*
X393650Y182208D01*
X393942Y182125D01*
X394150Y181833D01*
X394233Y181542D01*
Y181167D01*
G01Y181542D02*
X394358Y181792D01*
X394567Y182000D01*
X394817Y182083D01*
X395067Y182000D01*
X395275Y181792D01*
X395400Y181417D01*
X395358Y181042D01*
X395192Y180667D01*
G01X403192Y169767D02*
X403317Y169517D01*
X403400Y169225D01*
Y168892D01*
X403275Y168517D01*
X403067Y168225D01*
X402817Y168017D01*
X402400Y167850D01*
X402025Y167808D01*
X401650Y167892D01*
X401400Y168017D01*
X401150Y168267D01*
X400983Y168558D01*
X400900Y168850D01*
Y169142D01*
X400983Y169433D01*
X401108Y169683D01*
X401275Y169892D01*
G01X400900Y171950D02*
X400942Y172242D01*
X401067Y172575D01*
X401275Y172783D01*
X401567Y172867D01*
X401858Y172783D01*
X402108Y172533D01*
X402233Y172158D01*
Y171742D01*
X402317Y171492D01*
X402525Y171283D01*
X402817Y171200D01*
X403108Y171325D01*
X403317Y171617D01*
X403400Y171950D01*
X403317Y172283D01*
X403108Y172575D01*
X402817Y172700D01*
X402525Y172617D01*
X402317Y172408D01*
X402233Y172158D01*
Y171742D01*
X402108Y171367D01*
X401858Y171117D01*
X401567Y171033D01*
X401275Y171117D01*
X401067Y171325D01*
X400942Y171658D01*
X400900Y171950D01*
G01Y174217D02*
X403400D01*
Y175217D01*
X403275Y175550D01*
X402983Y175800D01*
X402650Y175883D01*
X402317Y175800D01*
X402067Y175592D01*
X401942Y175217D01*
Y174217D01*
G01X400900Y178150D02*
X403400D01*
X402900Y177650D01*
G01X400900D02*
Y178650D01*
G01Y181250D02*
X403400D01*
X402900Y180750D01*
G01X400900D02*
Y181750D01*
G01X407192Y169767D02*
X407317Y169517D01*
X407400Y169225D01*
Y168892D01*
X407275Y168517D01*
X407067Y168225D01*
X406817Y168017D01*
X406400Y167850D01*
X406025Y167808D01*
X405650Y167892D01*
X405400Y168017D01*
X405150Y168267D01*
X404983Y168558D01*
X404900Y168850D01*
Y169142D01*
X404983Y169433D01*
X405108Y169683D01*
X405275Y169892D01*
G01X404900Y171950D02*
X404942Y172242D01*
X405067Y172575D01*
X405275Y172783D01*
X405567Y172867D01*
X405858Y172783D01*
X406108Y172533D01*
X406233Y172158D01*
Y171742D01*
X406317Y171492D01*
X406525Y171283D01*
X406817Y171200D01*
X407108Y171325D01*
X407317Y171617D01*
X407400Y171950D01*
X407317Y172283D01*
X407108Y172575D01*
X406817Y172700D01*
X406525Y172617D01*
X406317Y172408D01*
X406233Y172158D01*
Y171742D01*
X406108Y171367D01*
X405858Y171117D01*
X405567Y171033D01*
X405275Y171117D01*
X405067Y171325D01*
X404942Y171658D01*
X404900Y171950D01*
G01Y174217D02*
X407400D01*
Y175217D01*
X407275Y175550D01*
X406983Y175800D01*
X406650Y175883D01*
X406317Y175800D01*
X406067Y175592D01*
X405942Y175217D01*
Y174217D01*
G01X404900Y178150D02*
X407400D01*
X406900Y177650D01*
G01X404900D02*
Y178650D01*
G01X407400Y181250D02*
X407317Y180917D01*
X407108Y180667D01*
X406858Y180500D01*
X406525Y180375D01*
X406150Y180333D01*
X405775Y180375D01*
X405442Y180500D01*
X405192Y180667D01*
X404983Y180917D01*
X404900Y181250D01*
X404983Y181583D01*
X405192Y181833D01*
X405442Y182000D01*
X405775Y182125D01*
X406150Y182167D01*
X406525Y182125D01*
X406858Y182000D01*
X407108Y181833D01*
X407317Y181583D01*
X407400Y181250D01*
G01X398589Y187602D02*
X398839Y187727D01*
X399131Y187810D01*
X399464D01*
X399839Y187685D01*
X400131Y187477D01*
X400339Y187227D01*
X400506Y186810D01*
X400548Y186435D01*
X400464Y186060D01*
X400339Y185810D01*
X400089Y185560D01*
X399798Y185393D01*
X399506Y185310D01*
X399214D01*
X398923Y185393D01*
X398673Y185518D01*
X398464Y185685D01*
G01X396406Y185310D02*
X396114Y185352D01*
X395781Y185477D01*
X395573Y185685D01*
X395489Y185977D01*
X395573Y186268D01*
X395823Y186518D01*
X396198Y186643D01*
X396614D01*
X396864Y186727D01*
X397073Y186935D01*
X397156Y187227D01*
X397031Y187518D01*
X396739Y187727D01*
X396406Y187810D01*
X396073Y187727D01*
X395781Y187518D01*
X395656Y187227D01*
X395739Y186935D01*
X395948Y186727D01*
X396198Y186643D01*
X396614D01*
X396989Y186518D01*
X397239Y186268D01*
X397323Y185977D01*
X397239Y185685D01*
X397031Y185477D01*
X396698Y185352D01*
X396406Y185310D01*
G01X394139D02*
Y187810D01*
X393139D01*
X392806Y187685D01*
X392556Y187393D01*
X392473Y187060D01*
X392556Y186727D01*
X392764Y186477D01*
X393139Y186352D01*
X394139D01*
G01X391123Y185685D02*
X390873Y185477D01*
X390581Y185352D01*
X390206Y185310D01*
X389831Y185393D01*
X389539Y185560D01*
X389331Y185852D01*
X389289Y186185D01*
X389373Y186518D01*
X389581Y186727D01*
X389873Y186893D01*
X390164Y186935D01*
X390456Y186893D01*
X390831Y186727D01*
X390706Y187810D01*
X389581D01*
G01X387192Y169767D02*
X387317Y169517D01*
X387400Y169225D01*
Y168892D01*
X387275Y168517D01*
X387067Y168225D01*
X386817Y168017D01*
X386400Y167850D01*
X386025Y167808D01*
X385650Y167892D01*
X385400Y168017D01*
X385150Y168267D01*
X384983Y168558D01*
X384900Y168850D01*
Y169142D01*
X384983Y169433D01*
X385108Y169683D01*
X385275Y169892D01*
G01X384900Y171950D02*
X384942Y172242D01*
X385067Y172575D01*
X385275Y172783D01*
X385567Y172867D01*
X385858Y172783D01*
X386108Y172533D01*
X386233Y172158D01*
Y171742D01*
X386317Y171492D01*
X386525Y171283D01*
X386817Y171200D01*
X387108Y171325D01*
X387317Y171617D01*
X387400Y171950D01*
X387317Y172283D01*
X387108Y172575D01*
X386817Y172700D01*
X386525Y172617D01*
X386317Y172408D01*
X386233Y172158D01*
Y171742D01*
X386108Y171367D01*
X385858Y171117D01*
X385567Y171033D01*
X385275Y171117D01*
X385067Y171325D01*
X384942Y171658D01*
X384900Y171950D01*
G01Y174217D02*
X387400D01*
Y175217D01*
X387275Y175550D01*
X386983Y175800D01*
X386650Y175883D01*
X386317Y175800D01*
X386067Y175592D01*
X385942Y175217D01*
Y174217D01*
G01X384900Y178067D02*
X385442Y178150D01*
X385900Y178275D01*
X386317Y178442D01*
X386775Y178650D01*
X387400Y178983D01*
Y177317D01*
G01X466000Y302200D02*
Y328000D01*
X444000D01*
Y341000D01*
X387400D01*
Y334200D01*
X373900D01*
Y329800D01*
X364800D01*
Y315300D01*
X362700D01*
Y275500D01*
X374100D01*
Y259500D01*
X438800D01*
Y261500D01*
X442300D01*
Y265000D01*
G01X382593Y457640D02*
X382843Y457765D01*
X383135Y457848D01*
X383468D01*
X383843Y457723D01*
X384135Y457515D01*
X384343Y457265D01*
X384510Y456848D01*
X384552Y456473D01*
X384468Y456098D01*
X384343Y455848D01*
X384093Y455598D01*
X383802Y455431D01*
X383510Y455348D01*
X383218D01*
X382927Y455431D01*
X382677Y455556D01*
X382468Y455723D01*
G01X381327D02*
X381077Y455515D01*
X380785Y455390D01*
X380410Y455348D01*
X380035Y455431D01*
X379743Y455598D01*
X379535Y455890D01*
X379493Y456223D01*
X379577Y456556D01*
X379785Y456765D01*
X380077Y456931D01*
X380368Y456973D01*
X380660Y456931D01*
X381035Y456765D01*
X380910Y457848D01*
X379785D01*
G01X377060Y456598D02*
X376227D01*
Y455848D01*
X376477Y455598D01*
X376768Y455431D01*
X377185Y455348D01*
X377602Y455431D01*
X377893Y455598D01*
X378143Y455848D01*
X378310Y456140D01*
X378393Y456473D01*
Y456765D01*
X378310Y457015D01*
X378143Y457306D01*
X377893Y457556D01*
X377643Y457723D01*
X377310Y457848D01*
X377018D01*
X376685Y457765D01*
X376435Y457598D01*
G01X374210Y455348D02*
Y457848D01*
X374710Y457348D01*
G01Y455348D02*
X373710D01*
G01X371110Y457848D02*
X371443Y457765D01*
X371693Y457556D01*
X371860Y457306D01*
X371985Y456973D01*
X372027Y456598D01*
X371985Y456223D01*
X371860Y455890D01*
X371693Y455640D01*
X371443Y455431D01*
X371110Y455348D01*
X370777Y455431D01*
X370527Y455640D01*
X370360Y455890D01*
X370235Y456223D01*
X370193Y456598D01*
X370235Y456973D01*
X370360Y457306D01*
X370527Y457556D01*
X370777Y457765D01*
X371110Y457848D01*
G01X368718Y455640D02*
X368427Y455431D01*
X368093Y455348D01*
X367760Y455431D01*
X367468Y455681D01*
X367260Y456056D01*
X367177Y456431D01*
Y456890D01*
X367260Y457265D01*
X367468Y457598D01*
X367718Y457765D01*
X368010Y457848D01*
X368343Y457765D01*
X368593Y457598D01*
X368760Y457348D01*
X368843Y457015D01*
X368760Y456723D01*
X368552Y456431D01*
X368302Y456265D01*
X368010Y456223D01*
X367677Y456306D01*
X367427Y456515D01*
X367177Y456890D01*
G01X382593Y465640D02*
X382843Y465765D01*
X383135Y465848D01*
X383468D01*
X383843Y465723D01*
X384135Y465515D01*
X384343Y465265D01*
X384510Y464848D01*
X384552Y464473D01*
X384468Y464098D01*
X384343Y463848D01*
X384093Y463598D01*
X383802Y463431D01*
X383510Y463348D01*
X383218D01*
X382927Y463431D01*
X382677Y463556D01*
X382468Y463723D01*
G01X381327D02*
X381077Y463515D01*
X380785Y463390D01*
X380410Y463348D01*
X380035Y463431D01*
X379743Y463598D01*
X379535Y463890D01*
X379493Y464223D01*
X379577Y464556D01*
X379785Y464765D01*
X380077Y464931D01*
X380368Y464973D01*
X380660Y464931D01*
X381035Y464765D01*
X380910Y465848D01*
X379785D01*
G01X377060Y464598D02*
X376227D01*
Y463848D01*
X376477Y463598D01*
X376768Y463431D01*
X377185Y463348D01*
X377602Y463431D01*
X377893Y463598D01*
X378143Y463848D01*
X378310Y464140D01*
X378393Y464473D01*
Y464765D01*
X378310Y465015D01*
X378143Y465306D01*
X377893Y465556D01*
X377643Y465723D01*
X377310Y465848D01*
X377018D01*
X376685Y465765D01*
X376435Y465598D01*
G01X374210Y463348D02*
Y465848D01*
X374710Y465348D01*
G01Y463348D02*
X373710D01*
G01X371110Y465848D02*
X371443Y465765D01*
X371693Y465556D01*
X371860Y465306D01*
X371985Y464973D01*
X372027Y464598D01*
X371985Y464223D01*
X371860Y463890D01*
X371693Y463640D01*
X371443Y463431D01*
X371110Y463348D01*
X370777Y463431D01*
X370527Y463640D01*
X370360Y463890D01*
X370235Y464223D01*
X370193Y464598D01*
X370235Y464973D01*
X370360Y465306D01*
X370527Y465556D01*
X370777Y465765D01*
X371110Y465848D01*
G01X368927Y463723D02*
X368677Y463515D01*
X368385Y463390D01*
X368010Y463348D01*
X367635Y463431D01*
X367343Y463598D01*
X367135Y463890D01*
X367093Y464223D01*
X367177Y464556D01*
X367385Y464765D01*
X367677Y464931D01*
X367968Y464973D01*
X368260Y464931D01*
X368635Y464765D01*
X368510Y465848D01*
X367385D01*
G01X382593Y453640D02*
X382843Y453765D01*
X383135Y453848D01*
X383468D01*
X383843Y453723D01*
X384135Y453515D01*
X384343Y453265D01*
X384510Y452848D01*
X384552Y452473D01*
X384468Y452098D01*
X384343Y451848D01*
X384093Y451598D01*
X383802Y451431D01*
X383510Y451348D01*
X383218D01*
X382927Y451431D01*
X382677Y451556D01*
X382468Y451723D01*
G01X380493Y451348D02*
X380410Y451890D01*
X380285Y452348D01*
X380118Y452765D01*
X379910Y453223D01*
X379577Y453848D01*
X381243D01*
G01X378393Y451348D02*
Y453848D01*
X377310Y451765D01*
X376227Y453848D01*
Y451348D01*
G01X374210D02*
Y453848D01*
X374710Y453348D01*
G01Y451348D02*
X373710D01*
G01X382593Y461640D02*
X382843Y461765D01*
X383135Y461848D01*
X383468D01*
X383843Y461723D01*
X384135Y461515D01*
X384343Y461265D01*
X384510Y460848D01*
X384552Y460473D01*
X384468Y460098D01*
X384343Y459848D01*
X384093Y459598D01*
X383802Y459431D01*
X383510Y459348D01*
X383218D01*
X382927Y459431D01*
X382677Y459556D01*
X382468Y459723D01*
G01X380493Y459348D02*
X380410Y459890D01*
X380285Y460348D01*
X380118Y460765D01*
X379910Y461223D01*
X379577Y461848D01*
X381243D01*
G01X378143D02*
Y459348D01*
X376477D01*
G01X373710D02*
Y461848D01*
X375252Y460056D01*
X373168D01*
G01X396427Y527501D02*
X396350Y528173D01*
X396235Y528741D01*
X396082Y529258D01*
X395890Y529826D01*
X395583Y530601D01*
X397117D01*
G01X393250Y527501D02*
X392982Y527553D01*
X392675Y527708D01*
X392483Y527966D01*
X392407Y528328D01*
X392483Y528689D01*
X392713Y528999D01*
X393058Y529154D01*
X393442D01*
X393672Y529258D01*
X393863Y529516D01*
X393940Y529878D01*
X393825Y530239D01*
X393557Y530498D01*
X393250Y530601D01*
X392943Y530498D01*
X392675Y530239D01*
X392560Y529878D01*
X392637Y529516D01*
X392828Y529258D01*
X393058Y529154D01*
X393442D01*
X393787Y528999D01*
X394017Y528689D01*
X394093Y528328D01*
X394017Y527966D01*
X393825Y527708D01*
X393518Y527553D01*
X393250Y527501D01*
G01X377427Y526001D02*
X377350Y526673D01*
X377235Y527241D01*
X377082Y527758D01*
X376890Y528326D01*
X376583Y529101D01*
X378117D01*
G01X374327Y526001D02*
X374250Y526673D01*
X374135Y527241D01*
X373982Y527758D01*
X373790Y528326D01*
X373483Y529101D01*
X375017D01*
G01X395578Y500084D02*
X395348Y500394D01*
X395080Y500549D01*
X394773Y500601D01*
X394390Y500498D01*
X394122Y500239D01*
X394045Y499929D01*
X394083Y499619D01*
X394237Y499361D01*
X395003Y498844D01*
X395348Y498483D01*
X395578Y497966D01*
X395655Y497501D01*
X394045D01*
G01X392478Y500084D02*
X392248Y500394D01*
X391980Y500549D01*
X391673Y500601D01*
X391290Y500498D01*
X391022Y500239D01*
X390945Y499929D01*
X390983Y499619D01*
X391137Y499361D01*
X391903Y498844D01*
X392248Y498483D01*
X392478Y497966D01*
X392555Y497501D01*
X390945D01*
G01X389378Y500084D02*
X389148Y500394D01*
X388880Y500549D01*
X388573Y500601D01*
X388190Y500498D01*
X387922Y500239D01*
X387845Y499929D01*
X387883Y499619D01*
X388037Y499361D01*
X388803Y498844D01*
X389148Y498483D01*
X389378Y497966D01*
X389455Y497501D01*
X387845D01*
G01X364328Y498550D02*
X364098Y498860D01*
X363830Y499015D01*
X363523Y499067D01*
X363140Y498964D01*
X362872Y498705D01*
X362795Y498395D01*
X362833Y498085D01*
X362987Y497827D01*
X363753Y497310D01*
X364098Y496949D01*
X364328Y496432D01*
X364405Y495967D01*
X362795D01*
G01X361228Y498550D02*
X360998Y498860D01*
X360730Y499015D01*
X360423Y499067D01*
X360040Y498964D01*
X359772Y498705D01*
X359695Y498395D01*
X359733Y498085D01*
X359887Y497827D01*
X360653Y497310D01*
X360998Y496949D01*
X361228Y496432D01*
X361305Y495967D01*
X359695D01*
G01X357400D02*
Y499067D01*
X357860Y498447D01*
G01Y495967D02*
X356940D01*
G01X386693Y493725D02*
X386943Y493850D01*
X387235Y493933D01*
X387568D01*
X387943Y493808D01*
X388235Y493600D01*
X388443Y493350D01*
X388610Y492933D01*
X388652Y492558D01*
X388568Y492183D01*
X388443Y491933D01*
X388193Y491683D01*
X387902Y491516D01*
X387610Y491433D01*
X387318D01*
X387027Y491516D01*
X386777Y491641D01*
X386568Y491808D01*
G01X384510Y491433D02*
X384218Y491475D01*
X383885Y491600D01*
X383677Y491808D01*
X383593Y492100D01*
X383677Y492391D01*
X383927Y492641D01*
X384302Y492766D01*
X384718D01*
X384968Y492850D01*
X385177Y493058D01*
X385260Y493350D01*
X385135Y493641D01*
X384843Y493850D01*
X384510Y493933D01*
X384177Y493850D01*
X383885Y493641D01*
X383760Y493350D01*
X383843Y493058D01*
X384052Y492850D01*
X384302Y492766D01*
X384718D01*
X385093Y492641D01*
X385343Y492391D01*
X385427Y492100D01*
X385343Y491808D01*
X385135Y491600D01*
X384802Y491475D01*
X384510Y491433D01*
G01X382493D02*
Y493933D01*
X381410Y491850D01*
X380327Y493933D01*
Y491433D01*
G01X378310D02*
Y493933D01*
X378810Y493433D01*
G01Y491433D02*
X377810D01*
G01X376002Y493516D02*
X375752Y493766D01*
X375460Y493891D01*
X375127Y493933D01*
X374710Y493850D01*
X374418Y493641D01*
X374335Y493391D01*
X374377Y493141D01*
X374543Y492933D01*
X375377Y492516D01*
X375752Y492225D01*
X376002Y491808D01*
X376085Y491433D01*
X374335D01*
G01X399765Y575864D02*
X399535Y576174D01*
X399267Y576329D01*
X398960Y576381D01*
X398577Y576278D01*
X398309Y576019D01*
X398232Y575709D01*
X398270Y575399D01*
X398424Y575141D01*
X399190Y574624D01*
X399535Y574263D01*
X399765Y573746D01*
X399842Y573281D01*
X398232D01*
G01X396665Y575864D02*
X396435Y576174D01*
X396167Y576329D01*
X395860Y576381D01*
X395477Y576278D01*
X395209Y576019D01*
X395132Y575709D01*
X395170Y575399D01*
X395324Y575141D01*
X396090Y574624D01*
X396435Y574263D01*
X396665Y573746D01*
X396742Y573281D01*
X395132D01*
G01X393565Y575864D02*
X393335Y576174D01*
X393067Y576329D01*
X392760Y576381D01*
X392377Y576278D01*
X392109Y576019D01*
X392032Y575709D01*
X392070Y575399D01*
X392224Y575141D01*
X392990Y574624D01*
X393335Y574263D01*
X393565Y573746D01*
X393642Y573281D01*
X392032D01*
G01X380578Y577584D02*
X380348Y577894D01*
X380080Y578049D01*
X379773Y578101D01*
X379390Y577998D01*
X379122Y577739D01*
X379045Y577429D01*
X379083Y577119D01*
X379237Y576861D01*
X380003Y576344D01*
X380348Y575983D01*
X380578Y575466D01*
X380655Y575001D01*
X379045D01*
G01X377478Y577584D02*
X377248Y577894D01*
X376980Y578049D01*
X376673Y578101D01*
X376290Y577998D01*
X376022Y577739D01*
X375945Y577429D01*
X375983Y577119D01*
X376137Y576861D01*
X376903Y576344D01*
X377248Y575983D01*
X377478Y575466D01*
X377555Y575001D01*
X375945D01*
G01X373650D02*
Y578101D01*
X374110Y577481D01*
G01Y575001D02*
X373190D01*
G01X396210Y565566D02*
X396133Y566238D01*
X396018Y566806D01*
X395865Y567323D01*
X395673Y567891D01*
X395366Y568666D01*
X396900D01*
G01X393033Y565566D02*
X392765Y565618D01*
X392458Y565773D01*
X392266Y566031D01*
X392190Y566393D01*
X392266Y566754D01*
X392496Y567064D01*
X392841Y567219D01*
X393225D01*
X393455Y567323D01*
X393646Y567581D01*
X393723Y567943D01*
X393608Y568304D01*
X393340Y568563D01*
X393033Y568666D01*
X392726Y568563D01*
X392458Y568304D01*
X392343Y567943D01*
X392420Y567581D01*
X392611Y567323D01*
X392841Y567219D01*
X393225D01*
X393570Y567064D01*
X393800Y566754D01*
X393876Y566393D01*
X393800Y566031D01*
X393608Y565773D01*
X393301Y565618D01*
X393033Y565566D01*
G01X377427Y564001D02*
X377350Y564673D01*
X377235Y565241D01*
X377082Y565758D01*
X376890Y566326D01*
X376583Y567101D01*
X378117D01*
G01X374327Y564001D02*
X374250Y564673D01*
X374135Y565241D01*
X373982Y565758D01*
X373790Y566326D01*
X373483Y567101D01*
X375017D01*
G01X400078Y538084D02*
X399848Y538394D01*
X399580Y538549D01*
X399273Y538601D01*
X398890Y538498D01*
X398622Y538239D01*
X398545Y537929D01*
X398583Y537619D01*
X398737Y537361D01*
X399503Y536844D01*
X399848Y536483D01*
X400078Y535966D01*
X400155Y535501D01*
X398545D01*
G01X396978Y538084D02*
X396748Y538394D01*
X396480Y538549D01*
X396173Y538601D01*
X395790Y538498D01*
X395522Y538239D01*
X395445Y537929D01*
X395483Y537619D01*
X395637Y537361D01*
X396403Y536844D01*
X396748Y536483D01*
X396978Y535966D01*
X397055Y535501D01*
X395445D01*
G01X393878Y538084D02*
X393648Y538394D01*
X393380Y538549D01*
X393073Y538601D01*
X392690Y538498D01*
X392422Y538239D01*
X392345Y537929D01*
X392383Y537619D01*
X392537Y537361D01*
X393303Y536844D01*
X393648Y536483D01*
X393878Y535966D01*
X393955Y535501D01*
X392345D01*
G01X381078Y539584D02*
X380848Y539894D01*
X380580Y540049D01*
X380273Y540101D01*
X379890Y539998D01*
X379622Y539739D01*
X379545Y539429D01*
X379583Y539119D01*
X379737Y538861D01*
X380503Y538344D01*
X380848Y537983D01*
X381078Y537466D01*
X381155Y537001D01*
X379545D01*
G01X377978Y539584D02*
X377748Y539894D01*
X377480Y540049D01*
X377173Y540101D01*
X376790Y539998D01*
X376522Y539739D01*
X376445Y539429D01*
X376483Y539119D01*
X376637Y538861D01*
X377403Y538344D01*
X377748Y537983D01*
X377978Y537466D01*
X378055Y537001D01*
X376445D01*
G01X374150D02*
Y540101D01*
X374610Y539481D01*
G01Y537001D02*
X373690D01*
G01X392343Y619662D02*
X392593Y619787D01*
X392885Y619870D01*
X393218D01*
X393593Y619745D01*
X393885Y619537D01*
X394093Y619287D01*
X394260Y618870D01*
X394302Y618495D01*
X394218Y618120D01*
X394093Y617870D01*
X393843Y617620D01*
X393552Y617453D01*
X393260Y617370D01*
X392968D01*
X392677Y617453D01*
X392427Y617578D01*
X392218Y617745D01*
G01X390160Y617370D02*
X389868Y617412D01*
X389535Y617537D01*
X389327Y617745D01*
X389243Y618037D01*
X389327Y618328D01*
X389577Y618578D01*
X389952Y618703D01*
X390368D01*
X390618Y618787D01*
X390827Y618995D01*
X390910Y619287D01*
X390785Y619578D01*
X390493Y619787D01*
X390160Y619870D01*
X389827Y619787D01*
X389535Y619578D01*
X389410Y619287D01*
X389493Y618995D01*
X389702Y618787D01*
X389952Y618703D01*
X390368D01*
X390743Y618578D01*
X390993Y618328D01*
X391077Y618037D01*
X390993Y617745D01*
X390785Y617537D01*
X390452Y617412D01*
X390160Y617370D01*
G01X387893Y619870D02*
Y617370D01*
X386227D01*
G01X383460D02*
Y619870D01*
X385002Y618078D01*
X382918D01*
G01X396327Y603000D02*
X396250Y603672D01*
X396135Y604240D01*
X395982Y604757D01*
X395790Y605325D01*
X395483Y606100D01*
X397017D01*
G01X393150Y603000D02*
X392882Y603052D01*
X392575Y603207D01*
X392383Y603465D01*
X392307Y603827D01*
X392383Y604188D01*
X392613Y604498D01*
X392958Y604653D01*
X393342D01*
X393572Y604757D01*
X393763Y605015D01*
X393840Y605377D01*
X393725Y605738D01*
X393457Y605997D01*
X393150Y606100D01*
X392843Y605997D01*
X392575Y605738D01*
X392460Y605377D01*
X392537Y605015D01*
X392728Y604757D01*
X392958Y604653D01*
X393342D01*
X393687Y604498D01*
X393917Y604188D01*
X393993Y603827D01*
X393917Y603465D01*
X393725Y603207D01*
X393418Y603052D01*
X393150Y603000D01*
G01X374804Y603264D02*
X374727Y603936D01*
X374612Y604504D01*
X374459Y605021D01*
X374267Y605589D01*
X373960Y606364D01*
X375494D01*
G01X371704Y603264D02*
X371627Y603936D01*
X371512Y604504D01*
X371359Y605021D01*
X371167Y605589D01*
X370860Y606364D01*
X372394D01*
G01X413104Y658950D02*
X380404D01*
Y640250D01*
X413104D01*
Y658950D01*
G01X415050Y640100D02*
X447750D01*
Y658800D01*
X415050D01*
Y640100D01*
G01X468183Y-12608D02*
X468433Y-12483D01*
X468725Y-12400D01*
X469058D01*
X469433Y-12525D01*
X469725Y-12733D01*
X469933Y-12983D01*
X470100Y-13400D01*
X470142Y-13775D01*
X470058Y-14150D01*
X469933Y-14400D01*
X469683Y-14650D01*
X469392Y-14817D01*
X469100Y-14900D01*
X468808D01*
X468517Y-14817D01*
X468267Y-14692D01*
X468058Y-14525D01*
G01X466000Y-14900D02*
X465708Y-14858D01*
X465375Y-14733D01*
X465167Y-14525D01*
X465083Y-14233D01*
X465167Y-13942D01*
X465417Y-13692D01*
X465792Y-13567D01*
X466208D01*
X466458Y-13483D01*
X466667Y-13275D01*
X466750Y-12983D01*
X466625Y-12692D01*
X466333Y-12483D01*
X466000Y-12400D01*
X465667Y-12483D01*
X465375Y-12692D01*
X465250Y-12983D01*
X465333Y-13275D01*
X465542Y-13483D01*
X465792Y-13567D01*
X466208D01*
X466583Y-13692D01*
X466833Y-13942D01*
X466917Y-14233D01*
X466833Y-14525D01*
X466625Y-14733D01*
X466292Y-14858D01*
X466000Y-14900D01*
G01X463817Y-12400D02*
Y-14192D01*
X463650Y-14567D01*
X463317Y-14817D01*
X462900Y-14900D01*
X462483Y-14817D01*
X462150Y-14567D01*
X461983Y-14192D01*
Y-12400D01*
G01X459800Y-14900D02*
Y-12400D01*
X460300Y-12900D01*
G01Y-14900D02*
X459300D01*
G01X457492Y-12817D02*
X457242Y-12567D01*
X456950Y-12442D01*
X456617Y-12400D01*
X456200Y-12483D01*
X455908Y-12692D01*
X455825Y-12942D01*
X455867Y-13192D01*
X456033Y-13400D01*
X456867Y-13817D01*
X457242Y-14108D01*
X457492Y-14525D01*
X457575Y-14900D01*
X455825D01*
G01X484183Y-12608D02*
X484433Y-12483D01*
X484725Y-12400D01*
X485058D01*
X485433Y-12525D01*
X485725Y-12733D01*
X485933Y-12983D01*
X486100Y-13400D01*
X486142Y-13775D01*
X486058Y-14150D01*
X485933Y-14400D01*
X485683Y-14650D01*
X485392Y-14817D01*
X485100Y-14900D01*
X484808D01*
X484517Y-14817D01*
X484267Y-14692D01*
X484058Y-14525D01*
G01X482000Y-14900D02*
X481708Y-14858D01*
X481375Y-14733D01*
X481167Y-14525D01*
X481083Y-14233D01*
X481167Y-13942D01*
X481417Y-13692D01*
X481792Y-13567D01*
X482208D01*
X482458Y-13483D01*
X482667Y-13275D01*
X482750Y-12983D01*
X482625Y-12692D01*
X482333Y-12483D01*
X482000Y-12400D01*
X481667Y-12483D01*
X481375Y-12692D01*
X481250Y-12983D01*
X481333Y-13275D01*
X481542Y-13483D01*
X481792Y-13567D01*
X482208D01*
X482583Y-13692D01*
X482833Y-13942D01*
X482917Y-14233D01*
X482833Y-14525D01*
X482625Y-14733D01*
X482292Y-14858D01*
X482000Y-14900D01*
G01X479817Y-12400D02*
Y-14192D01*
X479650Y-14567D01*
X479317Y-14817D01*
X478900Y-14900D01*
X478483Y-14817D01*
X478150Y-14567D01*
X477983Y-14192D01*
Y-12400D01*
G01X475800Y-14900D02*
Y-12400D01*
X476300Y-12900D01*
G01Y-14900D02*
X475300D01*
G01X472700D02*
Y-12400D01*
X473200Y-12900D01*
G01Y-14900D02*
X472200D01*
G01X452183Y-12908D02*
X452433Y-12783D01*
X452725Y-12700D01*
X453058D01*
X453433Y-12825D01*
X453725Y-13033D01*
X453933Y-13283D01*
X454100Y-13700D01*
X454142Y-14075D01*
X454058Y-14450D01*
X453933Y-14700D01*
X453683Y-14950D01*
X453392Y-15117D01*
X453100Y-15200D01*
X452808D01*
X452517Y-15117D01*
X452267Y-14992D01*
X452058Y-14825D01*
G01X450000Y-15200D02*
X449708Y-15158D01*
X449375Y-15033D01*
X449167Y-14825D01*
X449083Y-14533D01*
X449167Y-14242D01*
X449417Y-13992D01*
X449792Y-13867D01*
X450208D01*
X450458Y-13783D01*
X450667Y-13575D01*
X450750Y-13283D01*
X450625Y-12992D01*
X450333Y-12783D01*
X450000Y-12700D01*
X449667Y-12783D01*
X449375Y-12992D01*
X449250Y-13283D01*
X449333Y-13575D01*
X449542Y-13783D01*
X449792Y-13867D01*
X450208D01*
X450583Y-13992D01*
X450833Y-14242D01*
X450917Y-14533D01*
X450833Y-14825D01*
X450625Y-15033D01*
X450292Y-15158D01*
X450000Y-15200D01*
G01X447817Y-12700D02*
Y-14492D01*
X447650Y-14867D01*
X447317Y-15117D01*
X446900Y-15200D01*
X446483Y-15117D01*
X446150Y-14867D01*
X445983Y-14492D01*
Y-12700D01*
G01X443800Y-15200D02*
Y-12700D01*
X444300Y-13200D01*
G01Y-15200D02*
X443300D01*
G01X441617Y-14700D02*
X441367Y-14992D01*
X441033Y-15158D01*
X440658Y-15200D01*
X440325Y-15158D01*
X439992Y-14950D01*
X439783Y-14700D01*
X439742Y-14450D01*
X439825Y-14158D01*
X440117Y-13950D01*
X440408Y-13867D01*
X440783D01*
G01X440408D02*
X440158Y-13742D01*
X439950Y-13533D01*
X439867Y-13283D01*
X439950Y-13033D01*
X440158Y-12825D01*
X440533Y-12700D01*
X440908Y-12742D01*
X441283Y-12908D01*
G01X458733Y108359D02*
X458983Y108484D01*
X459275Y108567D01*
X459608D01*
X459983Y108442D01*
X460275Y108234D01*
X460483Y107984D01*
X460650Y107567D01*
X460692Y107192D01*
X460608Y106817D01*
X460483Y106567D01*
X460233Y106317D01*
X459942Y106150D01*
X459650Y106067D01*
X459358D01*
X459067Y106150D01*
X458817Y106275D01*
X458608Y106442D01*
G01X456633Y106067D02*
X456550Y106609D01*
X456425Y107067D01*
X456258Y107484D01*
X456050Y107942D01*
X455717Y108567D01*
X457383D01*
G01X453450D02*
Y106067D01*
G01X454408Y108567D02*
X452492D01*
G01X450350Y106067D02*
Y108567D01*
X450850Y108067D01*
G01Y106067D02*
X449850D01*
G01X430792Y135317D02*
X430917Y135067D01*
X431000Y134775D01*
Y134442D01*
X430875Y134067D01*
X430667Y133775D01*
X430417Y133567D01*
X430000Y133400D01*
X429625Y133358D01*
X429250Y133442D01*
X429000Y133567D01*
X428750Y133817D01*
X428583Y134108D01*
X428500Y134400D01*
Y134692D01*
X428583Y134983D01*
X428708Y135233D01*
X428875Y135442D01*
G01X428500Y137417D02*
X429042Y137500D01*
X429500Y137625D01*
X429917Y137792D01*
X430375Y138000D01*
X431000Y138333D01*
Y136667D01*
G01X428500Y139767D02*
X431000D01*
Y140767D01*
X430875Y141100D01*
X430583Y141350D01*
X430250Y141433D01*
X429917Y141350D01*
X429667Y141142D01*
X429542Y140767D01*
Y139767D01*
G01X428500Y143700D02*
X431000D01*
X430500Y143200D01*
G01X428500D02*
Y144200D01*
G01Y146717D02*
X429042Y146800D01*
X429500Y146925D01*
X429917Y147092D01*
X430375Y147300D01*
X431000Y147633D01*
Y145967D01*
G01X452379Y142766D02*
X452629Y142891D01*
X452921Y142974D01*
X453254D01*
X453629Y142849D01*
X453921Y142641D01*
X454129Y142391D01*
X454296Y141974D01*
X454338Y141599D01*
X454254Y141224D01*
X454129Y140974D01*
X453879Y140724D01*
X453588Y140557D01*
X453296Y140474D01*
X453004D01*
X452713Y140557D01*
X452463Y140682D01*
X452254Y140849D01*
G01X450279Y140474D02*
X450196Y141016D01*
X450071Y141474D01*
X449904Y141891D01*
X449696Y142349D01*
X449363Y142974D01*
X451029D01*
G01X447929Y140474D02*
Y142974D01*
X446929D01*
X446596Y142849D01*
X446346Y142557D01*
X446263Y142224D01*
X446346Y141891D01*
X446554Y141641D01*
X446929Y141516D01*
X447929D01*
G01X443996Y140474D02*
Y142974D01*
X444496Y142474D01*
G01Y140474D02*
X443496D01*
G01X440896D02*
X440604Y140516D01*
X440271Y140641D01*
X440063Y140849D01*
X439979Y141141D01*
X440063Y141432D01*
X440313Y141682D01*
X440688Y141807D01*
X441104D01*
X441354Y141891D01*
X441563Y142099D01*
X441646Y142391D01*
X441521Y142682D01*
X441229Y142891D01*
X440896Y142974D01*
X440563Y142891D01*
X440271Y142682D01*
X440146Y142391D01*
X440229Y142099D01*
X440438Y141891D01*
X440688Y141807D01*
X441104D01*
X441479Y141682D01*
X441729Y141432D01*
X441813Y141141D01*
X441729Y140849D01*
X441521Y140641D01*
X441188Y140516D01*
X440896Y140474D01*
G01X424792Y119217D02*
X424917Y118967D01*
X425000Y118675D01*
Y118342D01*
X424875Y117967D01*
X424667Y117675D01*
X424417Y117467D01*
X424000Y117300D01*
X423625Y117258D01*
X423250Y117342D01*
X423000Y117467D01*
X422750Y117717D01*
X422583Y118008D01*
X422500Y118300D01*
Y118592D01*
X422583Y118883D01*
X422708Y119133D01*
X422875Y119342D01*
G01X422500Y121317D02*
X423042Y121400D01*
X423500Y121525D01*
X423917Y121692D01*
X424375Y121900D01*
X425000Y122233D01*
Y120567D01*
G01X422500Y123667D02*
X425000D01*
Y124667D01*
X424875Y125000D01*
X424583Y125250D01*
X424250Y125333D01*
X423917Y125250D01*
X423667Y125042D01*
X423542Y124667D01*
Y123667D01*
G01X422500Y127600D02*
X425000D01*
X424500Y127100D01*
G01X422500D02*
Y128100D01*
G01X422792Y129992D02*
X422583Y130283D01*
X422500Y130617D01*
X422583Y130950D01*
X422833Y131242D01*
X423208Y131450D01*
X423583Y131533D01*
X424042D01*
X424417Y131450D01*
X424750Y131242D01*
X424917Y130992D01*
X425000Y130700D01*
X424917Y130367D01*
X424750Y130117D01*
X424500Y129950D01*
X424167Y129867D01*
X423875Y129950D01*
X423583Y130158D01*
X423417Y130408D01*
X423375Y130700D01*
X423458Y131033D01*
X423667Y131283D01*
X424042Y131533D01*
G01X420792Y119217D02*
X420917Y118967D01*
X421000Y118675D01*
Y118342D01*
X420875Y117967D01*
X420667Y117675D01*
X420417Y117467D01*
X420000Y117300D01*
X419625Y117258D01*
X419250Y117342D01*
X419000Y117467D01*
X418750Y117717D01*
X418583Y118008D01*
X418500Y118300D01*
Y118592D01*
X418583Y118883D01*
X418708Y119133D01*
X418875Y119342D01*
G01X418500Y121317D02*
X419042Y121400D01*
X419500Y121525D01*
X419917Y121692D01*
X420375Y121900D01*
X421000Y122233D01*
Y120567D01*
G01X418500Y123667D02*
X421000D01*
Y124667D01*
X420875Y125000D01*
X420583Y125250D01*
X420250Y125333D01*
X419917Y125250D01*
X419667Y125042D01*
X419542Y124667D01*
Y123667D01*
G01X420583Y126808D02*
X420833Y127058D01*
X420958Y127350D01*
X421000Y127683D01*
X420917Y128100D01*
X420708Y128392D01*
X420458Y128475D01*
X420208Y128433D01*
X420000Y128267D01*
X419583Y127433D01*
X419292Y127058D01*
X418875Y126808D01*
X418500Y126725D01*
Y128475D01*
G01X421000Y130700D02*
X420917Y130367D01*
X420708Y130117D01*
X420458Y129950D01*
X420125Y129825D01*
X419750Y129783D01*
X419375Y129825D01*
X419042Y129950D01*
X418792Y130117D01*
X418583Y130367D01*
X418500Y130700D01*
X418583Y131033D01*
X418792Y131283D01*
X419042Y131450D01*
X419375Y131575D01*
X419750Y131617D01*
X420125Y131575D01*
X420458Y131450D01*
X420708Y131283D01*
X420917Y131033D01*
X421000Y130700D01*
G01X427092Y152617D02*
X427217Y152367D01*
X427300Y152075D01*
Y151742D01*
X427175Y151367D01*
X426967Y151075D01*
X426717Y150867D01*
X426300Y150700D01*
X425925Y150658D01*
X425550Y150742D01*
X425300Y150867D01*
X425050Y151117D01*
X424883Y151408D01*
X424800Y151700D01*
Y151992D01*
X424883Y152283D01*
X425008Y152533D01*
X425175Y152742D01*
G01X424800Y154717D02*
X425342Y154800D01*
X425800Y154925D01*
X426217Y155092D01*
X426675Y155300D01*
X427300Y155633D01*
Y153967D01*
G01X424800Y157067D02*
X427300D01*
Y158067D01*
X427175Y158400D01*
X426883Y158650D01*
X426550Y158733D01*
X426217Y158650D01*
X425967Y158442D01*
X425842Y158067D01*
Y157067D01*
G01X424800Y161000D02*
X424842Y161292D01*
X424967Y161625D01*
X425175Y161833D01*
X425467Y161917D01*
X425758Y161833D01*
X426008Y161583D01*
X426133Y161208D01*
Y160792D01*
X426217Y160542D01*
X426425Y160333D01*
X426717Y160250D01*
X427008Y160375D01*
X427217Y160667D01*
X427300Y161000D01*
X427217Y161333D01*
X427008Y161625D01*
X426717Y161750D01*
X426425Y161667D01*
X426217Y161458D01*
X426133Y161208D01*
Y160792D01*
X426008Y160417D01*
X425758Y160167D01*
X425467Y160083D01*
X425175Y160167D01*
X424967Y160375D01*
X424842Y160708D01*
X424800Y161000D01*
G01X423092Y152617D02*
X423217Y152367D01*
X423300Y152075D01*
Y151742D01*
X423175Y151367D01*
X422967Y151075D01*
X422717Y150867D01*
X422300Y150700D01*
X421925Y150658D01*
X421550Y150742D01*
X421300Y150867D01*
X421050Y151117D01*
X420883Y151408D01*
X420800Y151700D01*
Y151992D01*
X420883Y152283D01*
X421008Y152533D01*
X421175Y152742D01*
G01X420800Y154717D02*
X421342Y154800D01*
X421800Y154925D01*
X422217Y155092D01*
X422675Y155300D01*
X423300Y155633D01*
Y153967D01*
G01X420800Y157067D02*
X423300D01*
Y158067D01*
X423175Y158400D01*
X422883Y158650D01*
X422550Y158733D01*
X422217Y158650D01*
X421967Y158442D01*
X421842Y158067D01*
Y157067D01*
G01X421092Y160292D02*
X420883Y160583D01*
X420800Y160917D01*
X420883Y161250D01*
X421133Y161542D01*
X421508Y161750D01*
X421883Y161833D01*
X422342D01*
X422717Y161750D01*
X423050Y161542D01*
X423217Y161292D01*
X423300Y161000D01*
X423217Y160667D01*
X423050Y160417D01*
X422800Y160250D01*
X422467Y160167D01*
X422175Y160250D01*
X421883Y160458D01*
X421717Y160708D01*
X421675Y161000D01*
X421758Y161333D01*
X421967Y161583D01*
X422342Y161833D01*
G01X431092Y152617D02*
X431217Y152367D01*
X431300Y152075D01*
Y151742D01*
X431175Y151367D01*
X430967Y151075D01*
X430717Y150867D01*
X430300Y150700D01*
X429925Y150658D01*
X429550Y150742D01*
X429300Y150867D01*
X429050Y151117D01*
X428883Y151408D01*
X428800Y151700D01*
Y151992D01*
X428883Y152283D01*
X429008Y152533D01*
X429175Y152742D01*
G01X428800Y154717D02*
X429342Y154800D01*
X429800Y154925D01*
X430217Y155092D01*
X430675Y155300D01*
X431300Y155633D01*
Y153967D01*
G01X428800Y157067D02*
X431300D01*
Y158067D01*
X431175Y158400D01*
X430883Y158650D01*
X430550Y158733D01*
X430217Y158650D01*
X429967Y158442D01*
X429842Y158067D01*
Y157067D01*
G01X428800Y161000D02*
X431300D01*
X430800Y160500D01*
G01X428800D02*
Y161500D01*
G01Y164100D02*
X431300D01*
X430800Y163600D01*
G01X428800D02*
Y164600D01*
G01X426792Y135317D02*
X426917Y135067D01*
X427000Y134775D01*
Y134442D01*
X426875Y134067D01*
X426667Y133775D01*
X426417Y133567D01*
X426000Y133400D01*
X425625Y133358D01*
X425250Y133442D01*
X425000Y133567D01*
X424750Y133817D01*
X424583Y134108D01*
X424500Y134400D01*
Y134692D01*
X424583Y134983D01*
X424708Y135233D01*
X424875Y135442D01*
G01X424500Y137417D02*
X425042Y137500D01*
X425500Y137625D01*
X425917Y137792D01*
X426375Y138000D01*
X427000Y138333D01*
Y136667D01*
G01X424500Y139767D02*
X427000D01*
Y140767D01*
X426875Y141100D01*
X426583Y141350D01*
X426250Y141433D01*
X425917Y141350D01*
X425667Y141142D01*
X425542Y140767D01*
Y139767D01*
G01X424500Y143700D02*
X427000D01*
X426500Y143200D01*
G01X424500D02*
Y144200D01*
G01X425000Y145883D02*
X424708Y146133D01*
X424542Y146467D01*
X424500Y146842D01*
X424542Y147175D01*
X424750Y147508D01*
X425000Y147717D01*
X425250Y147758D01*
X425542Y147675D01*
X425750Y147383D01*
X425833Y147092D01*
Y146717D01*
G01Y147092D02*
X425958Y147342D01*
X426167Y147550D01*
X426417Y147633D01*
X426667Y147550D01*
X426875Y147342D01*
X427000Y146967D01*
X426958Y146592D01*
X426792Y146217D01*
G01X422792Y135317D02*
X422917Y135067D01*
X423000Y134775D01*
Y134442D01*
X422875Y134067D01*
X422667Y133775D01*
X422417Y133567D01*
X422000Y133400D01*
X421625Y133358D01*
X421250Y133442D01*
X421000Y133567D01*
X420750Y133817D01*
X420583Y134108D01*
X420500Y134400D01*
Y134692D01*
X420583Y134983D01*
X420708Y135233D01*
X420875Y135442D01*
G01X420500Y137417D02*
X421042Y137500D01*
X421500Y137625D01*
X421917Y137792D01*
X422375Y138000D01*
X423000Y138333D01*
Y136667D01*
G01X420500Y139767D02*
X423000D01*
Y140767D01*
X422875Y141100D01*
X422583Y141350D01*
X422250Y141433D01*
X421917Y141350D01*
X421667Y141142D01*
X421542Y140767D01*
Y139767D01*
G01X420500Y143700D02*
X423000D01*
X422500Y143200D01*
G01X420500D02*
Y144200D01*
G01Y147300D02*
X423000D01*
X421208Y145758D01*
Y147842D01*
G01X455781Y144533D02*
Y147033D01*
X454740D01*
X454406Y146908D01*
X454198Y146741D01*
X454115Y146408D01*
X454198Y146075D01*
X454448Y145866D01*
X454740Y145741D01*
X455781D01*
G01X454740D02*
X454115Y144533D01*
G01X451931D02*
X451848Y145075D01*
X451723Y145533D01*
X451556Y145950D01*
X451348Y146408D01*
X451015Y147033D01*
X452681D01*
G01X449581Y144533D02*
Y147033D01*
X448581D01*
X448248Y146908D01*
X447998Y146616D01*
X447915Y146283D01*
X447998Y145950D01*
X448206Y145700D01*
X448581Y145575D01*
X449581D01*
G01X446440Y146616D02*
X446190Y146866D01*
X445898Y146991D01*
X445565Y147033D01*
X445148Y146950D01*
X444856Y146741D01*
X444773Y146491D01*
X444815Y146241D01*
X444981Y146033D01*
X445815Y145616D01*
X446190Y145325D01*
X446440Y144908D01*
X446523Y144533D01*
X444773D01*
G01X442548D02*
Y147033D01*
X443048Y146533D01*
G01Y144533D02*
X442048D01*
G01X455331Y150333D02*
Y152833D01*
X454290D01*
X453956Y152708D01*
X453748Y152541D01*
X453665Y152208D01*
X453748Y151875D01*
X453998Y151666D01*
X454290Y151541D01*
X455331D01*
G01X454290D02*
X453665Y150333D01*
G01X451481D02*
X451398Y150875D01*
X451273Y151333D01*
X451106Y151750D01*
X450898Y152208D01*
X450565Y152833D01*
X452231D01*
G01X449131Y150333D02*
Y152833D01*
X448131D01*
X447798Y152708D01*
X447548Y152416D01*
X447465Y152083D01*
X447548Y151750D01*
X447756Y151500D01*
X448131Y151375D01*
X449131D01*
G01X445198Y150333D02*
Y152833D01*
X445698Y152333D01*
G01Y150333D02*
X444698D01*
G01X442806Y150625D02*
X442515Y150416D01*
X442181Y150333D01*
X441848Y150416D01*
X441556Y150666D01*
X441348Y151041D01*
X441265Y151416D01*
Y151875D01*
X441348Y152250D01*
X441556Y152583D01*
X441806Y152750D01*
X442098Y152833D01*
X442431Y152750D01*
X442681Y152583D01*
X442848Y152333D01*
X442931Y152000D01*
X442848Y151708D01*
X442640Y151416D01*
X442390Y151250D01*
X442098Y151208D01*
X441765Y151291D01*
X441515Y151500D01*
X441265Y151875D01*
G01X455331Y154333D02*
Y156833D01*
X454290D01*
X453956Y156708D01*
X453748Y156541D01*
X453665Y156208D01*
X453748Y155875D01*
X453998Y155666D01*
X454290Y155541D01*
X455331D01*
G01X454290D02*
X453665Y154333D01*
G01X451481D02*
X451398Y154875D01*
X451273Y155333D01*
X451106Y155750D01*
X450898Y156208D01*
X450565Y156833D01*
X452231D01*
G01X449131Y154333D02*
Y156833D01*
X448131D01*
X447798Y156708D01*
X447548Y156416D01*
X447465Y156083D01*
X447548Y155750D01*
X447756Y155500D01*
X448131Y155375D01*
X449131D01*
G01X445198Y154333D02*
Y156833D01*
X445698Y156333D01*
G01Y154333D02*
X444698D01*
G01X442181D02*
X442098Y154875D01*
X441973Y155333D01*
X441806Y155750D01*
X441598Y156208D01*
X441265Y156833D01*
X442931D01*
G01X452015Y136624D02*
Y139124D01*
X450974D01*
X450640Y138999D01*
X450432Y138832D01*
X450349Y138499D01*
X450432Y138166D01*
X450682Y137957D01*
X450974Y137832D01*
X452015D01*
G01X450974D02*
X450349Y136624D01*
G01X448165D02*
X448082Y137166D01*
X447957Y137624D01*
X447790Y138041D01*
X447582Y138499D01*
X447249Y139124D01*
X448915D01*
G01X445815Y136624D02*
Y139124D01*
X444815D01*
X444482Y138999D01*
X444232Y138707D01*
X444149Y138374D01*
X444232Y138041D01*
X444440Y137791D01*
X444815Y137666D01*
X445815D01*
G01X442674Y138707D02*
X442424Y138957D01*
X442132Y139082D01*
X441799Y139124D01*
X441382Y139041D01*
X441090Y138832D01*
X441007Y138582D01*
X441049Y138332D01*
X441215Y138124D01*
X442049Y137707D01*
X442424Y137416D01*
X442674Y136999D01*
X442757Y136624D01*
X441007D01*
G01X439574Y138707D02*
X439324Y138957D01*
X439032Y139082D01*
X438699Y139124D01*
X438282Y139041D01*
X437990Y138832D01*
X437907Y138582D01*
X437949Y138332D01*
X438115Y138124D01*
X438949Y137707D01*
X439324Y137416D01*
X439574Y136999D01*
X439657Y136624D01*
X437907D01*
G01X442470Y120739D02*
X444970D01*
Y121780D01*
X444845Y122114D01*
X444678Y122322D01*
X444345Y122405D01*
X444012Y122322D01*
X443803Y122072D01*
X443678Y121780D01*
Y120739D01*
G01Y121780D02*
X442470Y122405D01*
G01Y124589D02*
X443012Y124672D01*
X443470Y124797D01*
X443887Y124964D01*
X444345Y125172D01*
X444970Y125505D01*
Y123839D01*
G01Y126855D02*
X443178D01*
X442803Y127022D01*
X442553Y127355D01*
X442470Y127772D01*
X442553Y128189D01*
X442803Y128522D01*
X443178Y128689D01*
X444970D01*
G01X444553Y130080D02*
X444803Y130330D01*
X444928Y130622D01*
X444970Y130955D01*
X444887Y131372D01*
X444678Y131664D01*
X444428Y131747D01*
X444178Y131705D01*
X443970Y131539D01*
X443553Y130705D01*
X443262Y130330D01*
X442845Y130080D01*
X442470Y129997D01*
Y131747D01*
G01X435092Y152617D02*
X435217Y152367D01*
X435300Y152075D01*
Y151742D01*
X435175Y151367D01*
X434967Y151075D01*
X434717Y150867D01*
X434300Y150700D01*
X433925Y150658D01*
X433550Y150742D01*
X433300Y150867D01*
X433050Y151117D01*
X432883Y151408D01*
X432800Y151700D01*
Y151992D01*
X432883Y152283D01*
X433008Y152533D01*
X433175Y152742D01*
G01X432800Y154717D02*
X433342Y154800D01*
X433800Y154925D01*
X434217Y155092D01*
X434675Y155300D01*
X435300Y155633D01*
Y153967D01*
G01X432800Y157067D02*
X435300D01*
Y158067D01*
X435175Y158400D01*
X434883Y158650D01*
X434550Y158733D01*
X434217Y158650D01*
X433967Y158442D01*
X433842Y158067D01*
Y157067D01*
G01X432800Y161000D02*
X435300D01*
X434800Y160500D01*
G01X432800D02*
Y161500D01*
G01X434883Y163308D02*
X435133Y163558D01*
X435258Y163850D01*
X435300Y164183D01*
X435217Y164600D01*
X435008Y164892D01*
X434758Y164975D01*
X434508Y164933D01*
X434300Y164767D01*
X433883Y163933D01*
X433592Y163558D01*
X433175Y163308D01*
X432800Y163225D01*
Y164975D01*
G01X434792Y135317D02*
X434917Y135067D01*
X435000Y134775D01*
Y134442D01*
X434875Y134067D01*
X434667Y133775D01*
X434417Y133567D01*
X434000Y133400D01*
X433625Y133358D01*
X433250Y133442D01*
X433000Y133567D01*
X432750Y133817D01*
X432583Y134108D01*
X432500Y134400D01*
Y134692D01*
X432583Y134983D01*
X432708Y135233D01*
X432875Y135442D01*
G01X432500Y137417D02*
X433042Y137500D01*
X433500Y137625D01*
X433917Y137792D01*
X434375Y138000D01*
X435000Y138333D01*
Y136667D01*
G01X432500Y139767D02*
X435000D01*
Y140767D01*
X434875Y141100D01*
X434583Y141350D01*
X434250Y141433D01*
X433917Y141350D01*
X433667Y141142D01*
X433542Y140767D01*
Y139767D01*
G01X432500Y143700D02*
X435000D01*
X434500Y143200D01*
G01X432500D02*
Y144200D01*
G01X433542Y146008D02*
X433833Y146300D01*
X434000Y146550D01*
X434083Y146883D01*
X434000Y147175D01*
X433833Y147383D01*
X433583Y147550D01*
X433292Y147592D01*
X433042Y147550D01*
X432792Y147383D01*
X432583Y147133D01*
X432500Y146842D01*
X432583Y146508D01*
X432833Y146217D01*
X433208Y146050D01*
X433625Y146008D01*
X434167Y146092D01*
X434458Y146217D01*
X434750Y146425D01*
X434958Y146717D01*
X435000Y147008D01*
X434917Y147300D01*
X434708Y147508D01*
G01X459533Y113758D02*
X459783Y113883D01*
X460075Y113966D01*
X460408D01*
X460783Y113841D01*
X461075Y113633D01*
X461283Y113383D01*
X461450Y112966D01*
X461492Y112591D01*
X461408Y112216D01*
X461283Y111966D01*
X461033Y111716D01*
X460742Y111549D01*
X460450Y111466D01*
X460158D01*
X459867Y111549D01*
X459617Y111674D01*
X459408Y111841D01*
G01X457350Y111466D02*
X457058Y111508D01*
X456725Y111633D01*
X456517Y111841D01*
X456433Y112133D01*
X456517Y112424D01*
X456767Y112674D01*
X457142Y112799D01*
X457558D01*
X457808Y112883D01*
X458017Y113091D01*
X458100Y113383D01*
X457975Y113674D01*
X457683Y113883D01*
X457350Y113966D01*
X457017Y113883D01*
X456725Y113674D01*
X456600Y113383D01*
X456683Y113091D01*
X456892Y112883D01*
X457142Y112799D01*
X457558D01*
X457933Y112674D01*
X458183Y112424D01*
X458267Y112133D01*
X458183Y111841D01*
X457975Y111633D01*
X457642Y111508D01*
X457350Y111466D01*
G01X454250Y113966D02*
Y111466D01*
G01X455208Y113966D02*
X453292D01*
G01X450650Y111466D02*
Y113966D01*
X452192Y112174D01*
X450108D01*
G01X437827Y120095D02*
X437619Y120428D01*
X437494Y120803D01*
Y121137D01*
X437619Y121470D01*
X437827Y121720D01*
X438119Y121845D01*
X438411Y121762D01*
X438661Y121553D01*
X438827Y121178D01*
X438911Y120678D01*
X439077Y120387D01*
X439369Y120262D01*
X439661Y120345D01*
X439869Y120553D01*
X439994Y120845D01*
Y121137D01*
X439911Y121428D01*
X439702Y121678D01*
G01X437494Y123195D02*
X439994D01*
G01Y124945D02*
X437494D01*
G01X438744D02*
Y123195D01*
G01X437494Y127087D02*
X438036Y127170D01*
X438494Y127295D01*
X438911Y127462D01*
X439369Y127670D01*
X439994Y128003D01*
Y126337D01*
G01Y129353D02*
X438202D01*
X437827Y129520D01*
X437577Y129853D01*
X437494Y130270D01*
X437577Y130687D01*
X437827Y131020D01*
X438202Y131187D01*
X439994D01*
G01X437494Y133370D02*
X439994D01*
X439494Y132870D01*
G01X437494D02*
Y133870D01*
G01X448846Y120332D02*
X448638Y120665D01*
X448513Y121040D01*
Y121374D01*
X448638Y121707D01*
X448846Y121957D01*
X449138Y122082D01*
X449430Y121999D01*
X449680Y121790D01*
X449846Y121415D01*
X449930Y120915D01*
X450096Y120624D01*
X450388Y120499D01*
X450680Y120582D01*
X450888Y120790D01*
X451013Y121082D01*
Y121374D01*
X450930Y121665D01*
X450721Y121915D01*
G01X448513Y123432D02*
X451013D01*
G01Y125182D02*
X448513D01*
G01X449763D02*
Y123432D01*
G01X448513Y127324D02*
X449055Y127407D01*
X449513Y127532D01*
X449930Y127699D01*
X450388Y127907D01*
X451013Y128240D01*
Y126574D01*
G01Y129590D02*
X449221D01*
X448846Y129757D01*
X448596Y130090D01*
X448513Y130507D01*
X448596Y130924D01*
X448846Y131257D01*
X449221Y131424D01*
X451013D01*
G01X450596Y132815D02*
X450846Y133065D01*
X450971Y133357D01*
X451013Y133690D01*
X450930Y134107D01*
X450721Y134399D01*
X450471Y134482D01*
X450221Y134440D01*
X450013Y134274D01*
X449596Y133440D01*
X449305Y133065D01*
X448888Y132815D01*
X448513Y132732D01*
Y134482D01*
G01X421292Y185467D02*
X421417Y185217D01*
X421500Y184925D01*
Y184592D01*
X421375Y184217D01*
X421167Y183925D01*
X420917Y183717D01*
X420500Y183550D01*
X420125Y183508D01*
X419750Y183592D01*
X419500Y183717D01*
X419250Y183967D01*
X419083Y184258D01*
X419000Y184550D01*
Y184842D01*
X419083Y185133D01*
X419208Y185383D01*
X419375Y185592D01*
G01X419000Y187567D02*
X419542Y187650D01*
X420000Y187775D01*
X420417Y187942D01*
X420875Y188150D01*
X421500Y188483D01*
Y186817D01*
G01X419000Y189917D02*
X421500D01*
Y190917D01*
X421375Y191250D01*
X421083Y191500D01*
X420750Y191583D01*
X420417Y191500D01*
X420167Y191292D01*
X420042Y190917D01*
Y189917D01*
G01X421083Y193058D02*
X421333Y193308D01*
X421458Y193600D01*
X421500Y193933D01*
X421417Y194350D01*
X421208Y194642D01*
X420958Y194725D01*
X420708Y194683D01*
X420500Y194517D01*
X420083Y193683D01*
X419792Y193308D01*
X419375Y193058D01*
X419000Y192975D01*
Y194725D01*
G01X425292Y185467D02*
X425417Y185217D01*
X425500Y184925D01*
Y184592D01*
X425375Y184217D01*
X425167Y183925D01*
X424917Y183717D01*
X424500Y183550D01*
X424125Y183508D01*
X423750Y183592D01*
X423500Y183717D01*
X423250Y183967D01*
X423083Y184258D01*
X423000Y184550D01*
Y184842D01*
X423083Y185133D01*
X423208Y185383D01*
X423375Y185592D01*
G01X423000Y187567D02*
X423542Y187650D01*
X424000Y187775D01*
X424417Y187942D01*
X424875Y188150D01*
X425500Y188483D01*
Y186817D01*
G01X423000Y189917D02*
X425500D01*
Y190917D01*
X425375Y191250D01*
X425083Y191500D01*
X424750Y191583D01*
X424417Y191500D01*
X424167Y191292D01*
X424042Y190917D01*
Y189917D01*
G01X423000Y193850D02*
X425500D01*
X425000Y193350D01*
G01X423000D02*
Y194350D01*
G01X435192Y169767D02*
X435317Y169517D01*
X435400Y169225D01*
Y168892D01*
X435275Y168517D01*
X435067Y168225D01*
X434817Y168017D01*
X434400Y167850D01*
X434025Y167808D01*
X433650Y167892D01*
X433400Y168017D01*
X433150Y168267D01*
X432983Y168558D01*
X432900Y168850D01*
Y169142D01*
X432983Y169433D01*
X433108Y169683D01*
X433275Y169892D01*
G01X432900Y171867D02*
X433442Y171950D01*
X433900Y172075D01*
X434317Y172242D01*
X434775Y172450D01*
X435400Y172783D01*
Y171117D01*
G01X432900Y174217D02*
X435400D01*
Y175217D01*
X435275Y175550D01*
X434983Y175800D01*
X434650Y175883D01*
X434317Y175800D01*
X434067Y175592D01*
X433942Y175217D01*
Y174217D01*
G01X433400Y177233D02*
X433108Y177483D01*
X432942Y177817D01*
X432900Y178192D01*
X432942Y178525D01*
X433150Y178858D01*
X433400Y179067D01*
X433650Y179108D01*
X433942Y179025D01*
X434150Y178733D01*
X434233Y178442D01*
Y178067D01*
G01Y178442D02*
X434358Y178692D01*
X434567Y178900D01*
X434817Y178983D01*
X435067Y178900D01*
X435275Y178692D01*
X435400Y178317D01*
X435358Y177942D01*
X435192Y177567D01*
G01X427192Y169648D02*
X427317Y169398D01*
X427400Y169106D01*
Y168773D01*
X427275Y168398D01*
X427067Y168106D01*
X426817Y167898D01*
X426400Y167731D01*
X426025Y167689D01*
X425650Y167773D01*
X425400Y167898D01*
X425150Y168148D01*
X424983Y168439D01*
X424900Y168731D01*
Y169023D01*
X424983Y169314D01*
X425108Y169564D01*
X425275Y169773D01*
G01X424900Y171748D02*
X425442Y171831D01*
X425900Y171956D01*
X426317Y172123D01*
X426775Y172331D01*
X427400Y172664D01*
Y170998D01*
G01X424900Y174098D02*
X427400D01*
Y175098D01*
X427275Y175431D01*
X426983Y175681D01*
X426650Y175764D01*
X426317Y175681D01*
X426067Y175473D01*
X425942Y175098D01*
Y174098D01*
G01X425275Y177114D02*
X425067Y177364D01*
X424942Y177656D01*
X424900Y178031D01*
X424983Y178406D01*
X425150Y178698D01*
X425442Y178906D01*
X425775Y178948D01*
X426108Y178864D01*
X426317Y178656D01*
X426483Y178364D01*
X426525Y178073D01*
X426483Y177781D01*
X426317Y177406D01*
X427400Y177531D01*
Y178656D01*
G01X423192Y169767D02*
X423317Y169517D01*
X423400Y169225D01*
Y168892D01*
X423275Y168517D01*
X423067Y168225D01*
X422817Y168017D01*
X422400Y167850D01*
X422025Y167808D01*
X421650Y167892D01*
X421400Y168017D01*
X421150Y168267D01*
X420983Y168558D01*
X420900Y168850D01*
Y169142D01*
X420983Y169433D01*
X421108Y169683D01*
X421275Y169892D01*
G01X420900Y171867D02*
X421442Y171950D01*
X421900Y172075D01*
X422317Y172242D01*
X422775Y172450D01*
X423400Y172783D01*
Y171117D01*
G01X420900Y174217D02*
X423400D01*
Y175217D01*
X423275Y175550D01*
X422983Y175800D01*
X422650Y175883D01*
X422317Y175800D01*
X422067Y175592D01*
X421942Y175217D01*
Y174217D01*
G01Y177358D02*
X422233Y177650D01*
X422400Y177900D01*
X422483Y178233D01*
X422400Y178525D01*
X422233Y178733D01*
X421983Y178900D01*
X421692Y178942D01*
X421442Y178900D01*
X421192Y178733D01*
X420983Y178483D01*
X420900Y178192D01*
X420983Y177858D01*
X421233Y177567D01*
X421608Y177400D01*
X422025Y177358D01*
X422567Y177442D01*
X422858Y177567D01*
X423150Y177775D01*
X423358Y178067D01*
X423400Y178358D01*
X423317Y178650D01*
X423108Y178858D01*
G01X431192Y169767D02*
X431317Y169517D01*
X431400Y169225D01*
Y168892D01*
X431275Y168517D01*
X431067Y168225D01*
X430817Y168017D01*
X430400Y167850D01*
X430025Y167808D01*
X429650Y167892D01*
X429400Y168017D01*
X429150Y168267D01*
X428983Y168558D01*
X428900Y168850D01*
Y169142D01*
X428983Y169433D01*
X429108Y169683D01*
X429275Y169892D01*
G01X428900Y171867D02*
X429442Y171950D01*
X429900Y172075D01*
X430317Y172242D01*
X430775Y172450D01*
X431400Y172783D01*
Y171117D01*
G01X428900Y174217D02*
X431400D01*
Y175217D01*
X431275Y175550D01*
X430983Y175800D01*
X430650Y175883D01*
X430317Y175800D01*
X430067Y175592D01*
X429942Y175217D01*
Y174217D01*
G01X428900Y178650D02*
X431400D01*
X429608Y177108D01*
Y179192D01*
G01X430852Y185358D02*
X430977Y185108D01*
X431060Y184816D01*
Y184483D01*
X430935Y184108D01*
X430727Y183816D01*
X430477Y183608D01*
X430060Y183441D01*
X429685Y183399D01*
X429310Y183483D01*
X429060Y183608D01*
X428810Y183858D01*
X428643Y184149D01*
X428560Y184441D01*
Y184733D01*
X428643Y185024D01*
X428768Y185274D01*
X428935Y185483D01*
G01X428560Y187541D02*
X428602Y187833D01*
X428727Y188166D01*
X428935Y188374D01*
X429227Y188458D01*
X429518Y188374D01*
X429768Y188124D01*
X429893Y187749D01*
Y187333D01*
X429977Y187083D01*
X430185Y186874D01*
X430477Y186791D01*
X430768Y186916D01*
X430977Y187208D01*
X431060Y187541D01*
X430977Y187874D01*
X430768Y188166D01*
X430477Y188291D01*
X430185Y188208D01*
X429977Y187999D01*
X429893Y187749D01*
Y187333D01*
X429768Y186958D01*
X429518Y186708D01*
X429227Y186624D01*
X428935Y186708D01*
X428727Y186916D01*
X428602Y187249D01*
X428560Y187541D01*
G01X431060Y189391D02*
X428560Y189974D01*
X431060Y190641D01*
X428560Y191308D01*
X431060Y191891D01*
G01X428560Y194241D02*
X431060D01*
X429268Y192699D01*
Y194783D01*
G01X455331Y170333D02*
Y172833D01*
X454290D01*
X453956Y172708D01*
X453748Y172541D01*
X453665Y172208D01*
X453748Y171875D01*
X453998Y171666D01*
X454290Y171541D01*
X455331D01*
G01X454290D02*
X453665Y170333D01*
G01X451481D02*
X451398Y170875D01*
X451273Y171333D01*
X451106Y171750D01*
X450898Y172208D01*
X450565Y172833D01*
X452231D01*
G01X449131Y170333D02*
Y172833D01*
X448131D01*
X447798Y172708D01*
X447548Y172416D01*
X447465Y172083D01*
X447548Y171750D01*
X447756Y171500D01*
X448131Y171375D01*
X449131D01*
G01X445198Y170333D02*
Y172833D01*
X445698Y172333D01*
G01Y170333D02*
X444698D01*
G01X443015Y170833D02*
X442765Y170541D01*
X442431Y170375D01*
X442056Y170333D01*
X441723Y170375D01*
X441390Y170583D01*
X441181Y170833D01*
X441140Y171083D01*
X441223Y171375D01*
X441515Y171583D01*
X441806Y171666D01*
X442181D01*
G01X441806D02*
X441556Y171791D01*
X441348Y172000D01*
X441265Y172250D01*
X441348Y172500D01*
X441556Y172708D01*
X441931Y172833D01*
X442306Y172791D01*
X442681Y172625D01*
G01X455331Y162333D02*
Y164833D01*
X454290D01*
X453956Y164708D01*
X453748Y164541D01*
X453665Y164208D01*
X453748Y163875D01*
X453998Y163666D01*
X454290Y163541D01*
X455331D01*
G01X454290D02*
X453665Y162333D01*
G01X451481D02*
X451398Y162875D01*
X451273Y163333D01*
X451106Y163750D01*
X450898Y164208D01*
X450565Y164833D01*
X452231D01*
G01X449131Y162333D02*
Y164833D01*
X448131D01*
X447798Y164708D01*
X447548Y164416D01*
X447465Y164083D01*
X447548Y163750D01*
X447756Y163500D01*
X448131Y163375D01*
X449131D01*
G01X445198Y162333D02*
Y164833D01*
X445698Y164333D01*
G01Y162333D02*
X444698D01*
G01X443015Y162708D02*
X442765Y162500D01*
X442473Y162375D01*
X442098Y162333D01*
X441723Y162416D01*
X441431Y162583D01*
X441223Y162875D01*
X441181Y163208D01*
X441265Y163541D01*
X441473Y163750D01*
X441765Y163916D01*
X442056Y163958D01*
X442348Y163916D01*
X442723Y163750D01*
X442598Y164833D01*
X441473D01*
G01X455331Y178333D02*
Y180833D01*
X454290D01*
X453956Y180708D01*
X453748Y180541D01*
X453665Y180208D01*
X453748Y179875D01*
X453998Y179666D01*
X454290Y179541D01*
X455331D01*
G01X454290D02*
X453665Y178333D01*
G01X451481D02*
X451398Y178875D01*
X451273Y179333D01*
X451106Y179750D01*
X450898Y180208D01*
X450565Y180833D01*
X452231D01*
G01X449131Y178333D02*
Y180833D01*
X448131D01*
X447798Y180708D01*
X447548Y180416D01*
X447465Y180083D01*
X447548Y179750D01*
X447756Y179500D01*
X448131Y179375D01*
X449131D01*
G01X445198Y178333D02*
Y180833D01*
X445698Y180333D01*
G01Y178333D02*
X444698D01*
G01X442098Y180833D02*
X442431Y180750D01*
X442681Y180541D01*
X442848Y180291D01*
X442973Y179958D01*
X443015Y179583D01*
X442973Y179208D01*
X442848Y178875D01*
X442681Y178625D01*
X442431Y178416D01*
X442098Y178333D01*
X441765Y178416D01*
X441515Y178625D01*
X441348Y178875D01*
X441223Y179208D01*
X441181Y179583D01*
X441223Y179958D01*
X441348Y180291D01*
X441515Y180541D01*
X441765Y180750D01*
X442098Y180833D01*
G01X455331Y174333D02*
Y176833D01*
X454290D01*
X453956Y176708D01*
X453748Y176541D01*
X453665Y176208D01*
X453748Y175875D01*
X453998Y175666D01*
X454290Y175541D01*
X455331D01*
G01X454290D02*
X453665Y174333D01*
G01X451481D02*
X451398Y174875D01*
X451273Y175333D01*
X451106Y175750D01*
X450898Y176208D01*
X450565Y176833D01*
X452231D01*
G01X449131Y174333D02*
Y176833D01*
X448131D01*
X447798Y176708D01*
X447548Y176416D01*
X447465Y176083D01*
X447548Y175750D01*
X447756Y175500D01*
X448131Y175375D01*
X449131D01*
G01X445198Y174333D02*
Y176833D01*
X445698Y176333D01*
G01Y174333D02*
X444698D01*
G01X442098D02*
Y176833D01*
X442598Y176333D01*
G01Y174333D02*
X441598D01*
G01X455331Y182333D02*
Y184833D01*
X454290D01*
X453956Y184708D01*
X453748Y184541D01*
X453665Y184208D01*
X453748Y183875D01*
X453998Y183666D01*
X454290Y183541D01*
X455331D01*
G01X454290D02*
X453665Y182333D01*
G01X451481D02*
X451398Y182875D01*
X451273Y183333D01*
X451106Y183750D01*
X450898Y184208D01*
X450565Y184833D01*
X452231D01*
G01X449131Y182333D02*
Y184833D01*
X448131D01*
X447798Y184708D01*
X447548Y184416D01*
X447465Y184083D01*
X447548Y183750D01*
X447756Y183500D01*
X448131Y183375D01*
X449131D01*
G01X445198Y182333D02*
X444906Y182375D01*
X444573Y182500D01*
X444365Y182708D01*
X444281Y183000D01*
X444365Y183291D01*
X444615Y183541D01*
X444990Y183666D01*
X445406D01*
X445656Y183750D01*
X445865Y183958D01*
X445948Y184250D01*
X445823Y184541D01*
X445531Y184750D01*
X445198Y184833D01*
X444865Y184750D01*
X444573Y184541D01*
X444448Y184250D01*
X444531Y183958D01*
X444740Y183750D01*
X444990Y183666D01*
X445406D01*
X445781Y183541D01*
X446031Y183291D01*
X446115Y183000D01*
X446031Y182708D01*
X445823Y182500D01*
X445490Y182375D01*
X445198Y182333D01*
G01X455331Y166333D02*
Y168833D01*
X454290D01*
X453956Y168708D01*
X453748Y168541D01*
X453665Y168208D01*
X453748Y167875D01*
X453998Y167666D01*
X454290Y167541D01*
X455331D01*
G01X454290D02*
X453665Y166333D01*
G01X451481D02*
X451398Y166875D01*
X451273Y167333D01*
X451106Y167750D01*
X450898Y168208D01*
X450565Y168833D01*
X452231D01*
G01X449131Y166333D02*
Y168833D01*
X448131D01*
X447798Y168708D01*
X447548Y168416D01*
X447465Y168083D01*
X447548Y167750D01*
X447756Y167500D01*
X448131Y167375D01*
X449131D01*
G01X445198Y166333D02*
Y168833D01*
X445698Y168333D01*
G01Y166333D02*
X444698D01*
G01X441598D02*
Y168833D01*
X443140Y167041D01*
X441056D01*
G01X455331Y158333D02*
Y160833D01*
X454290D01*
X453956Y160708D01*
X453748Y160541D01*
X453665Y160208D01*
X453748Y159875D01*
X453998Y159666D01*
X454290Y159541D01*
X455331D01*
G01X454290D02*
X453665Y158333D01*
G01X451481D02*
X451398Y158875D01*
X451273Y159333D01*
X451106Y159750D01*
X450898Y160208D01*
X450565Y160833D01*
X452231D01*
G01X449131Y158333D02*
Y160833D01*
X448131D01*
X447798Y160708D01*
X447548Y160416D01*
X447465Y160083D01*
X447548Y159750D01*
X447756Y159500D01*
X448131Y159375D01*
X449131D01*
G01X445198Y158333D02*
Y160833D01*
X445698Y160333D01*
G01Y158333D02*
X444698D01*
G01X442890Y159375D02*
X442598Y159666D01*
X442348Y159833D01*
X442015Y159916D01*
X441723Y159833D01*
X441515Y159666D01*
X441348Y159416D01*
X441306Y159125D01*
X441348Y158875D01*
X441515Y158625D01*
X441765Y158416D01*
X442056Y158333D01*
X442390Y158416D01*
X442681Y158666D01*
X442848Y159041D01*
X442890Y159458D01*
X442806Y160000D01*
X442681Y160291D01*
X442473Y160583D01*
X442181Y160791D01*
X441890Y160833D01*
X441598Y160750D01*
X441390Y160541D01*
G01X436900Y168017D02*
X439400D01*
Y169058D01*
X439275Y169392D01*
X439108Y169600D01*
X438775Y169683D01*
X438442Y169600D01*
X438233Y169350D01*
X438108Y169058D01*
Y168017D01*
G01Y169058D02*
X436900Y169683D01*
G01Y171867D02*
X437442Y171950D01*
X437900Y172075D01*
X438317Y172242D01*
X438775Y172450D01*
X439400Y172783D01*
Y171117D01*
G01X436900Y174217D02*
X439400D01*
Y175217D01*
X439275Y175550D01*
X438983Y175800D01*
X438650Y175883D01*
X438317Y175800D01*
X438067Y175592D01*
X437942Y175217D01*
Y174217D01*
G01X437275Y177233D02*
X437067Y177483D01*
X436942Y177775D01*
X436900Y178150D01*
X436983Y178525D01*
X437150Y178817D01*
X437442Y179025D01*
X437775Y179067D01*
X438108Y178983D01*
X438317Y178775D01*
X438483Y178483D01*
X438525Y178192D01*
X438483Y177900D01*
X438317Y177525D01*
X439400Y177650D01*
Y178775D01*
G01X466700Y285200D02*
X464000D01*
Y281300D01*
X461400D01*
Y277200D01*
X460500D01*
G01X458100Y274600D02*
Y271000D01*
X455000D01*
G01X466200Y290600D02*
Y289000D01*
G01Y298000D02*
Y294600D01*
G01X436144Y495892D02*
X436394Y496017D01*
X436686Y496100D01*
X437019D01*
X437394Y495975D01*
X437686Y495767D01*
X437894Y495517D01*
X438061Y495100D01*
X438103Y494725D01*
X438019Y494350D01*
X437894Y494100D01*
X437644Y493850D01*
X437353Y493683D01*
X437061Y493600D01*
X436769D01*
X436478Y493683D01*
X436228Y493808D01*
X436019Y493975D01*
G01X433961Y493600D02*
X433669Y493642D01*
X433336Y493767D01*
X433128Y493975D01*
X433044Y494267D01*
X433128Y494558D01*
X433378Y494808D01*
X433753Y494933D01*
X434169D01*
X434419Y495017D01*
X434628Y495225D01*
X434711Y495517D01*
X434586Y495808D01*
X434294Y496017D01*
X433961Y496100D01*
X433628Y496017D01*
X433336Y495808D01*
X433211Y495517D01*
X433294Y495225D01*
X433503Y495017D01*
X433753Y494933D01*
X434169D01*
X434544Y494808D01*
X434794Y494558D01*
X434878Y494267D01*
X434794Y493975D01*
X434586Y493767D01*
X434253Y493642D01*
X433961Y493600D01*
G01X431944D02*
Y496100D01*
X430861Y494017D01*
X429778Y496100D01*
Y493600D01*
G01X427761D02*
Y496100D01*
X428261Y495600D01*
G01Y493600D02*
X427261D01*
G01X424661D02*
Y496100D01*
X425161Y495600D01*
G01Y493600D02*
X424161D01*
G01X453233Y486310D02*
X453483Y486435D01*
X453775Y486518D01*
X454108D01*
X454483Y486393D01*
X454775Y486185D01*
X454983Y485935D01*
X455150Y485518D01*
X455192Y485143D01*
X455108Y484768D01*
X454983Y484518D01*
X454733Y484268D01*
X454442Y484101D01*
X454150Y484018D01*
X453858D01*
X453567Y484101D01*
X453317Y484226D01*
X453108Y484393D01*
G01X451133Y484018D02*
X451050Y484560D01*
X450925Y485018D01*
X450758Y485435D01*
X450550Y485893D01*
X450217Y486518D01*
X451883D01*
G01X449033Y484018D02*
Y486518D01*
X447950Y484435D01*
X446867Y486518D01*
Y484018D01*
G01X445767Y484393D02*
X445517Y484185D01*
X445225Y484060D01*
X444850Y484018D01*
X444475Y484101D01*
X444183Y484268D01*
X443975Y484560D01*
X443933Y484893D01*
X444017Y485226D01*
X444225Y485435D01*
X444517Y485601D01*
X444808Y485643D01*
X445100Y485601D01*
X445475Y485435D01*
X445350Y486518D01*
X444225D01*
G01X473243Y618899D02*
X473493Y619024D01*
X473785Y619107D01*
X474118D01*
X474493Y618982D01*
X474785Y618774D01*
X474993Y618524D01*
X475160Y618107D01*
X475202Y617732D01*
X475118Y617357D01*
X474993Y617107D01*
X474743Y616857D01*
X474452Y616690D01*
X474160Y616607D01*
X473868D01*
X473577Y616690D01*
X473327Y616815D01*
X473118Y616982D01*
G01X471143Y616607D02*
X471060Y617149D01*
X470935Y617607D01*
X470768Y618024D01*
X470560Y618482D01*
X470227Y619107D01*
X471893D01*
G01X468793D02*
Y616607D01*
X467127D01*
G01X464860D02*
Y619107D01*
X465360Y618607D01*
G01Y616607D02*
X464360D01*
G01X460043Y618899D02*
X460293Y619024D01*
X460585Y619107D01*
X460918D01*
X461293Y618982D01*
X461585Y618774D01*
X461793Y618524D01*
X461960Y618107D01*
X462002Y617732D01*
X461918Y617357D01*
X461793Y617107D01*
X461543Y616857D01*
X461252Y616690D01*
X460960Y616607D01*
X460668D01*
X460377Y616690D01*
X460127Y616815D01*
X459918Y616982D01*
G01X457860Y616607D02*
X457568Y616649D01*
X457235Y616774D01*
X457027Y616982D01*
X456943Y617274D01*
X457027Y617565D01*
X457277Y617815D01*
X457652Y617940D01*
X458068D01*
X458318Y618024D01*
X458527Y618232D01*
X458610Y618524D01*
X458485Y618815D01*
X458193Y619024D01*
X457860Y619107D01*
X457527Y619024D01*
X457235Y618815D01*
X457110Y618524D01*
X457193Y618232D01*
X457402Y618024D01*
X457652Y617940D01*
X458068D01*
X458443Y617815D01*
X458693Y617565D01*
X458777Y617274D01*
X458693Y616982D01*
X458485Y616774D01*
X458152Y616649D01*
X457860Y616607D01*
G01X455593Y619107D02*
Y616607D01*
X453927D01*
G01X451660D02*
Y619107D01*
X452160Y618607D01*
G01Y616607D02*
X451160D01*
G01X446843Y618899D02*
X447093Y619024D01*
X447385Y619107D01*
X447718D01*
X448093Y618982D01*
X448385Y618774D01*
X448593Y618524D01*
X448760Y618107D01*
X448802Y617732D01*
X448718Y617357D01*
X448593Y617107D01*
X448343Y616857D01*
X448052Y616690D01*
X447760Y616607D01*
X447468D01*
X447177Y616690D01*
X446927Y616815D01*
X446718Y616982D01*
G01X444660Y616607D02*
X444368Y616649D01*
X444035Y616774D01*
X443827Y616982D01*
X443743Y617274D01*
X443827Y617565D01*
X444077Y617815D01*
X444452Y617940D01*
X444868D01*
X445118Y618024D01*
X445327Y618232D01*
X445410Y618524D01*
X445285Y618815D01*
X444993Y619024D01*
X444660Y619107D01*
X444327Y619024D01*
X444035Y618815D01*
X443910Y618524D01*
X443993Y618232D01*
X444202Y618024D01*
X444452Y617940D01*
X444868D01*
X445243Y617815D01*
X445493Y617565D01*
X445577Y617274D01*
X445493Y616982D01*
X445285Y616774D01*
X444952Y616649D01*
X444660Y616607D01*
G01X442393Y619107D02*
Y616607D01*
X440727D01*
G01X439252Y618690D02*
X439002Y618940D01*
X438710Y619065D01*
X438377Y619107D01*
X437960Y619024D01*
X437668Y618815D01*
X437585Y618565D01*
X437627Y618315D01*
X437793Y618107D01*
X438627Y617690D01*
X439002Y617399D01*
X439252Y616982D01*
X439335Y616607D01*
X437585D01*
G01X497083Y-12608D02*
X497333Y-12483D01*
X497625Y-12400D01*
X497958D01*
X498333Y-12525D01*
X498625Y-12733D01*
X498833Y-12983D01*
X499000Y-13400D01*
X499042Y-13775D01*
X498958Y-14150D01*
X498833Y-14400D01*
X498583Y-14650D01*
X498292Y-14817D01*
X498000Y-14900D01*
X497708D01*
X497417Y-14817D01*
X497167Y-14692D01*
X496958Y-14525D01*
G01X494983Y-14900D02*
X494900Y-14358D01*
X494775Y-13900D01*
X494608Y-13483D01*
X494400Y-13025D01*
X494067Y-12400D01*
X495733D01*
G01X492717D02*
Y-14192D01*
X492550Y-14567D01*
X492217Y-14817D01*
X491800Y-14900D01*
X491383Y-14817D01*
X491050Y-14567D01*
X490883Y-14192D01*
Y-12400D01*
G01X488783Y-14900D02*
X488700Y-14358D01*
X488575Y-13900D01*
X488408Y-13483D01*
X488200Y-13025D01*
X487867Y-12400D01*
X489533D01*
G01X517940Y135280D02*
Y179923D01*
X530640D01*
Y196623D01*
X536440D01*
G01X533830Y114450D02*
X578300D01*
Y141323D01*
X607740D01*
Y196623D01*
X536440D01*
G01X535623Y156723D02*
Y159223D01*
X534582D01*
X534248Y159098D01*
X534040Y158931D01*
X533957Y158598D01*
X534040Y158265D01*
X534290Y158056D01*
X534582Y157931D01*
X535623D01*
G01X534582D02*
X533957Y156723D01*
G01X531690D02*
Y159223D01*
X532190Y158723D01*
G01Y156723D02*
X531190D01*
G01X529423Y159223D02*
Y156723D01*
X527757D01*
G01X526407Y157223D02*
X526157Y156931D01*
X525823Y156765D01*
X525448Y156723D01*
X525115Y156765D01*
X524782Y156973D01*
X524573Y157223D01*
X524532Y157473D01*
X524615Y157765D01*
X524907Y157973D01*
X525198Y158056D01*
X525573D01*
G01X525198D02*
X524948Y158181D01*
X524740Y158390D01*
X524657Y158640D01*
X524740Y158890D01*
X524948Y159098D01*
X525323Y159223D01*
X525698Y159181D01*
X526073Y159015D01*
G01X522390Y156723D02*
Y159223D01*
X522890Y158723D01*
G01Y156723D02*
X521890D01*
G01X550243Y127493D02*
Y129993D01*
X549202D01*
X548868Y129868D01*
X548660Y129701D01*
X548577Y129368D01*
X548660Y129035D01*
X548910Y128826D01*
X549202Y128701D01*
X550243D01*
G01X549202D02*
X548577Y127493D01*
G01X546310D02*
Y129993D01*
X546810Y129493D01*
G01Y127493D02*
X545810D01*
G01X544293D02*
Y129993D01*
X543210Y127910D01*
X542127Y129993D01*
Y127493D01*
G01X540902Y129576D02*
X540652Y129826D01*
X540360Y129951D01*
X540027Y129993D01*
X539610Y129910D01*
X539318Y129701D01*
X539235Y129451D01*
X539277Y129201D01*
X539443Y128993D01*
X540277Y128576D01*
X540652Y128285D01*
X540902Y127868D01*
X540985Y127493D01*
X539235D01*
G01X537927Y127993D02*
X537677Y127701D01*
X537343Y127535D01*
X536968Y127493D01*
X536635Y127535D01*
X536302Y127743D01*
X536093Y127993D01*
X536052Y128243D01*
X536135Y128535D01*
X536427Y128743D01*
X536718Y128826D01*
X537093D01*
G01X536718D02*
X536468Y128951D01*
X536260Y129160D01*
X536177Y129410D01*
X536260Y129660D01*
X536468Y129868D01*
X536843Y129993D01*
X537218Y129951D01*
X537593Y129785D01*
G01X552219Y149063D02*
Y151563D01*
X551178D01*
X550844Y151438D01*
X550636Y151271D01*
X550553Y150938D01*
X550636Y150605D01*
X550886Y150396D01*
X551178Y150271D01*
X552219D01*
G01X551178D02*
X550553Y149063D01*
G01X548286D02*
Y151563D01*
X548786Y151063D01*
G01Y149063D02*
X547786D01*
G01X546436Y151563D02*
X545853Y149063D01*
X545186Y151563D01*
X544519Y149063D01*
X543936Y151563D01*
G01X543003Y149563D02*
X542753Y149271D01*
X542419Y149105D01*
X542044Y149063D01*
X541711Y149105D01*
X541378Y149313D01*
X541169Y149563D01*
X541128Y149813D01*
X541211Y150105D01*
X541503Y150313D01*
X541794Y150396D01*
X542169D01*
G01X541794D02*
X541544Y150521D01*
X541336Y150730D01*
X541253Y150980D01*
X541336Y151230D01*
X541544Y151438D01*
X541919Y151563D01*
X542294Y151521D01*
X542669Y151355D01*
G01X539069Y149063D02*
X538986Y149605D01*
X538861Y150063D01*
X538694Y150480D01*
X538486Y150938D01*
X538153Y151563D01*
X539819D01*
G01X551883Y152663D02*
Y155163D01*
X550842D01*
X550508Y155038D01*
X550300Y154871D01*
X550217Y154538D01*
X550300Y154205D01*
X550550Y153996D01*
X550842Y153871D01*
X551883D01*
G01X550842D02*
X550217Y152663D01*
G01X547950D02*
Y155163D01*
X548450Y154663D01*
G01Y152663D02*
X547450D01*
G01X546100Y155163D02*
X545517Y152663D01*
X544850Y155163D01*
X544183Y152663D01*
X543600Y155163D01*
G01X542667Y153163D02*
X542417Y152871D01*
X542083Y152705D01*
X541708Y152663D01*
X541375Y152705D01*
X541042Y152913D01*
X540833Y153163D01*
X540792Y153413D01*
X540875Y153705D01*
X541167Y153913D01*
X541458Y153996D01*
X541833D01*
G01X541458D02*
X541208Y154121D01*
X541000Y154330D01*
X540917Y154580D01*
X541000Y154830D01*
X541208Y155038D01*
X541583Y155163D01*
X541958Y155121D01*
X542333Y154955D01*
G01X539442Y153705D02*
X539150Y153996D01*
X538900Y154163D01*
X538567Y154246D01*
X538275Y154163D01*
X538067Y153996D01*
X537900Y153746D01*
X537858Y153455D01*
X537900Y153205D01*
X538067Y152955D01*
X538317Y152746D01*
X538608Y152663D01*
X538942Y152746D01*
X539233Y152996D01*
X539400Y153371D01*
X539442Y153788D01*
X539358Y154330D01*
X539233Y154621D01*
X539025Y154913D01*
X538733Y155121D01*
X538442Y155163D01*
X538150Y155080D01*
X537942Y154871D01*
G01X539022Y134340D02*
X539147Y134090D01*
X539230Y133798D01*
Y133465D01*
X539105Y133090D01*
X538897Y132798D01*
X538647Y132590D01*
X538230Y132423D01*
X537855Y132381D01*
X537480Y132465D01*
X537230Y132590D01*
X536980Y132840D01*
X536813Y133131D01*
X536730Y133423D01*
Y133715D01*
X536813Y134006D01*
X536938Y134256D01*
X537105Y134465D01*
G01X536730Y136523D02*
X539230D01*
X538730Y136023D01*
G01X536730D02*
Y137023D01*
G01Y138540D02*
X539230D01*
X537147Y139623D01*
X539230Y140706D01*
X536730D01*
G01X538813Y141931D02*
X539063Y142181D01*
X539188Y142473D01*
X539230Y142806D01*
X539147Y143223D01*
X538938Y143515D01*
X538688Y143598D01*
X538438Y143556D01*
X538230Y143390D01*
X537813Y142556D01*
X537522Y142181D01*
X537105Y141931D01*
X536730Y141848D01*
Y143598D01*
G01X537022Y145115D02*
X536813Y145406D01*
X536730Y145740D01*
X536813Y146073D01*
X537063Y146365D01*
X537438Y146573D01*
X537813Y146656D01*
X538272D01*
X538647Y146573D01*
X538980Y146365D01*
X539147Y146115D01*
X539230Y145823D01*
X539147Y145490D01*
X538980Y145240D01*
X538730Y145073D01*
X538397Y144990D01*
X538105Y145073D01*
X537813Y145281D01*
X537647Y145531D01*
X537605Y145823D01*
X537688Y146156D01*
X537897Y146406D01*
X538272Y146656D01*
G01X532610Y154900D02*
X532860Y155025D01*
X533152Y155108D01*
X533485D01*
X533860Y154983D01*
X534152Y154775D01*
X534360Y154525D01*
X534527Y154108D01*
X534569Y153733D01*
X534485Y153358D01*
X534360Y153108D01*
X534110Y152858D01*
X533819Y152691D01*
X533527Y152608D01*
X533235D01*
X532944Y152691D01*
X532694Y152816D01*
X532485Y152983D01*
G01X530427Y152608D02*
Y155108D01*
X530927Y154608D01*
G01Y152608D02*
X529927D01*
G01X528577Y155108D02*
X527994Y152608D01*
X527327Y155108D01*
X526660Y152608D01*
X526077Y155108D01*
G01X524227Y152608D02*
Y155108D01*
X524727Y154608D01*
G01Y152608D02*
X523727D01*
G01X521127D02*
X520835Y152650D01*
X520502Y152775D01*
X520294Y152983D01*
X520210Y153275D01*
X520294Y153566D01*
X520544Y153816D01*
X520919Y153941D01*
X521335D01*
X521585Y154025D01*
X521794Y154233D01*
X521877Y154525D01*
X521752Y154816D01*
X521460Y155025D01*
X521127Y155108D01*
X520794Y155025D01*
X520502Y154816D01*
X520377Y154525D01*
X520460Y154233D01*
X520669Y154025D01*
X520919Y153941D01*
X521335D01*
X521710Y153816D01*
X521960Y153566D01*
X522044Y153275D01*
X521960Y152983D01*
X521752Y152775D01*
X521419Y152650D01*
X521127Y152608D01*
G01X532640Y151046D02*
X532890Y151171D01*
X533182Y151254D01*
X533515D01*
X533890Y151129D01*
X534182Y150921D01*
X534390Y150671D01*
X534557Y150254D01*
X534599Y149879D01*
X534515Y149504D01*
X534390Y149254D01*
X534140Y149004D01*
X533849Y148837D01*
X533557Y148754D01*
X533265D01*
X532974Y148837D01*
X532724Y148962D01*
X532515Y149129D01*
G01X530457Y148754D02*
Y151254D01*
X530957Y150754D01*
G01Y148754D02*
X529957D01*
G01X528607Y151254D02*
X528024Y148754D01*
X527357Y151254D01*
X526690Y148754D01*
X526107Y151254D01*
G01X524257Y148754D02*
Y151254D01*
X524757Y150754D01*
G01Y148754D02*
X523757D01*
G01X521865Y149046D02*
X521574Y148837D01*
X521240Y148754D01*
X520907Y148837D01*
X520615Y149087D01*
X520407Y149462D01*
X520324Y149837D01*
Y150296D01*
X520407Y150671D01*
X520615Y151004D01*
X520865Y151171D01*
X521157Y151254D01*
X521490Y151171D01*
X521740Y151004D01*
X521907Y150754D01*
X521990Y150421D01*
X521907Y150129D01*
X521699Y149837D01*
X521449Y149671D01*
X521157Y149629D01*
X520824Y149712D01*
X520574Y149921D01*
X520324Y150296D01*
G01X502967Y194184D02*
X505467D01*
Y195225D01*
X505342Y195559D01*
X505175Y195767D01*
X504842Y195850D01*
X504509Y195767D01*
X504300Y195517D01*
X504175Y195225D01*
Y194184D01*
G01Y195225D02*
X502967Y195850D01*
G01Y198034D02*
X503509Y198117D01*
X503967Y198242D01*
X504384Y198409D01*
X504842Y198617D01*
X505467Y198950D01*
Y197284D01*
G01X502967Y200384D02*
X505467D01*
Y201384D01*
X505342Y201717D01*
X505050Y201967D01*
X504717Y202050D01*
X504384Y201967D01*
X504134Y201759D01*
X504009Y201384D01*
Y200384D01*
G01X505050Y203525D02*
X505300Y203775D01*
X505425Y204067D01*
X505467Y204400D01*
X505384Y204817D01*
X505175Y205109D01*
X504925Y205192D01*
X504675Y205150D01*
X504467Y204984D01*
X504050Y204150D01*
X503759Y203775D01*
X503342Y203525D01*
X502967Y203442D01*
Y205192D01*
G01X504009Y206625D02*
X504300Y206917D01*
X504467Y207167D01*
X504550Y207500D01*
X504467Y207792D01*
X504300Y208000D01*
X504050Y208167D01*
X503759Y208209D01*
X503509Y208167D01*
X503259Y208000D01*
X503050Y207750D01*
X502967Y207459D01*
X503050Y207125D01*
X503300Y206834D01*
X503675Y206667D01*
X504092Y206625D01*
X504634Y206709D01*
X504925Y206834D01*
X505217Y207042D01*
X505425Y207334D01*
X505467Y207625D01*
X505384Y207917D01*
X505175Y208125D01*
G01X499467Y194184D02*
X501967D01*
Y195225D01*
X501842Y195559D01*
X501675Y195767D01*
X501342Y195850D01*
X501009Y195767D01*
X500800Y195517D01*
X500675Y195225D01*
Y194184D01*
G01Y195225D02*
X499467Y195850D01*
G01Y198034D02*
X500009Y198117D01*
X500467Y198242D01*
X500884Y198409D01*
X501342Y198617D01*
X501967Y198950D01*
Y197284D01*
G01X499467Y200384D02*
X501967D01*
Y201384D01*
X501842Y201717D01*
X501550Y201967D01*
X501217Y202050D01*
X500884Y201967D01*
X500634Y201759D01*
X500509Y201384D01*
Y200384D01*
G01X501550Y203525D02*
X501800Y203775D01*
X501925Y204067D01*
X501967Y204400D01*
X501884Y204817D01*
X501675Y205109D01*
X501425Y205192D01*
X501175Y205150D01*
X500967Y204984D01*
X500550Y204150D01*
X500259Y203775D01*
X499842Y203525D01*
X499467Y203442D01*
Y205192D01*
G01Y207334D02*
X500009Y207417D01*
X500467Y207542D01*
X500884Y207709D01*
X501342Y207917D01*
X501967Y208250D01*
Y206584D01*
G01X501875Y189731D02*
Y192231D01*
X500834D01*
X500500Y192106D01*
X500292Y191939D01*
X500209Y191606D01*
X500292Y191273D01*
X500542Y191064D01*
X500834Y190939D01*
X501875D01*
G01X500834D02*
X500209Y189731D01*
G01X498025D02*
X497942Y190273D01*
X497817Y190731D01*
X497650Y191148D01*
X497442Y191606D01*
X497109Y192231D01*
X498775D01*
G01X495675Y189731D02*
Y192231D01*
X494675D01*
X494342Y192106D01*
X494092Y191814D01*
X494009Y191481D01*
X494092Y191148D01*
X494300Y190898D01*
X494675Y190773D01*
X495675D01*
G01X492534Y191814D02*
X492284Y192064D01*
X491992Y192189D01*
X491659Y192231D01*
X491242Y192148D01*
X490950Y191939D01*
X490867Y191689D01*
X490909Y191439D01*
X491075Y191231D01*
X491909Y190814D01*
X492284Y190523D01*
X492534Y190106D01*
X492617Y189731D01*
X490867D01*
G01X489350Y190023D02*
X489059Y189814D01*
X488725Y189731D01*
X488392Y189814D01*
X488100Y190064D01*
X487892Y190439D01*
X487809Y190814D01*
Y191273D01*
X487892Y191648D01*
X488100Y191981D01*
X488350Y192148D01*
X488642Y192231D01*
X488975Y192148D01*
X489225Y191981D01*
X489392Y191731D01*
X489475Y191398D01*
X489392Y191106D01*
X489184Y190814D01*
X488934Y190648D01*
X488642Y190606D01*
X488309Y190689D01*
X488059Y190898D01*
X487809Y191273D01*
G01X506467Y194184D02*
X508967D01*
Y195225D01*
X508842Y195559D01*
X508675Y195767D01*
X508342Y195850D01*
X508009Y195767D01*
X507800Y195517D01*
X507675Y195225D01*
Y194184D01*
G01Y195225D02*
X506467Y195850D01*
G01Y198034D02*
X507009Y198117D01*
X507467Y198242D01*
X507884Y198409D01*
X508342Y198617D01*
X508967Y198950D01*
Y197284D01*
G01X506467Y200384D02*
X508967D01*
Y201384D01*
X508842Y201717D01*
X508550Y201967D01*
X508217Y202050D01*
X507884Y201967D01*
X507634Y201759D01*
X507509Y201384D01*
Y200384D01*
G01X508550Y203525D02*
X508800Y203775D01*
X508925Y204067D01*
X508967Y204400D01*
X508884Y204817D01*
X508675Y205109D01*
X508425Y205192D01*
X508175Y205150D01*
X507967Y204984D01*
X507550Y204150D01*
X507259Y203775D01*
X506842Y203525D01*
X506467Y203442D01*
Y205192D01*
G01X506842Y206500D02*
X506634Y206750D01*
X506509Y207042D01*
X506467Y207417D01*
X506550Y207792D01*
X506717Y208084D01*
X507009Y208292D01*
X507342Y208334D01*
X507675Y208250D01*
X507884Y208042D01*
X508050Y207750D01*
X508092Y207459D01*
X508050Y207167D01*
X507884Y206792D01*
X508967Y206917D01*
Y208042D01*
G01X518963Y189942D02*
Y192442D01*
X517922D01*
X517588Y192317D01*
X517380Y192150D01*
X517297Y191817D01*
X517380Y191484D01*
X517630Y191275D01*
X517922Y191150D01*
X518963D01*
G01X517922D02*
X517297Y189942D01*
G01X515113D02*
X515030Y190484D01*
X514905Y190942D01*
X514738Y191359D01*
X514530Y191817D01*
X514197Y192442D01*
X515863D01*
G01X512763Y189942D02*
Y192442D01*
X511763D01*
X511430Y192317D01*
X511180Y192025D01*
X511097Y191692D01*
X511180Y191359D01*
X511388Y191109D01*
X511763Y190984D01*
X512763D01*
G01X509622Y192025D02*
X509372Y192275D01*
X509080Y192400D01*
X508747Y192442D01*
X508330Y192359D01*
X508038Y192150D01*
X507955Y191900D01*
X507997Y191650D01*
X508163Y191442D01*
X508997Y191025D01*
X509372Y190734D01*
X509622Y190317D01*
X509705Y189942D01*
X507955D01*
G01X505730D02*
X505438Y189984D01*
X505105Y190109D01*
X504897Y190317D01*
X504813Y190609D01*
X504897Y190900D01*
X505147Y191150D01*
X505522Y191275D01*
X505938D01*
X506188Y191359D01*
X506397Y191567D01*
X506480Y191859D01*
X506355Y192150D01*
X506063Y192359D01*
X505730Y192442D01*
X505397Y192359D01*
X505105Y192150D01*
X504980Y191859D01*
X505063Y191567D01*
X505272Y191359D01*
X505522Y191275D01*
X505938D01*
X506313Y191150D01*
X506563Y190900D01*
X506647Y190609D01*
X506563Y190317D01*
X506355Y190109D01*
X506022Y189984D01*
X505730Y189942D01*
G01X535523Y160523D02*
Y163023D01*
X534482D01*
X534148Y162898D01*
X533940Y162731D01*
X533857Y162398D01*
X533940Y162065D01*
X534190Y161856D01*
X534482Y161731D01*
X535523D01*
G01X534482D02*
X533857Y160523D01*
G01X531590D02*
Y163023D01*
X532090Y162523D01*
G01Y160523D02*
X531090D01*
G01X529323Y163023D02*
Y160523D01*
X527657D01*
G01X526182Y162606D02*
X525932Y162856D01*
X525640Y162981D01*
X525307Y163023D01*
X524890Y162940D01*
X524598Y162731D01*
X524515Y162481D01*
X524557Y162231D01*
X524723Y162023D01*
X525557Y161606D01*
X525932Y161315D01*
X526182Y160898D01*
X526265Y160523D01*
X524515D01*
G01X522373D02*
X522290Y161065D01*
X522165Y161523D01*
X521998Y161940D01*
X521790Y162398D01*
X521457Y163023D01*
X523123D01*
G01X533384Y168662D02*
X535884D01*
Y169703D01*
X535759Y170037D01*
X535592Y170245D01*
X535259Y170328D01*
X534926Y170245D01*
X534717Y169995D01*
X534592Y169703D01*
Y168662D01*
G01Y169703D02*
X533384Y170328D01*
G01X534426Y171803D02*
X534717Y172095D01*
X534884Y172345D01*
X534967Y172678D01*
X534884Y172970D01*
X534717Y173178D01*
X534467Y173345D01*
X534176Y173387D01*
X533926Y173345D01*
X533676Y173178D01*
X533467Y172928D01*
X533384Y172637D01*
X533467Y172303D01*
X533717Y172012D01*
X534092Y171845D01*
X534509Y171803D01*
X535051Y171887D01*
X535342Y172012D01*
X535634Y172220D01*
X535842Y172512D01*
X535884Y172803D01*
X535801Y173095D01*
X535592Y173303D01*
G01X535884Y174445D02*
X533384Y175028D01*
X535884Y175695D01*
X533384Y176362D01*
X535884Y176945D01*
G01X533384Y178795D02*
X535884D01*
X535384Y178295D01*
G01X533384D02*
Y179295D01*
G01X535467Y181103D02*
X535717Y181353D01*
X535842Y181645D01*
X535884Y181978D01*
X535801Y182395D01*
X535592Y182687D01*
X535342Y182770D01*
X535092Y182728D01*
X534884Y182562D01*
X534467Y181728D01*
X534176Y181353D01*
X533759Y181103D01*
X533384Y181020D01*
Y182770D01*
G01X536747Y168644D02*
X539247D01*
Y169685D01*
X539122Y170019D01*
X538955Y170227D01*
X538622Y170310D01*
X538289Y170227D01*
X538080Y169977D01*
X537955Y169685D01*
Y168644D01*
G01Y169685D02*
X536747Y170310D01*
G01X537789Y171785D02*
X538080Y172077D01*
X538247Y172327D01*
X538330Y172660D01*
X538247Y172952D01*
X538080Y173160D01*
X537830Y173327D01*
X537539Y173369D01*
X537289Y173327D01*
X537039Y173160D01*
X536830Y172910D01*
X536747Y172619D01*
X536830Y172285D01*
X537080Y171994D01*
X537455Y171827D01*
X537872Y171785D01*
X538414Y171869D01*
X538705Y171994D01*
X538997Y172202D01*
X539205Y172494D01*
X539247Y172785D01*
X539164Y173077D01*
X538955Y173285D01*
G01X539247Y174427D02*
X536747Y175010D01*
X539247Y175677D01*
X536747Y176344D01*
X539247Y176927D01*
G01X536747Y178777D02*
X539247D01*
X538747Y178277D01*
G01X536747D02*
Y179277D01*
G01Y181877D02*
X539247D01*
X538747Y181377D01*
G01X536747D02*
Y182377D01*
G01X540447Y168694D02*
X542947D01*
Y169735D01*
X542822Y170069D01*
X542655Y170277D01*
X542322Y170360D01*
X541989Y170277D01*
X541780Y170027D01*
X541655Y169735D01*
Y168694D01*
G01Y169735D02*
X540447Y170360D01*
G01X541489Y171835D02*
X541780Y172127D01*
X541947Y172377D01*
X542030Y172710D01*
X541947Y173002D01*
X541780Y173210D01*
X541530Y173377D01*
X541239Y173419D01*
X540989Y173377D01*
X540739Y173210D01*
X540530Y172960D01*
X540447Y172669D01*
X540530Y172335D01*
X540780Y172044D01*
X541155Y171877D01*
X541572Y171835D01*
X542114Y171919D01*
X542405Y172044D01*
X542697Y172252D01*
X542905Y172544D01*
X542947Y172835D01*
X542864Y173127D01*
X542655Y173335D01*
G01X542947Y174477D02*
X540447Y175060D01*
X542947Y175727D01*
X540447Y176394D01*
X542947Y176977D01*
G01X541489Y178035D02*
X541780Y178327D01*
X541947Y178577D01*
X542030Y178910D01*
X541947Y179202D01*
X541780Y179410D01*
X541530Y179577D01*
X541239Y179619D01*
X540989Y179577D01*
X540739Y179410D01*
X540530Y179160D01*
X540447Y178869D01*
X540530Y178535D01*
X540780Y178244D01*
X541155Y178077D01*
X541572Y178035D01*
X542114Y178119D01*
X542405Y178244D01*
X542697Y178452D01*
X542905Y178744D01*
X542947Y179035D01*
X542864Y179327D01*
X542655Y179535D01*
G01X550363Y183844D02*
Y186344D01*
X549322D01*
X548988Y186219D01*
X548780Y186052D01*
X548697Y185719D01*
X548780Y185386D01*
X549030Y185177D01*
X549322Y185052D01*
X550363D01*
G01X549322D02*
X548697Y183844D01*
G01X547222Y184886D02*
X546930Y185177D01*
X546680Y185344D01*
X546347Y185427D01*
X546055Y185344D01*
X545847Y185177D01*
X545680Y184927D01*
X545638Y184636D01*
X545680Y184386D01*
X545847Y184136D01*
X546097Y183927D01*
X546388Y183844D01*
X546722Y183927D01*
X547013Y184177D01*
X547180Y184552D01*
X547222Y184969D01*
X547138Y185511D01*
X547013Y185802D01*
X546805Y186094D01*
X546513Y186302D01*
X546222Y186344D01*
X545930Y186261D01*
X545722Y186052D01*
G01X544580Y186344D02*
X543997Y183844D01*
X543330Y186344D01*
X542663Y183844D01*
X542080Y186344D01*
G01X540230Y183844D02*
Y186344D01*
X540730Y185844D01*
G01Y183844D02*
X539730D01*
G01X537922Y184886D02*
X537630Y185177D01*
X537380Y185344D01*
X537047Y185427D01*
X536755Y185344D01*
X536547Y185177D01*
X536380Y184927D01*
X536338Y184636D01*
X536380Y184386D01*
X536547Y184136D01*
X536797Y183927D01*
X537088Y183844D01*
X537422Y183927D01*
X537713Y184177D01*
X537880Y184552D01*
X537922Y184969D01*
X537838Y185511D01*
X537713Y185802D01*
X537505Y186094D01*
X537213Y186302D01*
X536922Y186344D01*
X536630Y186261D01*
X536422Y186052D01*
G01X550080Y188277D02*
X550413Y188319D01*
X550705Y188485D01*
X550955Y188735D01*
X551122Y189027D01*
X551205Y189360D01*
Y189694D01*
X551122Y190027D01*
X550955Y190319D01*
X550705Y190569D01*
X550413Y190735D01*
X550080Y190777D01*
X549747Y190735D01*
X549455Y190569D01*
X549205Y190319D01*
X549038Y190027D01*
X548955Y189694D01*
Y189360D01*
X549038Y189027D01*
X549205Y188735D01*
X549455Y188485D01*
X549747Y188319D01*
X550080Y188277D01*
G01X549747Y188944D02*
X549247Y188277D01*
G01X546980D02*
Y190777D01*
X547480Y190277D01*
G01Y188277D02*
X546480D01*
G01X544713Y190777D02*
Y188277D01*
X543047D01*
G01X541572Y190360D02*
X541322Y190610D01*
X541030Y190735D01*
X540697Y190777D01*
X540280Y190694D01*
X539988Y190485D01*
X539905Y190235D01*
X539947Y189985D01*
X540113Y189777D01*
X540947Y189360D01*
X541322Y189069D01*
X541572Y188652D01*
X541655Y188277D01*
X539905D01*
G01X529333Y170992D02*
X529583Y171117D01*
X529875Y171200D01*
X530208D01*
X530583Y171075D01*
X530875Y170867D01*
X531083Y170617D01*
X531250Y170200D01*
X531292Y169825D01*
X531208Y169450D01*
X531083Y169200D01*
X530833Y168950D01*
X530542Y168783D01*
X530250Y168700D01*
X529958D01*
X529667Y168783D01*
X529417Y168908D01*
X529208Y169075D01*
G01X527942Y169742D02*
X527650Y170033D01*
X527400Y170200D01*
X527067Y170283D01*
X526775Y170200D01*
X526567Y170033D01*
X526400Y169783D01*
X526358Y169492D01*
X526400Y169242D01*
X526567Y168992D01*
X526817Y168783D01*
X527108Y168700D01*
X527442Y168783D01*
X527733Y169033D01*
X527900Y169408D01*
X527942Y169825D01*
X527858Y170367D01*
X527733Y170658D01*
X527525Y170950D01*
X527233Y171158D01*
X526942Y171200D01*
X526650Y171117D01*
X526442Y170908D01*
G01X525300Y171200D02*
X524717Y168700D01*
X524050Y171200D01*
X523383Y168700D01*
X522800Y171200D01*
G01X520950Y168700D02*
Y171200D01*
X521450Y170700D01*
G01Y168700D02*
X520450D01*
G01X550411Y162911D02*
Y161119D01*
X550244Y160744D01*
X549911Y160494D01*
X549494Y160411D01*
X549077Y160494D01*
X548744Y160744D01*
X548577Y161119D01*
Y162911D01*
G01X547186Y161453D02*
X546894Y161744D01*
X546644Y161911D01*
X546311Y161994D01*
X546019Y161911D01*
X545811Y161744D01*
X545644Y161494D01*
X545602Y161203D01*
X545644Y160953D01*
X545811Y160703D01*
X546061Y160494D01*
X546352Y160411D01*
X546686Y160494D01*
X546977Y160744D01*
X547144Y161119D01*
X547186Y161536D01*
X547102Y162078D01*
X546977Y162369D01*
X546769Y162661D01*
X546477Y162869D01*
X546186Y162911D01*
X545894Y162828D01*
X545686Y162619D01*
G01X544544Y162911D02*
X543961Y160411D01*
X543294Y162911D01*
X542627Y160411D01*
X542044Y162911D01*
G01X540194Y160411D02*
Y162911D01*
X540694Y162411D01*
G01Y160411D02*
X539694D01*
G01X534600Y657200D02*
Y660200D01*
X533600D01*
X533200Y660050D01*
X532900Y659850D01*
X532650Y659550D01*
X532450Y659200D01*
X532400Y658700D01*
X532450Y658200D01*
X532650Y657850D01*
X532900Y657550D01*
X533200Y657350D01*
X533600Y657200D01*
X534600D01*
G01X530650Y658550D02*
X529050D01*
X529200Y658900D01*
X529450Y659100D01*
X529800Y659200D01*
X530150Y659150D01*
X530450Y659000D01*
X530650Y658650D01*
X530750Y658350D01*
Y658050D01*
X530650Y657750D01*
X530400Y657450D01*
X530100Y657250D01*
X529750Y657200D01*
X529400Y657300D01*
X529050Y657600D01*
G01X526300Y657200D02*
Y660200D01*
G01X522700D02*
Y657200D01*
G01X523400Y659200D02*
X522000D01*
G01X518200Y657200D02*
Y659200D01*
G01Y658850D02*
X518400Y659050D01*
X518700Y659150D01*
X519050Y659200D01*
X519400Y659100D01*
X519700Y658900D01*
X519900Y658600D01*
X520000Y658200D01*
X519900Y657800D01*
X519700Y657500D01*
X519400Y657300D01*
X519050Y657200D01*
X518700Y657250D01*
X518400Y657400D01*
X518200Y657600D01*
G01X517000Y656200D02*
X514000D01*
G01X512900Y660200D02*
Y657200D01*
X510900D01*
G01X509400Y657650D02*
X509100Y657400D01*
X508750Y657250D01*
X508300Y657200D01*
X507850Y657300D01*
X507500Y657500D01*
X507250Y657850D01*
X507200Y658250D01*
X507300Y658650D01*
X507550Y658900D01*
X507900Y659100D01*
X508250Y659150D01*
X508600Y659100D01*
X509050Y658900D01*
X508900Y660200D01*
X507550D01*
G01X506200Y656200D02*
X503200D01*
G01X502200Y657650D02*
X501900Y657400D01*
X501550Y657250D01*
X501100Y657200D01*
X500650Y657300D01*
X500300Y657500D01*
X500050Y657850D01*
X500000Y658250D01*
X500100Y658650D01*
X500350Y658900D01*
X500700Y659100D01*
X501050Y659150D01*
X501400Y659100D01*
X501850Y658900D01*
X501700Y660200D01*
X500350D01*
G01X497500Y659200D02*
Y657200D01*
G01Y660000D02*
X497600Y660050D01*
Y660150D01*
X497500Y660200D01*
X497400Y660150D01*
Y660050D01*
X497500Y660000D01*
G01X494750Y657200D02*
Y659200D01*
G01Y658700D02*
X494550Y658950D01*
X494250Y659150D01*
X493850Y659200D01*
X493500Y659150D01*
X493200Y658950D01*
X493050Y658600D01*
Y657200D01*
G01X489500Y658950D02*
X489850Y659150D01*
X490150Y659200D01*
X490550Y659100D01*
X490850Y658900D01*
X491050Y658550D01*
X491100Y658200D01*
X491050Y657850D01*
X490850Y657550D01*
X490550Y657300D01*
X490150Y657200D01*
X489800Y657300D01*
X489500Y657500D01*
G01X487550Y657200D02*
Y660200D01*
G01Y658750D02*
X487300Y659000D01*
X487050Y659150D01*
X486650Y659200D01*
X486350Y659150D01*
X486000Y658950D01*
X485850Y658650D01*
Y657200D01*
G01X592633Y33192D02*
X592883Y33317D01*
X593175Y33400D01*
X593508D01*
X593883Y33275D01*
X594175Y33067D01*
X594383Y32817D01*
X594550Y32400D01*
X594592Y32025D01*
X594508Y31650D01*
X594383Y31400D01*
X594133Y31150D01*
X593842Y30983D01*
X593550Y30900D01*
X593258D01*
X592967Y30983D01*
X592717Y31108D01*
X592508Y31275D01*
G01X590533Y30900D02*
X590450Y31442D01*
X590325Y31900D01*
X590158Y32317D01*
X589950Y32775D01*
X589617Y33400D01*
X591283D01*
G01X588267D02*
Y31608D01*
X588100Y31233D01*
X587767Y30983D01*
X587350Y30900D01*
X586933Y30983D01*
X586600Y31233D01*
X586433Y31608D01*
Y33400D01*
G01X585167Y31400D02*
X584917Y31108D01*
X584583Y30942D01*
X584208Y30900D01*
X583875Y30942D01*
X583542Y31150D01*
X583333Y31400D01*
X583292Y31650D01*
X583375Y31942D01*
X583667Y32150D01*
X583958Y32233D01*
X584333D01*
G01X583958D02*
X583708Y32358D01*
X583500Y32567D01*
X583417Y32817D01*
X583500Y33067D01*
X583708Y33275D01*
X584083Y33400D01*
X584458Y33358D01*
X584833Y33192D01*
G01X604633Y-11408D02*
X604883Y-11283D01*
X605175Y-11200D01*
X605508D01*
X605883Y-11325D01*
X606175Y-11533D01*
X606383Y-11783D01*
X606550Y-12200D01*
X606592Y-12575D01*
X606508Y-12950D01*
X606383Y-13200D01*
X606133Y-13450D01*
X605842Y-13617D01*
X605550Y-13700D01*
X605258D01*
X604967Y-13617D01*
X604717Y-13492D01*
X604508Y-13325D01*
G01X602533Y-13700D02*
X602450Y-13158D01*
X602325Y-12700D01*
X602158Y-12283D01*
X601950Y-11825D01*
X601617Y-11200D01*
X603283D01*
G01X600267D02*
Y-12992D01*
X600100Y-13367D01*
X599767Y-13617D01*
X599350Y-13700D01*
X598933Y-13617D01*
X598600Y-13367D01*
X598433Y-12992D01*
Y-11200D01*
G01X597042Y-12658D02*
X596750Y-12367D01*
X596500Y-12200D01*
X596167Y-12117D01*
X595875Y-12200D01*
X595667Y-12367D01*
X595500Y-12617D01*
X595458Y-12908D01*
X595500Y-13158D01*
X595667Y-13408D01*
X595917Y-13617D01*
X596208Y-13700D01*
X596542Y-13617D01*
X596833Y-13367D01*
X597000Y-12992D01*
X597042Y-12575D01*
X596958Y-12033D01*
X596833Y-11742D01*
X596625Y-11450D01*
X596333Y-11242D01*
X596042Y-11200D01*
X595750Y-11283D01*
X595542Y-11492D01*
G01X568733Y32792D02*
X568983Y32917D01*
X569275Y33000D01*
X569608D01*
X569983Y32875D01*
X570275Y32667D01*
X570483Y32417D01*
X570650Y32000D01*
X570692Y31625D01*
X570608Y31250D01*
X570483Y31000D01*
X570233Y30750D01*
X569942Y30583D01*
X569650Y30500D01*
X569358D01*
X569067Y30583D01*
X568817Y30708D01*
X568608Y30875D01*
G01X566633Y30500D02*
X566550Y31042D01*
X566425Y31500D01*
X566258Y31917D01*
X566050Y32375D01*
X565717Y33000D01*
X567383D01*
G01X564367D02*
Y31208D01*
X564200Y30833D01*
X563867Y30583D01*
X563450Y30500D01*
X563033Y30583D01*
X562700Y30833D01*
X562533Y31208D01*
Y33000D01*
G01X559850Y30500D02*
Y33000D01*
X561392Y31208D01*
X559308D01*
G01X611933Y-16708D02*
X612183Y-16583D01*
X612475Y-16500D01*
X612808D01*
X613183Y-16625D01*
X613475Y-16833D01*
X613683Y-17083D01*
X613850Y-17500D01*
X613892Y-17875D01*
X613808Y-18250D01*
X613683Y-18500D01*
X613433Y-18750D01*
X613142Y-18917D01*
X612850Y-19000D01*
X612558D01*
X612267Y-18917D01*
X612017Y-18792D01*
X611808Y-18625D01*
G01X609250Y-19000D02*
Y-16500D01*
X610792Y-18292D01*
X608708D01*
G01X606400Y-17750D02*
X605567D01*
Y-18500D01*
X605817Y-18750D01*
X606108Y-18917D01*
X606525Y-19000D01*
X606942Y-18917D01*
X607233Y-18750D01*
X607483Y-18500D01*
X607650Y-18208D01*
X607733Y-17875D01*
Y-17583D01*
X607650Y-17333D01*
X607483Y-17042D01*
X607233Y-16792D01*
X606983Y-16625D01*
X606650Y-16500D01*
X606358D01*
X606025Y-16583D01*
X605775Y-16750D01*
G01X604342Y-16917D02*
X604092Y-16667D01*
X603800Y-16542D01*
X603467Y-16500D01*
X603050Y-16583D01*
X602758Y-16792D01*
X602675Y-17042D01*
X602717Y-17292D01*
X602883Y-17500D01*
X603717Y-17917D01*
X604092Y-18208D01*
X604342Y-18625D01*
X604425Y-19000D01*
X602675D01*
G01X601367Y-18625D02*
X601117Y-18833D01*
X600825Y-18958D01*
X600450Y-19000D01*
X600075Y-18917D01*
X599783Y-18750D01*
X599575Y-18458D01*
X599533Y-18125D01*
X599617Y-17792D01*
X599825Y-17583D01*
X600117Y-17417D01*
X600408Y-17375D01*
X600700Y-17417D01*
X601075Y-17583D01*
X600950Y-16500D01*
X599825D01*
G01X592433Y70742D02*
X592683Y70867D01*
X592975Y70950D01*
X593308D01*
X593683Y70825D01*
X593975Y70617D01*
X594183Y70367D01*
X594350Y69950D01*
X594392Y69575D01*
X594308Y69200D01*
X594183Y68950D01*
X593933Y68700D01*
X593642Y68533D01*
X593350Y68450D01*
X593058D01*
X592767Y68533D01*
X592517Y68658D01*
X592308Y68825D01*
G01X590333Y68450D02*
X590250Y68992D01*
X590125Y69450D01*
X589958Y69867D01*
X589750Y70325D01*
X589417Y70950D01*
X591083D01*
G01X587150D02*
Y68450D01*
G01X588108Y70950D02*
X586192D01*
G01X584842Y70533D02*
X584592Y70783D01*
X584300Y70908D01*
X583967Y70950D01*
X583550Y70867D01*
X583258Y70658D01*
X583175Y70408D01*
X583217Y70158D01*
X583383Y69950D01*
X584217Y69533D01*
X584592Y69242D01*
X584842Y68825D01*
X584925Y68450D01*
X583175D01*
G01X568733Y70842D02*
X568983Y70967D01*
X569275Y71050D01*
X569608D01*
X569983Y70925D01*
X570275Y70717D01*
X570483Y70467D01*
X570650Y70050D01*
X570692Y69675D01*
X570608Y69300D01*
X570483Y69050D01*
X570233Y68800D01*
X569942Y68633D01*
X569650Y68550D01*
X569358D01*
X569067Y68633D01*
X568817Y68758D01*
X568608Y68925D01*
G01X566633Y68550D02*
X566550Y69092D01*
X566425Y69550D01*
X566258Y69967D01*
X566050Y70425D01*
X565717Y71050D01*
X567383D01*
G01X563450D02*
Y68550D01*
G01X564408Y71050D02*
X562492D01*
G01X561267Y69050D02*
X561017Y68758D01*
X560683Y68592D01*
X560308Y68550D01*
X559975Y68592D01*
X559642Y68800D01*
X559433Y69050D01*
X559392Y69300D01*
X559475Y69592D01*
X559767Y69800D01*
X560058Y69883D01*
X560433D01*
G01X560058D02*
X559808Y70008D01*
X559600Y70217D01*
X559517Y70467D01*
X559600Y70717D01*
X559808Y70925D01*
X560183Y71050D01*
X560558Y71008D01*
X560933Y70842D01*
G01X558549Y153379D02*
X559349Y153729D01*
X560282Y153962D01*
X561349D01*
X562549Y153612D01*
X563482Y153029D01*
X564149Y152329D01*
X564682Y151162D01*
X564815Y150112D01*
X564549Y149062D01*
X564149Y148362D01*
X563349Y147662D01*
X562415Y147195D01*
X561482Y146962D01*
X560549D01*
X559615Y147195D01*
X558815Y147545D01*
X558149Y148012D01*
G01X604098Y152532D02*
Y155032D01*
X603057D01*
X602723Y154907D01*
X602515Y154740D01*
X602432Y154407D01*
X602515Y154074D01*
X602765Y153865D01*
X603057Y153740D01*
X604098D01*
G01X603057D02*
X602432Y152532D01*
G01X600165D02*
Y155032D01*
X600665Y154532D01*
G01Y152532D02*
X599665D01*
G01X597898Y155032D02*
Y152532D01*
X596232D01*
G01X594757Y154615D02*
X594507Y154865D01*
X594215Y154990D01*
X593882Y155032D01*
X593465Y154949D01*
X593173Y154740D01*
X593090Y154490D01*
X593132Y154240D01*
X593298Y154032D01*
X594132Y153615D01*
X594507Y153324D01*
X594757Y152907D01*
X594840Y152532D01*
X593090D01*
G01X590865Y155032D02*
X591198Y154949D01*
X591448Y154740D01*
X591615Y154490D01*
X591740Y154157D01*
X591782Y153782D01*
X591740Y153407D01*
X591615Y153074D01*
X591448Y152824D01*
X591198Y152615D01*
X590865Y152532D01*
X590532Y152615D01*
X590282Y152824D01*
X590115Y153074D01*
X589990Y153407D01*
X589948Y153782D01*
X589990Y154157D01*
X590115Y154490D01*
X590282Y154740D01*
X590532Y154949D01*
X590865Y155032D01*
G01X559020Y135577D02*
Y138077D01*
X557979D01*
X557645Y137952D01*
X557437Y137785D01*
X557354Y137452D01*
X557437Y137119D01*
X557687Y136910D01*
X557979Y136785D01*
X559020D01*
G01X557979D02*
X557354Y135577D01*
G01X555087D02*
Y138077D01*
X555587Y137577D01*
G01Y135577D02*
X554587D01*
G01X553237Y138077D02*
X552654Y135577D01*
X551987Y138077D01*
X551320Y135577D01*
X550737Y138077D01*
G01X549804Y136077D02*
X549554Y135785D01*
X549220Y135619D01*
X548845Y135577D01*
X548512Y135619D01*
X548179Y135827D01*
X547970Y136077D01*
X547929Y136327D01*
X548012Y136619D01*
X548304Y136827D01*
X548595Y136910D01*
X548970D01*
G01X548595D02*
X548345Y137035D01*
X548137Y137244D01*
X548054Y137494D01*
X548137Y137744D01*
X548345Y137952D01*
X548720Y138077D01*
X549095Y138035D01*
X549470Y137869D01*
G01X545287Y135577D02*
Y138077D01*
X546829Y136285D01*
X544745D01*
G01X558972Y139741D02*
Y142241D01*
X557931D01*
X557597Y142116D01*
X557389Y141949D01*
X557306Y141616D01*
X557389Y141283D01*
X557639Y141074D01*
X557931Y140949D01*
X558972D01*
G01X557931D02*
X557306Y139741D01*
G01X555039D02*
Y142241D01*
X555539Y141741D01*
G01Y139741D02*
X554539D01*
G01X553189Y142241D02*
X552606Y139741D01*
X551939Y142241D01*
X551272Y139741D01*
X550689Y142241D01*
G01X549756Y140241D02*
X549506Y139949D01*
X549172Y139783D01*
X548797Y139741D01*
X548464Y139783D01*
X548131Y139991D01*
X547922Y140241D01*
X547881Y140491D01*
X547964Y140783D01*
X548256Y140991D01*
X548547Y141074D01*
X548922D01*
G01X548547D02*
X548297Y141199D01*
X548089Y141408D01*
X548006Y141658D01*
X548089Y141908D01*
X548297Y142116D01*
X548672Y142241D01*
X549047Y142199D01*
X549422Y142033D01*
G01X546656Y140241D02*
X546406Y139949D01*
X546072Y139783D01*
X545697Y139741D01*
X545364Y139783D01*
X545031Y139991D01*
X544822Y140241D01*
X544781Y140491D01*
X544864Y140783D01*
X545156Y140991D01*
X545447Y141074D01*
X545822D01*
G01X545447D02*
X545197Y141199D01*
X544989Y141408D01*
X544906Y141658D01*
X544989Y141908D01*
X545197Y142116D01*
X545572Y142241D01*
X545947Y142199D01*
X546322Y142033D01*
G01X556943Y123133D02*
Y125633D01*
X555902D01*
X555568Y125508D01*
X555360Y125341D01*
X555277Y125008D01*
X555360Y124675D01*
X555610Y124466D01*
X555902Y124341D01*
X556943D01*
G01X555902D02*
X555277Y123133D01*
G01X553010D02*
Y125633D01*
X553510Y125133D01*
G01Y123133D02*
X552510D01*
G01X550993D02*
Y125633D01*
X549910Y123550D01*
X548827Y125633D01*
Y123133D01*
G01X547727Y123508D02*
X547477Y123300D01*
X547185Y123175D01*
X546810Y123133D01*
X546435Y123216D01*
X546143Y123383D01*
X545935Y123675D01*
X545893Y124008D01*
X545977Y124341D01*
X546185Y124550D01*
X546477Y124716D01*
X546768Y124758D01*
X547060Y124716D01*
X547435Y124550D01*
X547310Y125633D01*
X546185D01*
G01X540830Y132790D02*
X543330D01*
Y133831D01*
X543205Y134165D01*
X543038Y134373D01*
X542705Y134456D01*
X542372Y134373D01*
X542163Y134123D01*
X542038Y133831D01*
Y132790D01*
G01Y133831D02*
X540830Y134456D01*
G01Y136723D02*
X543330D01*
X542830Y136223D01*
G01X540830D02*
Y137223D01*
G01Y138740D02*
X543330D01*
X541247Y139823D01*
X543330Y140906D01*
X540830D01*
G01X542913Y142131D02*
X543163Y142381D01*
X543288Y142673D01*
X543330Y143006D01*
X543247Y143423D01*
X543038Y143715D01*
X542788Y143798D01*
X542538Y143756D01*
X542330Y143590D01*
X541913Y142756D01*
X541622Y142381D01*
X541205Y142131D01*
X540830Y142048D01*
Y143798D01*
G01Y146023D02*
X543330D01*
X542830Y145523D01*
G01X540830D02*
Y146523D01*
G01X556743Y115583D02*
Y118083D01*
X555702D01*
X555368Y117958D01*
X555160Y117791D01*
X555077Y117458D01*
X555160Y117125D01*
X555410Y116916D01*
X555702Y116791D01*
X556743D01*
G01X555702D02*
X555077Y115583D01*
G01X552810D02*
Y118083D01*
X553310Y117583D01*
G01Y115583D02*
X552310D01*
G01X550793D02*
Y118083D01*
X549710Y116000D01*
X548627Y118083D01*
Y115583D01*
G01X547402Y116625D02*
X547110Y116916D01*
X546860Y117083D01*
X546527Y117166D01*
X546235Y117083D01*
X546027Y116916D01*
X545860Y116666D01*
X545818Y116375D01*
X545860Y116125D01*
X546027Y115875D01*
X546277Y115666D01*
X546568Y115583D01*
X546902Y115666D01*
X547193Y115916D01*
X547360Y116291D01*
X547402Y116708D01*
X547318Y117250D01*
X547193Y117541D01*
X546985Y117833D01*
X546693Y118041D01*
X546402Y118083D01*
X546110Y118000D01*
X545902Y117791D01*
G01X567900Y153817D02*
X570400D01*
Y154858D01*
X570275Y155192D01*
X570108Y155400D01*
X569775Y155483D01*
X569442Y155400D01*
X569233Y155150D01*
X569108Y154858D01*
Y153817D01*
G01Y154858D02*
X567900Y155483D01*
G01X568942Y156958D02*
X569233Y157250D01*
X569400Y157500D01*
X569483Y157833D01*
X569400Y158125D01*
X569233Y158333D01*
X568983Y158500D01*
X568692Y158542D01*
X568442Y158500D01*
X568192Y158333D01*
X567983Y158083D01*
X567900Y157792D01*
X567983Y157458D01*
X568233Y157167D01*
X568608Y157000D01*
X569025Y156958D01*
X569567Y157042D01*
X569858Y157167D01*
X570150Y157375D01*
X570358Y157667D01*
X570400Y157958D01*
X570317Y158250D01*
X570108Y158458D01*
G01X570400Y159600D02*
X567900Y160183D01*
X570400Y160850D01*
X567900Y161517D01*
X570400Y162100D01*
G01X567900Y164450D02*
X570400D01*
X568608Y162908D01*
Y164992D01*
G01X568192Y166342D02*
X567983Y166633D01*
X567900Y166967D01*
X567983Y167300D01*
X568233Y167592D01*
X568608Y167800D01*
X568983Y167883D01*
X569442D01*
X569817Y167800D01*
X570150Y167592D01*
X570317Y167342D01*
X570400Y167050D01*
X570317Y166717D01*
X570150Y166467D01*
X569900Y166300D01*
X569567Y166217D01*
X569275Y166300D01*
X568983Y166508D01*
X568817Y166758D01*
X568775Y167050D01*
X568858Y167383D01*
X569067Y167633D01*
X569442Y167883D01*
G01X556937Y146883D02*
Y145091D01*
X556770Y144716D01*
X556437Y144466D01*
X556020Y144383D01*
X555603Y144466D01*
X555270Y144716D01*
X555103Y145091D01*
Y146883D01*
G01X552920Y144383D02*
Y146883D01*
X553420Y146383D01*
G01Y144383D02*
X552420D01*
G01X551070Y146883D02*
X550487Y144383D01*
X549820Y146883D01*
X549153Y144383D01*
X548570Y146883D01*
G01X547637Y144883D02*
X547387Y144591D01*
X547053Y144425D01*
X546678Y144383D01*
X546345Y144425D01*
X546012Y144633D01*
X545803Y144883D01*
X545762Y145133D01*
X545845Y145425D01*
X546137Y145633D01*
X546428Y145716D01*
X546803D01*
G01X546428D02*
X546178Y145841D01*
X545970Y146050D01*
X545887Y146300D01*
X545970Y146550D01*
X546178Y146758D01*
X546553Y146883D01*
X546928Y146841D01*
X547303Y146675D01*
G01X585463Y154890D02*
X585713Y155015D01*
X586005Y155098D01*
X586338D01*
X586713Y154973D01*
X587005Y154765D01*
X587213Y154515D01*
X587380Y154098D01*
X587422Y153723D01*
X587338Y153348D01*
X587213Y153098D01*
X586963Y152848D01*
X586672Y152681D01*
X586380Y152598D01*
X586088D01*
X585797Y152681D01*
X585547Y152806D01*
X585338Y152973D01*
G01X584113Y152598D02*
Y155098D01*
X583072D01*
X582738Y154973D01*
X582530Y154806D01*
X582447Y154473D01*
X582530Y154140D01*
X582780Y153931D01*
X583072Y153806D01*
X584113D01*
G01X583072D02*
X582447Y152598D01*
G01X580180D02*
Y155098D01*
X580680Y154598D01*
G01Y152598D02*
X579680D01*
G01X577913Y155098D02*
Y152598D01*
X576247D01*
G01X573480D02*
Y155098D01*
X575022Y153306D01*
X572938D01*
G01X571280Y122044D02*
X571530Y122169D01*
X571822Y122252D01*
X572155D01*
X572530Y122127D01*
X572822Y121919D01*
X573030Y121669D01*
X573197Y121252D01*
X573239Y120877D01*
X573155Y120502D01*
X573030Y120252D01*
X572780Y120002D01*
X572489Y119835D01*
X572197Y119752D01*
X571905D01*
X571614Y119835D01*
X571364Y119960D01*
X571155Y120127D01*
G01X569930Y119752D02*
Y122252D01*
X568889D01*
X568555Y122127D01*
X568347Y121960D01*
X568264Y121627D01*
X568347Y121294D01*
X568597Y121085D01*
X568889Y120960D01*
X569930D01*
G01X568889D02*
X568264Y119752D01*
G01X565997D02*
Y122252D01*
X566497Y121752D01*
G01Y119752D02*
X565497D01*
G01X563980D02*
Y122252D01*
X562897Y120169D01*
X561814Y122252D01*
Y119752D01*
G01X560589Y121835D02*
X560339Y122085D01*
X560047Y122210D01*
X559714Y122252D01*
X559297Y122169D01*
X559005Y121960D01*
X558922Y121710D01*
X558964Y121460D01*
X559130Y121252D01*
X559964Y120835D01*
X560339Y120544D01*
X560589Y120127D01*
X560672Y119752D01*
X558922D01*
G01X556683Y121900D02*
Y119400D01*
X555017D01*
G01X552750D02*
Y121900D01*
X553250Y121400D01*
G01Y119400D02*
X552250D01*
G01X550733D02*
Y121900D01*
X549650Y119817D01*
X548567Y121900D01*
Y119400D01*
G01X547342Y121483D02*
X547092Y121733D01*
X546800Y121858D01*
X546467Y121900D01*
X546050Y121817D01*
X545758Y121608D01*
X545675Y121358D01*
X545717Y121108D01*
X545883Y120900D01*
X546717Y120483D01*
X547092Y120192D01*
X547342Y119775D01*
X547425Y119400D01*
X545675D01*
G01X604098Y167077D02*
Y169577D01*
X603057D01*
X602723Y169452D01*
X602515Y169285D01*
X602432Y168952D01*
X602515Y168619D01*
X602765Y168410D01*
X603057Y168285D01*
X604098D01*
G01X603057D02*
X602432Y167077D01*
G01X600165D02*
Y169577D01*
X600665Y169077D01*
G01Y167077D02*
X599665D01*
G01X597898Y169577D02*
Y167077D01*
X596232D01*
G01X593965D02*
Y169577D01*
X594465Y169077D01*
G01Y167077D02*
X593465D01*
G01X590865D02*
Y169577D01*
X591365Y169077D01*
G01Y167077D02*
X590365D01*
G01X604098Y163577D02*
Y166077D01*
X603057D01*
X602723Y165952D01*
X602515Y165785D01*
X602432Y165452D01*
X602515Y165119D01*
X602765Y164910D01*
X603057Y164785D01*
X604098D01*
G01X603057D02*
X602432Y163577D01*
G01X600165D02*
Y166077D01*
X600665Y165577D01*
G01Y163577D02*
X599665D01*
G01X597898Y166077D02*
Y163577D01*
X596232D01*
G01X593965D02*
Y166077D01*
X594465Y165577D01*
G01Y163577D02*
X593465D01*
G01X590365D02*
Y166077D01*
X591907Y164285D01*
X589823D01*
G01X604098Y159577D02*
Y162077D01*
X603057D01*
X602723Y161952D01*
X602515Y161785D01*
X602432Y161452D01*
X602515Y161119D01*
X602765Y160910D01*
X603057Y160785D01*
X604098D01*
G01X603057D02*
X602432Y159577D01*
G01X600165D02*
Y162077D01*
X600665Y161577D01*
G01Y159577D02*
X599665D01*
G01X597898Y162077D02*
Y159577D01*
X596232D01*
G01X593965D02*
Y162077D01*
X594465Y161577D01*
G01Y159577D02*
X593465D01*
G01X590865D02*
X590573Y159619D01*
X590240Y159744D01*
X590032Y159952D01*
X589948Y160244D01*
X590032Y160535D01*
X590282Y160785D01*
X590657Y160910D01*
X591073D01*
X591323Y160994D01*
X591532Y161202D01*
X591615Y161494D01*
X591490Y161785D01*
X591198Y161994D01*
X590865Y162077D01*
X590532Y161994D01*
X590240Y161785D01*
X590115Y161494D01*
X590198Y161202D01*
X590407Y160994D01*
X590657Y160910D01*
X591073D01*
X591448Y160785D01*
X591698Y160535D01*
X591782Y160244D01*
X591698Y159952D01*
X591490Y159744D01*
X591157Y159619D01*
X590865Y159577D01*
G01X605013Y190944D02*
Y193444D01*
X603972D01*
X603638Y193319D01*
X603430Y193152D01*
X603347Y192819D01*
X603430Y192486D01*
X603680Y192277D01*
X603972Y192152D01*
X605013D01*
G01X603972D02*
X603347Y190944D01*
G01X601080D02*
Y193444D01*
X601580Y192944D01*
G01Y190944D02*
X600580D01*
G01X598813Y193444D02*
Y190944D01*
X597147D01*
G01X594880D02*
Y193444D01*
X595380Y192944D01*
G01Y190944D02*
X594380D01*
G01X592572Y193027D02*
X592322Y193277D01*
X592030Y193402D01*
X591697Y193444D01*
X591280Y193361D01*
X590988Y193152D01*
X590905Y192902D01*
X590947Y192652D01*
X591113Y192444D01*
X591947Y192027D01*
X592322Y191736D01*
X592572Y191319D01*
X592655Y190944D01*
X590905D01*
G01X604963Y183260D02*
Y185760D01*
X603922D01*
X603588Y185635D01*
X603380Y185468D01*
X603297Y185135D01*
X603380Y184802D01*
X603630Y184593D01*
X603922Y184468D01*
X604963D01*
G01X603922D02*
X603297Y183260D01*
G01X601030D02*
Y185760D01*
X601530Y185260D01*
G01Y183260D02*
X600530D01*
G01X598763Y185760D02*
Y183260D01*
X597097D01*
G01X594830D02*
Y185760D01*
X595330Y185260D01*
G01Y183260D02*
X594330D01*
G01X592438Y183552D02*
X592147Y183343D01*
X591813Y183260D01*
X591480Y183343D01*
X591188Y183593D01*
X590980Y183968D01*
X590897Y184343D01*
Y184802D01*
X590980Y185177D01*
X591188Y185510D01*
X591438Y185677D01*
X591730Y185760D01*
X592063Y185677D01*
X592313Y185510D01*
X592480Y185260D01*
X592563Y184927D01*
X592480Y184635D01*
X592272Y184343D01*
X592022Y184177D01*
X591730Y184135D01*
X591397Y184218D01*
X591147Y184427D01*
X590897Y184802D01*
G01X604653Y179100D02*
Y181600D01*
X603612D01*
X603278Y181475D01*
X603070Y181308D01*
X602987Y180975D01*
X603070Y180642D01*
X603320Y180433D01*
X603612Y180308D01*
X604653D01*
G01X603612D02*
X602987Y179100D01*
G01X600720D02*
Y181600D01*
X601220Y181100D01*
G01Y179100D02*
X600220D01*
G01X598453Y181600D02*
Y179100D01*
X596787D01*
G01X595312Y181183D02*
X595062Y181433D01*
X594770Y181558D01*
X594437Y181600D01*
X594020Y181517D01*
X593728Y181308D01*
X593645Y181058D01*
X593687Y180808D01*
X593853Y180600D01*
X594687Y180183D01*
X595062Y179892D01*
X595312Y179475D01*
X595395Y179100D01*
X593645D01*
G01X592212Y181183D02*
X591962Y181433D01*
X591670Y181558D01*
X591337Y181600D01*
X590920Y181517D01*
X590628Y181308D01*
X590545Y181058D01*
X590587Y180808D01*
X590753Y180600D01*
X591587Y180183D01*
X591962Y179892D01*
X592212Y179475D01*
X592295Y179100D01*
X590545D01*
G01X565963Y162344D02*
Y164844D01*
X564922D01*
X564588Y164719D01*
X564380Y164552D01*
X564297Y164219D01*
X564380Y163886D01*
X564630Y163677D01*
X564922Y163552D01*
X565963D01*
G01X564922D02*
X564297Y162344D01*
G01X562822Y163386D02*
X562530Y163677D01*
X562280Y163844D01*
X561947Y163927D01*
X561655Y163844D01*
X561447Y163677D01*
X561280Y163427D01*
X561238Y163136D01*
X561280Y162886D01*
X561447Y162636D01*
X561697Y162427D01*
X561988Y162344D01*
X562322Y162427D01*
X562613Y162677D01*
X562780Y163052D01*
X562822Y163469D01*
X562738Y164011D01*
X562613Y164302D01*
X562405Y164594D01*
X562113Y164802D01*
X561822Y164844D01*
X561530Y164761D01*
X561322Y164552D01*
G01X560180Y164844D02*
X559597Y162344D01*
X558930Y164844D01*
X558263Y162344D01*
X557680Y164844D01*
G01X555913Y162344D02*
X555830Y162886D01*
X555705Y163344D01*
X555538Y163761D01*
X555330Y164219D01*
X554997Y164844D01*
X556663D01*
G01X566063Y158644D02*
Y161144D01*
X565022D01*
X564688Y161019D01*
X564480Y160852D01*
X564397Y160519D01*
X564480Y160186D01*
X564730Y159977D01*
X565022Y159852D01*
X566063D01*
G01X565022D02*
X564397Y158644D01*
G01X562922Y159686D02*
X562630Y159977D01*
X562380Y160144D01*
X562047Y160227D01*
X561755Y160144D01*
X561547Y159977D01*
X561380Y159727D01*
X561338Y159436D01*
X561380Y159186D01*
X561547Y158936D01*
X561797Y158727D01*
X562088Y158644D01*
X562422Y158727D01*
X562713Y158977D01*
X562880Y159352D01*
X562922Y159769D01*
X562838Y160311D01*
X562713Y160602D01*
X562505Y160894D01*
X562213Y161102D01*
X561922Y161144D01*
X561630Y161061D01*
X561422Y160852D01*
G01X560280Y161144D02*
X559697Y158644D01*
X559030Y161144D01*
X558363Y158644D01*
X557780Y161144D01*
G01X555430Y158644D02*
Y161144D01*
X556972Y159352D01*
X554888D01*
G01X586933Y181707D02*
Y184207D01*
X585892D01*
X585558Y184082D01*
X585350Y183915D01*
X585267Y183582D01*
X585350Y183249D01*
X585600Y183040D01*
X585892Y182915D01*
X586933D01*
G01X585892D02*
X585267Y181707D01*
G01X583000D02*
Y184207D01*
X583500Y183707D01*
G01Y181707D02*
X582500D01*
G01X580733Y184207D02*
Y181707D01*
X579067D01*
G01X577592Y182749D02*
X577300Y183040D01*
X577050Y183207D01*
X576717Y183290D01*
X576425Y183207D01*
X576217Y183040D01*
X576050Y182790D01*
X576008Y182499D01*
X576050Y182249D01*
X576217Y181999D01*
X576467Y181790D01*
X576758Y181707D01*
X577092Y181790D01*
X577383Y182040D01*
X577550Y182415D01*
X577592Y182832D01*
X577508Y183374D01*
X577383Y183665D01*
X577175Y183957D01*
X576883Y184165D01*
X576592Y184207D01*
X576300Y184124D01*
X576092Y183915D01*
G01X567143Y169096D02*
Y171596D01*
X566102D01*
X565768Y171471D01*
X565560Y171304D01*
X565477Y170971D01*
X565560Y170638D01*
X565810Y170429D01*
X566102Y170304D01*
X567143D01*
G01X566102D02*
X565477Y169096D01*
G01X564002Y170138D02*
X563710Y170429D01*
X563460Y170596D01*
X563127Y170679D01*
X562835Y170596D01*
X562627Y170429D01*
X562460Y170179D01*
X562418Y169888D01*
X562460Y169638D01*
X562627Y169388D01*
X562877Y169179D01*
X563168Y169096D01*
X563502Y169179D01*
X563793Y169429D01*
X563960Y169804D01*
X564002Y170221D01*
X563918Y170763D01*
X563793Y171054D01*
X563585Y171346D01*
X563293Y171554D01*
X563002Y171596D01*
X562710Y171513D01*
X562502Y171304D01*
G01X561360Y171596D02*
X560777Y169096D01*
X560110Y171596D01*
X559443Y169096D01*
X558860Y171596D01*
G01X557010Y169096D02*
X556718Y169138D01*
X556385Y169263D01*
X556177Y169471D01*
X556093Y169763D01*
X556177Y170054D01*
X556427Y170304D01*
X556802Y170429D01*
X557218D01*
X557468Y170513D01*
X557677Y170721D01*
X557760Y171013D01*
X557635Y171304D01*
X557343Y171513D01*
X557010Y171596D01*
X556677Y171513D01*
X556385Y171304D01*
X556260Y171013D01*
X556343Y170721D01*
X556552Y170513D01*
X556802Y170429D01*
X557218D01*
X557593Y170304D01*
X557843Y170054D01*
X557927Y169763D01*
X557843Y169471D01*
X557635Y169263D01*
X557302Y169138D01*
X557010Y169096D01*
G01X565440Y176777D02*
Y179277D01*
X564399D01*
X564065Y179152D01*
X563857Y178985D01*
X563774Y178652D01*
X563857Y178319D01*
X564107Y178110D01*
X564399Y177985D01*
X565440D01*
G01X564399D02*
X563774Y176777D01*
G01X562299Y177819D02*
X562007Y178110D01*
X561757Y178277D01*
X561424Y178360D01*
X561132Y178277D01*
X560924Y178110D01*
X560757Y177860D01*
X560715Y177569D01*
X560757Y177319D01*
X560924Y177069D01*
X561174Y176860D01*
X561465Y176777D01*
X561799Y176860D01*
X562090Y177110D01*
X562257Y177485D01*
X562299Y177902D01*
X562215Y178444D01*
X562090Y178735D01*
X561882Y179027D01*
X561590Y179235D01*
X561299Y179277D01*
X561007Y179194D01*
X560799Y178985D01*
G01X559657Y179277D02*
X559074Y176777D01*
X558407Y179277D01*
X557740Y176777D01*
X557157Y179277D01*
G01X556224Y177152D02*
X555974Y176944D01*
X555682Y176819D01*
X555307Y176777D01*
X554932Y176860D01*
X554640Y177027D01*
X554432Y177319D01*
X554390Y177652D01*
X554474Y177985D01*
X554682Y178194D01*
X554974Y178360D01*
X555265Y178402D01*
X555557Y178360D01*
X555932Y178194D01*
X555807Y179277D01*
X554682D01*
G01X548847Y168844D02*
X551347D01*
Y169885D01*
X551222Y170219D01*
X551055Y170427D01*
X550722Y170510D01*
X550389Y170427D01*
X550180Y170177D01*
X550055Y169885D01*
Y168844D01*
G01Y169885D02*
X548847Y170510D01*
G01X549889Y171985D02*
X550180Y172277D01*
X550347Y172527D01*
X550430Y172860D01*
X550347Y173152D01*
X550180Y173360D01*
X549930Y173527D01*
X549639Y173569D01*
X549389Y173527D01*
X549139Y173360D01*
X548930Y173110D01*
X548847Y172819D01*
X548930Y172485D01*
X549180Y172194D01*
X549555Y172027D01*
X549972Y171985D01*
X550514Y172069D01*
X550805Y172194D01*
X551097Y172402D01*
X551305Y172694D01*
X551347Y172985D01*
X551264Y173277D01*
X551055Y173485D01*
G01X551347Y174627D02*
X548847Y175210D01*
X551347Y175877D01*
X548847Y176544D01*
X551347Y177127D01*
G01X548847Y178977D02*
X551347D01*
X550847Y178477D01*
G01X548847D02*
Y179477D01*
G01X551347Y182077D02*
X551264Y181744D01*
X551055Y181494D01*
X550805Y181327D01*
X550472Y181202D01*
X550097Y181160D01*
X549722Y181202D01*
X549389Y181327D01*
X549139Y181494D01*
X548930Y181744D01*
X548847Y182077D01*
X548930Y182410D01*
X549139Y182660D01*
X549389Y182827D01*
X549722Y182952D01*
X550097Y182994D01*
X550472Y182952D01*
X550805Y182827D01*
X551055Y182660D01*
X551264Y182410D01*
X551347Y182077D01*
G01X543927Y171946D02*
X546427D01*
Y172987D01*
X546302Y173321D01*
X546135Y173529D01*
X545802Y173612D01*
X545469Y173529D01*
X545260Y173279D01*
X545135Y172987D01*
Y171946D01*
G01Y172987D02*
X543927Y173612D01*
G01X544969Y175087D02*
X545260Y175379D01*
X545427Y175629D01*
X545510Y175962D01*
X545427Y176254D01*
X545260Y176462D01*
X545010Y176629D01*
X544719Y176671D01*
X544469Y176629D01*
X544219Y176462D01*
X544010Y176212D01*
X543927Y175921D01*
X544010Y175587D01*
X544260Y175296D01*
X544635Y175129D01*
X545052Y175087D01*
X545594Y175171D01*
X545885Y175296D01*
X546177Y175504D01*
X546385Y175796D01*
X546427Y176087D01*
X546344Y176379D01*
X546135Y176587D01*
G01X546427Y177729D02*
X543927Y178312D01*
X546427Y178979D01*
X543927Y179646D01*
X546427Y180229D01*
G01X544219Y181371D02*
X544010Y181662D01*
X543927Y181996D01*
X544010Y182329D01*
X544260Y182621D01*
X544635Y182829D01*
X545010Y182912D01*
X545469D01*
X545844Y182829D01*
X546177Y182621D01*
X546344Y182371D01*
X546427Y182079D01*
X546344Y181746D01*
X546177Y181496D01*
X545927Y181329D01*
X545594Y181246D01*
X545302Y181329D01*
X545010Y181537D01*
X544844Y181787D01*
X544802Y182079D01*
X544885Y182412D01*
X545094Y182662D01*
X545469Y182912D01*
G01X567921Y171005D02*
X570421D01*
Y172046D01*
X570296Y172380D01*
X570129Y172588D01*
X569796Y172671D01*
X569463Y172588D01*
X569254Y172338D01*
X569129Y172046D01*
Y171005D01*
G01Y172046D02*
X567921Y172671D01*
G01Y174938D02*
X570421D01*
X569921Y174438D01*
G01X567921D02*
Y175438D01*
G01X570421Y177205D02*
X567921D01*
Y178871D01*
G01X568213Y180430D02*
X568004Y180721D01*
X567921Y181055D01*
X568004Y181388D01*
X568254Y181680D01*
X568629Y181888D01*
X569004Y181971D01*
X569463D01*
X569838Y181888D01*
X570171Y181680D01*
X570338Y181430D01*
X570421Y181138D01*
X570338Y180805D01*
X570171Y180555D01*
X569921Y180388D01*
X569588Y180305D01*
X569296Y180388D01*
X569004Y180596D01*
X568838Y180846D01*
X568796Y181138D01*
X568879Y181471D01*
X569088Y181721D01*
X569463Y181971D01*
G01X604988Y189577D02*
Y187785D01*
X604821Y187410D01*
X604488Y187160D01*
X604071Y187077D01*
X603654Y187160D01*
X603321Y187410D01*
X603154Y187785D01*
Y189577D01*
G01X600971Y187077D02*
Y189577D01*
X601471Y189077D01*
G01Y187077D02*
X600471D01*
G01X598704Y189577D02*
Y187077D01*
X597038D01*
G01X595563Y189160D02*
X595313Y189410D01*
X595021Y189535D01*
X594688Y189577D01*
X594271Y189494D01*
X593979Y189285D01*
X593896Y189035D01*
X593938Y188785D01*
X594104Y188577D01*
X594938Y188160D01*
X595313Y187869D01*
X595563Y187452D01*
X595646Y187077D01*
X593896D01*
G01X585393Y188232D02*
X585643Y188357D01*
X585935Y188440D01*
X586268D01*
X586643Y188315D01*
X586935Y188107D01*
X587143Y187857D01*
X587310Y187440D01*
X587352Y187065D01*
X587268Y186690D01*
X587143Y186440D01*
X586893Y186190D01*
X586602Y186023D01*
X586310Y185940D01*
X586018D01*
X585727Y186023D01*
X585477Y186148D01*
X585268Y186315D01*
G01X583210Y185940D02*
Y188440D01*
X583710Y187940D01*
G01Y185940D02*
X582710D01*
G01X580943Y188440D02*
Y185940D01*
X579277D01*
G01X576510D02*
Y188440D01*
X578052Y186648D01*
X575968D01*
G01X585363Y170069D02*
X585613Y170194D01*
X585905Y170277D01*
X586238D01*
X586613Y170152D01*
X586905Y169944D01*
X587113Y169694D01*
X587280Y169277D01*
X587322Y168902D01*
X587238Y168527D01*
X587113Y168277D01*
X586863Y168027D01*
X586572Y167860D01*
X586280Y167777D01*
X585988D01*
X585697Y167860D01*
X585447Y167985D01*
X585238Y168152D01*
G01X584013Y167777D02*
Y170277D01*
X582972D01*
X582638Y170152D01*
X582430Y169985D01*
X582347Y169652D01*
X582430Y169319D01*
X582680Y169110D01*
X582972Y168985D01*
X584013D01*
G01X582972D02*
X582347Y167777D01*
G01X580080D02*
Y170277D01*
X580580Y169777D01*
G01Y167777D02*
X579580D01*
G01X577813Y170277D02*
Y167777D01*
X576147D01*
G01X573880D02*
Y170277D01*
X574380Y169777D01*
G01Y167777D02*
X573380D01*
G01X585563Y166136D02*
X585813Y166261D01*
X586105Y166344D01*
X586438D01*
X586813Y166219D01*
X587105Y166011D01*
X587313Y165761D01*
X587480Y165344D01*
X587522Y164969D01*
X587438Y164594D01*
X587313Y164344D01*
X587063Y164094D01*
X586772Y163927D01*
X586480Y163844D01*
X586188D01*
X585897Y163927D01*
X585647Y164052D01*
X585438Y164219D01*
G01X584213Y163844D02*
Y166344D01*
X583172D01*
X582838Y166219D01*
X582630Y166052D01*
X582547Y165719D01*
X582630Y165386D01*
X582880Y165177D01*
X583172Y165052D01*
X584213D01*
G01X583172D02*
X582547Y163844D01*
G01X580280D02*
Y166344D01*
X580780Y165844D01*
G01Y163844D02*
X579780D01*
G01X578013Y166344D02*
Y163844D01*
X576347D01*
G01X574872Y165927D02*
X574622Y166177D01*
X574330Y166302D01*
X573997Y166344D01*
X573580Y166261D01*
X573288Y166052D01*
X573205Y165802D01*
X573247Y165552D01*
X573413Y165344D01*
X574247Y164927D01*
X574622Y164636D01*
X574872Y164219D01*
X574955Y163844D01*
X573205D01*
G01X585563Y162236D02*
X585813Y162361D01*
X586105Y162444D01*
X586438D01*
X586813Y162319D01*
X587105Y162111D01*
X587313Y161861D01*
X587480Y161444D01*
X587522Y161069D01*
X587438Y160694D01*
X587313Y160444D01*
X587063Y160194D01*
X586772Y160027D01*
X586480Y159944D01*
X586188D01*
X585897Y160027D01*
X585647Y160152D01*
X585438Y160319D01*
G01X584213Y159944D02*
Y162444D01*
X583172D01*
X582838Y162319D01*
X582630Y162152D01*
X582547Y161819D01*
X582630Y161486D01*
X582880Y161277D01*
X583172Y161152D01*
X584213D01*
G01X583172D02*
X582547Y159944D01*
G01X580280D02*
Y162444D01*
X580780Y161944D01*
G01Y159944D02*
X579780D01*
G01X578013Y162444D02*
Y159944D01*
X576347D01*
G01X574997Y160444D02*
X574747Y160152D01*
X574413Y159986D01*
X574038Y159944D01*
X573705Y159986D01*
X573372Y160194D01*
X573163Y160444D01*
X573122Y160694D01*
X573205Y160986D01*
X573497Y161194D01*
X573788Y161277D01*
X574163D01*
G01X573788D02*
X573538Y161402D01*
X573330Y161611D01*
X573247Y161861D01*
X573330Y162111D01*
X573538Y162319D01*
X573913Y162444D01*
X574288Y162402D01*
X574663Y162236D01*
G01X568000Y184258D02*
X570500D01*
Y185842D01*
G01X569292Y185258D02*
Y184258D01*
G01X568000Y188150D02*
X570500D01*
X570000Y187650D01*
G01X568000D02*
Y188650D01*
G01X570500Y190417D02*
X568000D01*
Y192083D01*
G01Y194350D02*
X570500D01*
X570000Y193850D01*
G01X568000D02*
Y194850D01*
G01X563361Y182024D02*
X563694Y182066D01*
X563986Y182232D01*
X564236Y182482D01*
X564403Y182774D01*
X564486Y183107D01*
Y183441D01*
X564403Y183774D01*
X564236Y184066D01*
X563986Y184316D01*
X563694Y184482D01*
X563361Y184524D01*
X563028Y184482D01*
X562736Y184316D01*
X562486Y184066D01*
X562319Y183774D01*
X562236Y183441D01*
Y183107D01*
X562319Y182774D01*
X562486Y182482D01*
X562736Y182232D01*
X563028Y182066D01*
X563361Y182024D01*
G01X563028Y182691D02*
X562528Y182024D01*
G01X561053Y183066D02*
X560761Y183357D01*
X560511Y183524D01*
X560178Y183607D01*
X559886Y183524D01*
X559678Y183357D01*
X559511Y183107D01*
X559469Y182816D01*
X559511Y182566D01*
X559678Y182316D01*
X559928Y182107D01*
X560219Y182024D01*
X560553Y182107D01*
X560844Y182357D01*
X561011Y182732D01*
X561053Y183149D01*
X560969Y183691D01*
X560844Y183982D01*
X560636Y184274D01*
X560344Y184482D01*
X560053Y184524D01*
X559761Y184441D01*
X559553Y184232D01*
G01X558411Y184524D02*
X557828Y182024D01*
X557161Y184524D01*
X556494Y182024D01*
X555911Y184524D01*
G01X554853Y184107D02*
X554603Y184357D01*
X554311Y184482D01*
X553978Y184524D01*
X553561Y184441D01*
X553269Y184232D01*
X553186Y183982D01*
X553228Y183732D01*
X553394Y183524D01*
X554228Y183107D01*
X554603Y182816D01*
X554853Y182399D01*
X554936Y182024D01*
X553186D01*
G01X585433Y496142D02*
X585683Y496267D01*
X585975Y496350D01*
X586308D01*
X586683Y496225D01*
X586975Y496017D01*
X587183Y495767D01*
X587350Y495350D01*
X587392Y494975D01*
X587308Y494600D01*
X587183Y494350D01*
X586933Y494100D01*
X586642Y493933D01*
X586350Y493850D01*
X586058D01*
X585767Y493933D01*
X585517Y494058D01*
X585308Y494225D01*
G01X583333Y493850D02*
X583250Y494392D01*
X583125Y494850D01*
X582958Y495267D01*
X582750Y495725D01*
X582417Y496350D01*
X584083D01*
G01X581233Y493850D02*
Y496350D01*
X580150Y494267D01*
X579067Y496350D01*
Y493850D01*
G01X577842Y494892D02*
X577550Y495183D01*
X577300Y495350D01*
X576967Y495433D01*
X576675Y495350D01*
X576467Y495183D01*
X576300Y494933D01*
X576258Y494642D01*
X576300Y494392D01*
X576467Y494142D01*
X576717Y493933D01*
X577008Y493850D01*
X577342Y493933D01*
X577633Y494183D01*
X577800Y494558D01*
X577842Y494975D01*
X577758Y495517D01*
X577633Y495808D01*
X577425Y496100D01*
X577133Y496308D01*
X576842Y496350D01*
X576550Y496267D01*
X576342Y496058D01*
G01X567500Y492500D02*
X590075D01*
G01X567500Y474500D02*
X590072D01*
G01X567500D02*
Y477195D01*
G01Y492500D02*
Y489802D01*
G01X602864Y489800D02*
Y493362D01*
X590068D01*
Y489800D01*
G01X602864Y477200D02*
Y473409D01*
X590068D01*
Y477200D01*
G01X596599Y567252D02*
X596724Y567002D01*
X596807Y566710D01*
Y566377D01*
X596682Y566002D01*
X596474Y565710D01*
X596224Y565502D01*
X595807Y565335D01*
X595432Y565293D01*
X595057Y565377D01*
X594807Y565502D01*
X594557Y565752D01*
X594390Y566043D01*
X594307Y566335D01*
Y566627D01*
X594390Y566918D01*
X594515Y567168D01*
X594682Y567377D01*
G01X594307Y569352D02*
X594849Y569435D01*
X595307Y569560D01*
X595724Y569727D01*
X596182Y569935D01*
X596807Y570268D01*
Y568602D01*
G01Y571702D02*
X594307D01*
Y573368D01*
G01X595349Y574843D02*
X595640Y575135D01*
X595807Y575385D01*
X595890Y575718D01*
X595807Y576010D01*
X595640Y576218D01*
X595390Y576385D01*
X595099Y576427D01*
X594849Y576385D01*
X594599Y576218D01*
X594390Y575968D01*
X594307Y575677D01*
X594390Y575343D01*
X594640Y575052D01*
X595015Y574885D01*
X595432Y574843D01*
X595974Y574927D01*
X596265Y575052D01*
X596557Y575260D01*
X596765Y575552D01*
X596807Y575843D01*
X596724Y576135D01*
X596515Y576343D01*
G01X592940Y567229D02*
X593065Y566979D01*
X593148Y566687D01*
Y566354D01*
X593023Y565979D01*
X592815Y565687D01*
X592565Y565479D01*
X592148Y565312D01*
X591773Y565270D01*
X591398Y565354D01*
X591148Y565479D01*
X590898Y565729D01*
X590731Y566020D01*
X590648Y566312D01*
Y566604D01*
X590731Y566895D01*
X590856Y567145D01*
X591023Y567354D01*
G01X590648Y569329D02*
X591190Y569412D01*
X591648Y569537D01*
X592065Y569704D01*
X592523Y569912D01*
X593148Y570245D01*
Y568579D01*
G01Y571679D02*
X590648D01*
Y573345D01*
G01Y575529D02*
X591190Y575612D01*
X591648Y575737D01*
X592065Y575904D01*
X592523Y576112D01*
X593148Y576445D01*
Y574779D01*
G01X604233Y616992D02*
X604483Y617117D01*
X604775Y617200D01*
X605108D01*
X605483Y617075D01*
X605775Y616867D01*
X605983Y616617D01*
X606150Y616200D01*
X606192Y615825D01*
X606108Y615450D01*
X605983Y615200D01*
X605733Y614950D01*
X605442Y614783D01*
X605150Y614700D01*
X604858D01*
X604567Y614783D01*
X604317Y614908D01*
X604108Y615075D01*
G01X602133Y614700D02*
X602050Y615242D01*
X601925Y615700D01*
X601758Y616117D01*
X601550Y616575D01*
X601217Y617200D01*
X602883D01*
G01X599783D02*
Y614700D01*
X598117D01*
G01X596767Y615200D02*
X596517Y614908D01*
X596183Y614742D01*
X595808Y614700D01*
X595475Y614742D01*
X595142Y614950D01*
X594933Y615200D01*
X594892Y615450D01*
X594975Y615742D01*
X595267Y615950D01*
X595558Y616033D01*
X595933D01*
G01X595558D02*
X595308Y616158D01*
X595100Y616367D01*
X595017Y616617D01*
X595100Y616867D01*
X595308Y617075D01*
X595683Y617200D01*
X596058Y617158D01*
X596433Y616992D01*
G01X600571Y658679D02*
X567871D01*
Y639979D01*
X600571D01*
Y658679D01*
G01X725000Y-54300D02*
Y-57300D01*
X723000D01*
G01X720400D02*
Y-54300D01*
X721000Y-54900D01*
G01Y-57300D02*
X719800D01*
G01X716200D02*
Y-54300D01*
X718050Y-56450D01*
X715550D01*
G01X710600Y-54300D02*
Y-57300D01*
X708600D01*
G01X706000D02*
Y-54300D01*
X706600Y-54900D01*
G01Y-57300D02*
X705400D01*
G01X703350Y-54800D02*
X703050Y-54500D01*
X702700Y-54350D01*
X702300Y-54300D01*
X701800Y-54400D01*
X701450Y-54650D01*
X701350Y-54950D01*
X701400Y-55250D01*
X701600Y-55500D01*
X702600Y-56000D01*
X703050Y-56350D01*
X703350Y-56850D01*
X703450Y-57300D01*
X701350D01*
G01X696200Y-54300D02*
Y-57300D01*
X694200D01*
G01X691600D02*
Y-54300D01*
X692200Y-54900D01*
G01Y-57300D02*
X691000D01*
G01X688000Y-54300D02*
X688400Y-54400D01*
X688700Y-54650D01*
X688900Y-54950D01*
X689050Y-55350D01*
X689100Y-55800D01*
X689050Y-56250D01*
X688900Y-56650D01*
X688700Y-56950D01*
X688400Y-57200D01*
X688000Y-57300D01*
X687600Y-57200D01*
X687300Y-56950D01*
X687100Y-56650D01*
X686950Y-56250D01*
X686900Y-55800D01*
X686950Y-55350D01*
X687100Y-54950D01*
X687300Y-54650D01*
X687600Y-54400D01*
X688000Y-54300D01*
G01X681800D02*
Y-57300D01*
X679800D01*
G01X678300Y-56850D02*
X678000Y-57100D01*
X677650Y-57250D01*
X677200Y-57300D01*
X676750Y-57200D01*
X676400Y-57000D01*
X676150Y-56650D01*
X676100Y-56250D01*
X676200Y-55850D01*
X676450Y-55600D01*
X676800Y-55400D01*
X677150Y-55350D01*
X677500Y-55400D01*
X677950Y-55600D01*
X677800Y-54300D01*
X676450D01*
G01X671000D02*
Y-57300D01*
X669000D01*
G01X667500Y-56700D02*
X667200Y-57050D01*
X666800Y-57250D01*
X666350Y-57300D01*
X665950Y-57250D01*
X665550Y-57000D01*
X665300Y-56700D01*
X665250Y-56400D01*
X665350Y-56050D01*
X665700Y-55800D01*
X666050Y-55700D01*
X666500D01*
G01X666050D02*
X665750Y-55550D01*
X665500Y-55300D01*
X665400Y-55000D01*
X665500Y-54700D01*
X665750Y-54450D01*
X666200Y-54300D01*
X666650Y-54350D01*
X667100Y-54550D01*
G01X660200Y-54300D02*
Y-57300D01*
X658200D01*
G01X655600D02*
Y-54300D01*
X656200Y-54900D01*
G01Y-57300D02*
X655000D01*
G01X653500Y-58300D02*
X650500D01*
G01X648500Y-57300D02*
X648400Y-56650D01*
X648250Y-56100D01*
X648050Y-55600D01*
X647800Y-55050D01*
X647400Y-54300D01*
X649400D01*
G01X645900Y-56700D02*
X645600Y-57050D01*
X645200Y-57250D01*
X644750Y-57300D01*
X644350Y-57250D01*
X643950Y-57000D01*
X643700Y-56700D01*
X643650Y-56400D01*
X643750Y-56050D01*
X644100Y-55800D01*
X644450Y-55700D01*
X644900D01*
G01X644450D02*
X644150Y-55550D01*
X643900Y-55300D01*
X643800Y-55000D01*
X643900Y-54700D01*
X644150Y-54450D01*
X644600Y-54300D01*
X645050Y-54350D01*
X645500Y-54550D01*
G01X641200Y-57300D02*
X641600Y-57250D01*
X641950Y-57050D01*
X642250Y-56750D01*
X642450Y-56400D01*
X642550Y-56000D01*
Y-55600D01*
X642450Y-55200D01*
X642250Y-54850D01*
X641950Y-54550D01*
X641600Y-54350D01*
X641200Y-54300D01*
X640800Y-54350D01*
X640450Y-54550D01*
X640150Y-54850D01*
X639950Y-55200D01*
X639850Y-55600D01*
Y-56000D01*
X639950Y-56400D01*
X640150Y-56750D01*
X640450Y-57050D01*
X640800Y-57250D01*
X641200Y-57300D01*
G01X638450D02*
Y-54300D01*
G01Y-55750D02*
X638200Y-55500D01*
X637950Y-55350D01*
X637550Y-55300D01*
X637250Y-55350D01*
X636900Y-55550D01*
X636750Y-55850D01*
Y-57300D01*
G01X635500D02*
Y-55300D01*
G01Y-55850D02*
X635350Y-55600D01*
X635100Y-55400D01*
X634750Y-55300D01*
X634400Y-55400D01*
X634150Y-55600D01*
X634000Y-55850D01*
Y-57300D01*
G01Y-55850D02*
X633850Y-55600D01*
X633600Y-55400D01*
X633250Y-55300D01*
X632900Y-55400D01*
X632650Y-55600D01*
X632500Y-55900D01*
Y-57300D01*
G01X631900Y-58300D02*
X628900D01*
G01X627900Y-57300D02*
Y-54300D01*
X626900D01*
X626500Y-54450D01*
X626200Y-54650D01*
X625950Y-54950D01*
X625750Y-55300D01*
X625700Y-55800D01*
X625750Y-56300D01*
X625950Y-56650D01*
X626200Y-56950D01*
X626500Y-57150D01*
X626900Y-57300D01*
X627900D01*
G01X661313Y5493D02*
X661438Y5243D01*
X661521Y4951D01*
Y4618D01*
X661396Y4243D01*
X661188Y3951D01*
X660938Y3743D01*
X660521Y3576D01*
X660146Y3534D01*
X659771Y3618D01*
X659521Y3743D01*
X659271Y3993D01*
X659104Y4284D01*
X659021Y4576D01*
Y4868D01*
X659104Y5159D01*
X659229Y5409D01*
X659396Y5618D01*
G01X660063Y6884D02*
X660354Y7176D01*
X660521Y7426D01*
X660604Y7759D01*
X660521Y8051D01*
X660354Y8259D01*
X660104Y8426D01*
X659813Y8468D01*
X659563Y8426D01*
X659313Y8259D01*
X659104Y8009D01*
X659021Y7718D01*
X659104Y7384D01*
X659354Y7093D01*
X659729Y6926D01*
X660146Y6884D01*
X660688Y6968D01*
X660979Y7093D01*
X661271Y7301D01*
X661479Y7593D01*
X661521Y7884D01*
X661438Y8176D01*
X661229Y8384D01*
G01X661521Y9526D02*
X659021Y10109D01*
X661521Y10776D01*
X659021Y11443D01*
X661521Y12026D01*
G01X659021Y13876D02*
X661521D01*
X661021Y13376D01*
G01X659021D02*
Y14376D01*
G01X661104Y16184D02*
X661354Y16434D01*
X661479Y16726D01*
X661521Y17059D01*
X661438Y17476D01*
X661229Y17768D01*
X660979Y17851D01*
X660729Y17809D01*
X660521Y17643D01*
X660104Y16809D01*
X659813Y16434D01*
X659396Y16184D01*
X659021Y16101D01*
Y17851D01*
G01X663700Y30417D02*
X666200D01*
Y31458D01*
X666075Y31792D01*
X665908Y32000D01*
X665575Y32083D01*
X665242Y32000D01*
X665033Y31750D01*
X664908Y31458D01*
Y30417D01*
G01Y31458D02*
X663700Y32083D01*
G01X664742Y33558D02*
X665033Y33850D01*
X665200Y34100D01*
X665283Y34433D01*
X665200Y34725D01*
X665033Y34933D01*
X664783Y35100D01*
X664492Y35142D01*
X664242Y35100D01*
X663992Y34933D01*
X663783Y34683D01*
X663700Y34392D01*
X663783Y34058D01*
X664033Y33767D01*
X664408Y33600D01*
X664825Y33558D01*
X665367Y33642D01*
X665658Y33767D01*
X665950Y33975D01*
X666158Y34267D01*
X666200Y34558D01*
X666117Y34850D01*
X665908Y35058D01*
G01X666200Y36533D02*
X664408D01*
X664033Y36700D01*
X663783Y37033D01*
X663700Y37450D01*
X663783Y37867D01*
X664033Y38200D01*
X664408Y38367D01*
X666200D01*
G01X664200Y39633D02*
X663908Y39883D01*
X663742Y40217D01*
X663700Y40592D01*
X663742Y40925D01*
X663950Y41258D01*
X664200Y41467D01*
X664450Y41508D01*
X664742Y41425D01*
X664950Y41133D01*
X665033Y40842D01*
Y40467D01*
G01Y40842D02*
X665158Y41092D01*
X665367Y41300D01*
X665617Y41383D01*
X665867Y41300D01*
X666075Y41092D01*
X666200Y40717D01*
X666158Y40342D01*
X665992Y39967D01*
G01X630533Y-16900D02*
Y-14400D01*
X629492D01*
X629158Y-14525D01*
X628950Y-14692D01*
X628867Y-15025D01*
X628950Y-15358D01*
X629200Y-15567D01*
X629492Y-15692D01*
X630533D01*
G01X629492D02*
X628867Y-16900D01*
G01X627392Y-15858D02*
X627100Y-15567D01*
X626850Y-15400D01*
X626517Y-15317D01*
X626225Y-15400D01*
X626017Y-15567D01*
X625850Y-15817D01*
X625808Y-16108D01*
X625850Y-16358D01*
X626017Y-16608D01*
X626267Y-16817D01*
X626558Y-16900D01*
X626892Y-16817D01*
X627183Y-16567D01*
X627350Y-16192D01*
X627392Y-15775D01*
X627308Y-15233D01*
X627183Y-14942D01*
X626975Y-14650D01*
X626683Y-14442D01*
X626392Y-14400D01*
X626100Y-14483D01*
X625892Y-14692D01*
G01X624417Y-14400D02*
Y-16192D01*
X624250Y-16567D01*
X623917Y-16817D01*
X623500Y-16900D01*
X623083Y-16817D01*
X622750Y-16567D01*
X622583Y-16192D01*
Y-14400D01*
G01X620400Y-16900D02*
Y-14400D01*
X620900Y-14900D01*
G01Y-16900D02*
X619900D01*
G01X616800D02*
Y-14400D01*
X618342Y-16192D01*
X616258D01*
G01X646733Y-20900D02*
Y-18400D01*
X645692D01*
X645358Y-18525D01*
X645150Y-18692D01*
X645067Y-19025D01*
X645150Y-19358D01*
X645400Y-19567D01*
X645692Y-19692D01*
X646733D01*
G01X645692D02*
X645067Y-20900D01*
G01X643592Y-19858D02*
X643300Y-19567D01*
X643050Y-19400D01*
X642717Y-19317D01*
X642425Y-19400D01*
X642217Y-19567D01*
X642050Y-19817D01*
X642008Y-20108D01*
X642050Y-20358D01*
X642217Y-20608D01*
X642467Y-20817D01*
X642758Y-20900D01*
X643092Y-20817D01*
X643383Y-20567D01*
X643550Y-20192D01*
X643592Y-19775D01*
X643508Y-19233D01*
X643383Y-18942D01*
X643175Y-18650D01*
X642883Y-18442D01*
X642592Y-18400D01*
X642300Y-18483D01*
X642092Y-18692D01*
G01X640617Y-18400D02*
Y-20192D01*
X640450Y-20567D01*
X640117Y-20817D01*
X639700Y-20900D01*
X639283Y-20817D01*
X638950Y-20567D01*
X638783Y-20192D01*
Y-18400D01*
G01X636600Y-20900D02*
Y-18400D01*
X637100Y-18900D01*
G01Y-20900D02*
X636100D01*
G01X633583D02*
X633500Y-20358D01*
X633375Y-19900D01*
X633208Y-19483D01*
X633000Y-19025D01*
X632667Y-18400D01*
X634333D01*
G01X630883Y-20900D02*
Y-18400D01*
X629842D01*
X629508Y-18525D01*
X629300Y-18692D01*
X629217Y-19025D01*
X629300Y-19358D01*
X629550Y-19567D01*
X629842Y-19692D01*
X630883D01*
G01X629842D02*
X629217Y-20900D01*
G01X627742Y-19858D02*
X627450Y-19567D01*
X627200Y-19400D01*
X626867Y-19317D01*
X626575Y-19400D01*
X626367Y-19567D01*
X626200Y-19817D01*
X626158Y-20108D01*
X626200Y-20358D01*
X626367Y-20608D01*
X626617Y-20817D01*
X626908Y-20900D01*
X627242Y-20817D01*
X627533Y-20567D01*
X627700Y-20192D01*
X627742Y-19775D01*
X627658Y-19233D01*
X627533Y-18942D01*
X627325Y-18650D01*
X627033Y-18442D01*
X626742Y-18400D01*
X626450Y-18483D01*
X626242Y-18692D01*
G01X624767Y-18400D02*
Y-20192D01*
X624600Y-20567D01*
X624267Y-20817D01*
X623850Y-20900D01*
X623433Y-20817D01*
X623100Y-20567D01*
X622933Y-20192D01*
Y-18400D01*
G01X620750Y-20900D02*
Y-18400D01*
X621250Y-18900D01*
G01Y-20900D02*
X620250D01*
G01X617650D02*
X617358Y-20858D01*
X617025Y-20733D01*
X616817Y-20525D01*
X616733Y-20233D01*
X616817Y-19942D01*
X617067Y-19692D01*
X617442Y-19567D01*
X617858D01*
X618108Y-19483D01*
X618317Y-19275D01*
X618400Y-18983D01*
X618275Y-18692D01*
X617983Y-18483D01*
X617650Y-18400D01*
X617317Y-18483D01*
X617025Y-18692D01*
X616900Y-18983D01*
X616983Y-19275D01*
X617192Y-19483D01*
X617442Y-19567D01*
X617858D01*
X618233Y-19692D01*
X618483Y-19942D01*
X618567Y-20233D01*
X618483Y-20525D01*
X618275Y-20733D01*
X617942Y-20858D01*
X617650Y-20900D01*
G01X646588Y-16599D02*
Y-14099D01*
X645547D01*
X645213Y-14224D01*
X645005Y-14391D01*
X644922Y-14724D01*
X645005Y-15057D01*
X645255Y-15266D01*
X645547Y-15391D01*
X646588D01*
G01X645547D02*
X644922Y-16599D01*
G01X643447Y-15557D02*
X643155Y-15266D01*
X642905Y-15099D01*
X642572Y-15016D01*
X642280Y-15099D01*
X642072Y-15266D01*
X641905Y-15516D01*
X641863Y-15807D01*
X641905Y-16057D01*
X642072Y-16307D01*
X642322Y-16516D01*
X642613Y-16599D01*
X642947Y-16516D01*
X643238Y-16266D01*
X643405Y-15891D01*
X643447Y-15474D01*
X643363Y-14932D01*
X643238Y-14641D01*
X643030Y-14349D01*
X642738Y-14141D01*
X642447Y-14099D01*
X642155Y-14182D01*
X641947Y-14391D01*
G01X640472Y-14099D02*
Y-15891D01*
X640305Y-16266D01*
X639972Y-16516D01*
X639555Y-16599D01*
X639138Y-16516D01*
X638805Y-16266D01*
X638638Y-15891D01*
Y-14099D01*
G01X636455Y-16599D02*
Y-14099D01*
X636955Y-14599D01*
G01Y-16599D02*
X635955D01*
G01X634272Y-16099D02*
X634022Y-16391D01*
X633688Y-16557D01*
X633313Y-16599D01*
X632980Y-16557D01*
X632647Y-16349D01*
X632438Y-16099D01*
X632397Y-15849D01*
X632480Y-15557D01*
X632772Y-15349D01*
X633063Y-15266D01*
X633438D01*
G01X633063D02*
X632813Y-15141D01*
X632605Y-14932D01*
X632522Y-14682D01*
X632605Y-14432D01*
X632813Y-14224D01*
X633188Y-14099D01*
X633563Y-14141D01*
X633938Y-14307D01*
G01X675348Y8316D02*
X675598Y8441D01*
X675890Y8524D01*
X676223D01*
X676598Y8399D01*
X676890Y8191D01*
X677098Y7941D01*
X677265Y7524D01*
X677307Y7149D01*
X677223Y6774D01*
X677098Y6524D01*
X676848Y6274D01*
X676557Y6107D01*
X676265Y6024D01*
X675973D01*
X675682Y6107D01*
X675432Y6232D01*
X675223Y6399D01*
G01X673957Y7066D02*
X673665Y7357D01*
X673415Y7524D01*
X673082Y7607D01*
X672790Y7524D01*
X672582Y7357D01*
X672415Y7107D01*
X672373Y6816D01*
X672415Y6566D01*
X672582Y6316D01*
X672832Y6107D01*
X673123Y6024D01*
X673457Y6107D01*
X673748Y6357D01*
X673915Y6732D01*
X673957Y7149D01*
X673873Y7691D01*
X673748Y7982D01*
X673540Y8274D01*
X673248Y8482D01*
X672957Y8524D01*
X672665Y8441D01*
X672457Y8232D01*
G01X670982Y8524D02*
Y6732D01*
X670815Y6357D01*
X670482Y6107D01*
X670065Y6024D01*
X669648Y6107D01*
X669315Y6357D01*
X669148Y6732D01*
Y8524D01*
G01X666965Y6024D02*
Y8524D01*
X667465Y8024D01*
G01Y6024D02*
X666465D01*
G01X663365D02*
Y8524D01*
X664907Y6732D01*
X662823D01*
G01X660980Y21559D02*
X661230Y21684D01*
X661522Y21767D01*
X661855D01*
X662230Y21642D01*
X662522Y21434D01*
X662730Y21184D01*
X662897Y20767D01*
X662939Y20392D01*
X662855Y20017D01*
X662730Y19767D01*
X662480Y19517D01*
X662189Y19350D01*
X661897Y19267D01*
X661605D01*
X661314Y19350D01*
X661064Y19475D01*
X660855Y19642D01*
G01X659589Y20309D02*
X659297Y20600D01*
X659047Y20767D01*
X658714Y20850D01*
X658422Y20767D01*
X658214Y20600D01*
X658047Y20350D01*
X658005Y20059D01*
X658047Y19809D01*
X658214Y19559D01*
X658464Y19350D01*
X658755Y19267D01*
X659089Y19350D01*
X659380Y19600D01*
X659547Y19975D01*
X659589Y20392D01*
X659505Y20934D01*
X659380Y21225D01*
X659172Y21517D01*
X658880Y21725D01*
X658589Y21767D01*
X658297Y21684D01*
X658089Y21475D01*
G01X656614Y21767D02*
Y19975D01*
X656447Y19600D01*
X656114Y19350D01*
X655697Y19267D01*
X655280Y19350D01*
X654947Y19600D01*
X654780Y19975D01*
Y21767D01*
G01X652597Y19267D02*
Y21767D01*
X653097Y21267D01*
G01Y19267D02*
X652097D01*
G01X650414Y19767D02*
X650164Y19475D01*
X649830Y19309D01*
X649455Y19267D01*
X649122Y19309D01*
X648789Y19517D01*
X648580Y19767D01*
X648539Y20017D01*
X648622Y20309D01*
X648914Y20517D01*
X649205Y20600D01*
X649580D01*
G01X649205D02*
X648955Y20725D01*
X648747Y20934D01*
X648664Y21184D01*
X648747Y21434D01*
X648955Y21642D01*
X649330Y21767D01*
X649705Y21725D01*
X650080Y21559D01*
G01X617833Y-11408D02*
X618083Y-11283D01*
X618375Y-11200D01*
X618708D01*
X619083Y-11325D01*
X619375Y-11533D01*
X619583Y-11783D01*
X619750Y-12200D01*
X619792Y-12575D01*
X619708Y-12950D01*
X619583Y-13200D01*
X619333Y-13450D01*
X619042Y-13617D01*
X618750Y-13700D01*
X618458D01*
X618167Y-13617D01*
X617917Y-13492D01*
X617708Y-13325D01*
G01X615733Y-13700D02*
X615650Y-13158D01*
X615525Y-12700D01*
X615358Y-12283D01*
X615150Y-11825D01*
X614817Y-11200D01*
X616483D01*
G01X613467D02*
Y-12992D01*
X613300Y-13367D01*
X612967Y-13617D01*
X612550Y-13700D01*
X612133Y-13617D01*
X611800Y-13367D01*
X611633Y-12992D01*
Y-11200D01*
G01X610367Y-13325D02*
X610117Y-13533D01*
X609825Y-13658D01*
X609450Y-13700D01*
X609075Y-13617D01*
X608783Y-13450D01*
X608575Y-13158D01*
X608533Y-12825D01*
X608617Y-12492D01*
X608825Y-12283D01*
X609117Y-12117D01*
X609408Y-12075D01*
X609700Y-12117D01*
X610075Y-12283D01*
X609950Y-11200D01*
X608825D01*
G01X662183Y1642D02*
X662433Y1767D01*
X662725Y1850D01*
X663058D01*
X663433Y1725D01*
X663725Y1517D01*
X663933Y1267D01*
X664100Y850D01*
X664142Y475D01*
X664058Y100D01*
X663933Y-150D01*
X663683Y-400D01*
X663392Y-567D01*
X663100Y-650D01*
X662808D01*
X662517Y-567D01*
X662267Y-442D01*
X662058Y-275D01*
G01X659500Y-650D02*
Y1850D01*
X661042Y58D01*
X658958D01*
G01X656650Y600D02*
X655817D01*
Y-150D01*
X656067Y-400D01*
X656358Y-567D01*
X656775Y-650D01*
X657192Y-567D01*
X657483Y-400D01*
X657733Y-150D01*
X657900Y142D01*
X657983Y475D01*
Y767D01*
X657900Y1017D01*
X657733Y1308D01*
X657483Y1558D01*
X657233Y1725D01*
X656900Y1850D01*
X656608D01*
X656275Y1767D01*
X656025Y1600D01*
G01X654592Y1433D02*
X654342Y1683D01*
X654050Y1808D01*
X653717Y1850D01*
X653300Y1767D01*
X653008Y1558D01*
X652925Y1308D01*
X652967Y1058D01*
X653133Y850D01*
X653967Y433D01*
X654342Y142D01*
X654592Y-275D01*
X654675Y-650D01*
X652925D01*
G01X651492Y1433D02*
X651242Y1683D01*
X650950Y1808D01*
X650617Y1850D01*
X650200Y1767D01*
X649908Y1558D01*
X649825Y1308D01*
X649867Y1058D01*
X650033Y850D01*
X650867Y433D01*
X651242Y142D01*
X651492Y-275D01*
X651575Y-650D01*
X649825D01*
G01X626578Y-1417D02*
X626348Y-1107D01*
X626080Y-952D01*
X625773Y-900D01*
X625390Y-1003D01*
X625122Y-1262D01*
X625045Y-1572D01*
X625083Y-1882D01*
X625237Y-2140D01*
X626003Y-2657D01*
X626348Y-3018D01*
X626578Y-3535D01*
X626655Y-4000D01*
X625045D01*
G01X622750D02*
X622482Y-3948D01*
X622175Y-3793D01*
X621983Y-3535D01*
X621907Y-3173D01*
X621983Y-2812D01*
X622213Y-2502D01*
X622558Y-2347D01*
X622942D01*
X623172Y-2243D01*
X623363Y-1985D01*
X623440Y-1623D01*
X623325Y-1262D01*
X623057Y-1003D01*
X622750Y-900D01*
X622443Y-1003D01*
X622175Y-1262D01*
X622060Y-1623D01*
X622137Y-1985D01*
X622328Y-2243D01*
X622558Y-2347D01*
X622942D01*
X623287Y-2502D01*
X623517Y-2812D01*
X623593Y-3173D01*
X623517Y-3535D01*
X623325Y-3793D01*
X623018Y-3948D01*
X622750Y-4000D01*
G01X619650D02*
X619382Y-3948D01*
X619075Y-3793D01*
X618883Y-3535D01*
X618807Y-3173D01*
X618883Y-2812D01*
X619113Y-2502D01*
X619458Y-2347D01*
X619842D01*
X620072Y-2243D01*
X620263Y-1985D01*
X620340Y-1623D01*
X620225Y-1262D01*
X619957Y-1003D01*
X619650Y-900D01*
X619343Y-1003D01*
X619075Y-1262D01*
X618960Y-1623D01*
X619037Y-1985D01*
X619228Y-2243D01*
X619458Y-2347D01*
X619842D01*
X620187Y-2502D01*
X620417Y-2812D01*
X620493Y-3173D01*
X620417Y-3535D01*
X620225Y-3793D01*
X619918Y-3948D01*
X619650Y-4000D01*
G01X626850Y27500D02*
Y30600D01*
X627310Y29980D01*
G01Y27500D02*
X626390D01*
G01X623290D02*
Y30600D01*
X624708Y28378D01*
X622792D01*
G01X620190Y27500D02*
Y30600D01*
X621608Y28378D01*
X619692D01*
G01X621376Y283D02*
X645766D01*
Y25873D01*
X621376D01*
G01X674183Y95000D02*
Y97500D01*
X673142D01*
X672808Y97375D01*
X672600Y97208D01*
X672517Y96875D01*
X672600Y96542D01*
X672850Y96333D01*
X673142Y96208D01*
X674183D01*
G01X673142D02*
X672517Y95000D01*
G01X671042Y96042D02*
X670750Y96333D01*
X670500Y96500D01*
X670167Y96583D01*
X669875Y96500D01*
X669667Y96333D01*
X669500Y96083D01*
X669458Y95792D01*
X669500Y95542D01*
X669667Y95292D01*
X669917Y95083D01*
X670208Y95000D01*
X670542Y95083D01*
X670833Y95333D01*
X671000Y95708D01*
X671042Y96125D01*
X670958Y96667D01*
X670833Y96958D01*
X670625Y97250D01*
X670333Y97458D01*
X670042Y97500D01*
X669750Y97417D01*
X669542Y97208D01*
G01X667150Y97500D02*
Y95000D01*
G01X668108Y97500D02*
X666192D01*
G01X663550Y95000D02*
Y97500D01*
X665092Y95708D01*
X663008D01*
G01X659783Y95200D02*
Y97700D01*
X658742D01*
X658408Y97575D01*
X658200Y97408D01*
X658117Y97075D01*
X658200Y96742D01*
X658450Y96533D01*
X658742Y96408D01*
X659783D01*
G01X658742D02*
X658117Y95200D01*
G01X656642Y96242D02*
X656350Y96533D01*
X656100Y96700D01*
X655767Y96783D01*
X655475Y96700D01*
X655267Y96533D01*
X655100Y96283D01*
X655058Y95992D01*
X655100Y95742D01*
X655267Y95492D01*
X655517Y95283D01*
X655808Y95200D01*
X656142Y95283D01*
X656433Y95533D01*
X656600Y95908D01*
X656642Y96325D01*
X656558Y96867D01*
X656433Y97158D01*
X656225Y97450D01*
X655933Y97658D01*
X655642Y97700D01*
X655350Y97617D01*
X655142Y97408D01*
G01X652750Y97700D02*
Y95200D01*
G01X653708Y97700D02*
X651792D01*
G01X650567Y95700D02*
X650317Y95408D01*
X649983Y95242D01*
X649608Y95200D01*
X649275Y95242D01*
X648942Y95450D01*
X648733Y95700D01*
X648692Y95950D01*
X648775Y96242D01*
X649067Y96450D01*
X649358Y96533D01*
X649733D01*
G01X649358D02*
X649108Y96658D01*
X648900Y96867D01*
X648817Y97117D01*
X648900Y97367D01*
X649108Y97575D01*
X649483Y97700D01*
X649858Y97658D01*
X650233Y97492D01*
G01X627578Y36583D02*
X627348Y36893D01*
X627080Y37048D01*
X626773Y37100D01*
X626390Y36997D01*
X626122Y36738D01*
X626045Y36428D01*
X626083Y36118D01*
X626237Y35860D01*
X627003Y35343D01*
X627348Y34982D01*
X627578Y34465D01*
X627655Y34000D01*
X626045D01*
G01X623750D02*
X623482Y34052D01*
X623175Y34207D01*
X622983Y34465D01*
X622907Y34827D01*
X622983Y35188D01*
X623213Y35498D01*
X623558Y35653D01*
X623942D01*
X624172Y35757D01*
X624363Y36015D01*
X624440Y36377D01*
X624325Y36738D01*
X624057Y36997D01*
X623750Y37100D01*
X623443Y36997D01*
X623175Y36738D01*
X623060Y36377D01*
X623137Y36015D01*
X623328Y35757D01*
X623558Y35653D01*
X623942D01*
X624287Y35498D01*
X624517Y35188D01*
X624593Y34827D01*
X624517Y34465D01*
X624325Y34207D01*
X624018Y34052D01*
X623750Y34000D01*
G01X620650D02*
X620382Y34052D01*
X620075Y34207D01*
X619883Y34465D01*
X619807Y34827D01*
X619883Y35188D01*
X620113Y35498D01*
X620458Y35653D01*
X620842D01*
X621072Y35757D01*
X621263Y36015D01*
X621340Y36377D01*
X621225Y36738D01*
X620957Y36997D01*
X620650Y37100D01*
X620343Y36997D01*
X620075Y36738D01*
X619960Y36377D01*
X620037Y36015D01*
X620228Y35757D01*
X620458Y35653D01*
X620842D01*
X621187Y35498D01*
X621417Y35188D01*
X621493Y34827D01*
X621417Y34465D01*
X621225Y34207D01*
X620918Y34052D01*
X620650Y34000D01*
G01X626850Y65000D02*
Y68100D01*
X627310Y67480D01*
G01Y65000D02*
X626390D01*
G01X623290D02*
Y68100D01*
X624708Y65878D01*
X622792D01*
G01X620190Y65000D02*
Y68100D01*
X621608Y65878D01*
X619692D01*
G01X621376Y38083D02*
X645766D01*
Y63673D01*
X621376D01*
G01X627078Y74583D02*
X626848Y74893D01*
X626580Y75048D01*
X626273Y75100D01*
X625890Y74997D01*
X625622Y74738D01*
X625545Y74428D01*
X625583Y74118D01*
X625737Y73860D01*
X626503Y73343D01*
X626848Y72982D01*
X627078Y72465D01*
X627155Y72000D01*
X625545D01*
G01X623250D02*
X622982Y72052D01*
X622675Y72207D01*
X622483Y72465D01*
X622407Y72827D01*
X622483Y73188D01*
X622713Y73498D01*
X623058Y73653D01*
X623442D01*
X623672Y73757D01*
X623863Y74015D01*
X623940Y74377D01*
X623825Y74738D01*
X623557Y74997D01*
X623250Y75100D01*
X622943Y74997D01*
X622675Y74738D01*
X622560Y74377D01*
X622637Y74015D01*
X622828Y73757D01*
X623058Y73653D01*
X623442D01*
X623787Y73498D01*
X624017Y73188D01*
X624093Y72827D01*
X624017Y72465D01*
X623825Y72207D01*
X623518Y72052D01*
X623250Y72000D01*
G01X620150D02*
X619882Y72052D01*
X619575Y72207D01*
X619383Y72465D01*
X619307Y72827D01*
X619383Y73188D01*
X619613Y73498D01*
X619958Y73653D01*
X620342D01*
X620572Y73757D01*
X620763Y74015D01*
X620840Y74377D01*
X620725Y74738D01*
X620457Y74997D01*
X620150Y75100D01*
X619843Y74997D01*
X619575Y74738D01*
X619460Y74377D01*
X619537Y74015D01*
X619728Y73757D01*
X619958Y73653D01*
X620342D01*
X620687Y73498D01*
X620917Y73188D01*
X620993Y72827D01*
X620917Y72465D01*
X620725Y72207D01*
X620418Y72052D01*
X620150Y72000D01*
G01X621376Y75883D02*
X645766D01*
Y101473D01*
X621376D01*
G01X674183Y98500D02*
Y101000D01*
X673142D01*
X672808Y100875D01*
X672600Y100708D01*
X672517Y100375D01*
X672600Y100042D01*
X672850Y99833D01*
X673142Y99708D01*
X674183D01*
G01X673142D02*
X672517Y98500D01*
G01X671042Y99542D02*
X670750Y99833D01*
X670500Y100000D01*
X670167Y100083D01*
X669875Y100000D01*
X669667Y99833D01*
X669500Y99583D01*
X669458Y99292D01*
X669500Y99042D01*
X669667Y98792D01*
X669917Y98583D01*
X670208Y98500D01*
X670542Y98583D01*
X670833Y98833D01*
X671000Y99208D01*
X671042Y99625D01*
X670958Y100167D01*
X670833Y100458D01*
X670625Y100750D01*
X670333Y100958D01*
X670042Y101000D01*
X669750Y100917D01*
X669542Y100708D01*
G01X667150Y101000D02*
Y98500D01*
G01X668108Y101000D02*
X666192D01*
G01X664050Y98500D02*
Y101000D01*
X664550Y100500D01*
G01Y98500D02*
X663550D01*
G01X659783Y98700D02*
Y101200D01*
X658742D01*
X658408Y101075D01*
X658200Y100908D01*
X658117Y100575D01*
X658200Y100242D01*
X658450Y100033D01*
X658742Y99908D01*
X659783D01*
G01X658742D02*
X658117Y98700D01*
G01X656642Y99742D02*
X656350Y100033D01*
X656100Y100200D01*
X655767Y100283D01*
X655475Y100200D01*
X655267Y100033D01*
X655100Y99783D01*
X655058Y99492D01*
X655100Y99242D01*
X655267Y98992D01*
X655517Y98783D01*
X655808Y98700D01*
X656142Y98783D01*
X656433Y99033D01*
X656600Y99408D01*
X656642Y99825D01*
X656558Y100367D01*
X656433Y100658D01*
X656225Y100950D01*
X655933Y101158D01*
X655642Y101200D01*
X655350Y101117D01*
X655142Y100908D01*
G01X652750Y101200D02*
Y98700D01*
G01X653708Y101200D02*
X651792D01*
G01X650442Y100783D02*
X650192Y101033D01*
X649900Y101158D01*
X649567Y101200D01*
X649150Y101117D01*
X648858Y100908D01*
X648775Y100658D01*
X648817Y100408D01*
X648983Y100200D01*
X649817Y99783D01*
X650192Y99492D01*
X650442Y99075D01*
X650525Y98700D01*
X648775D01*
G01X619450Y103000D02*
Y106100D01*
X619910Y105480D01*
G01Y103000D02*
X618990D01*
G01X615890D02*
Y106100D01*
X617308Y103878D01*
X615392D01*
G01X612790Y103000D02*
Y106100D01*
X614208Y103878D01*
X612292D01*
G01X640459Y212217D02*
X640584Y211967D01*
X640667Y211675D01*
Y211342D01*
X640542Y210967D01*
X640334Y210675D01*
X640084Y210467D01*
X639667Y210300D01*
X639292Y210258D01*
X638917Y210342D01*
X638667Y210467D01*
X638417Y210717D01*
X638250Y211008D01*
X638167Y211300D01*
Y211592D01*
X638250Y211883D01*
X638375Y212133D01*
X638542Y212342D01*
G01X639209Y213608D02*
X639500Y213900D01*
X639667Y214150D01*
X639750Y214483D01*
X639667Y214775D01*
X639500Y214983D01*
X639250Y215150D01*
X638959Y215192D01*
X638709Y215150D01*
X638459Y214983D01*
X638250Y214733D01*
X638167Y214442D01*
X638250Y214108D01*
X638500Y213817D01*
X638875Y213650D01*
X639292Y213608D01*
X639834Y213692D01*
X640125Y213817D01*
X640417Y214025D01*
X640625Y214317D01*
X640667Y214608D01*
X640584Y214900D01*
X640375Y215108D01*
G01X638167Y216667D02*
X640667D01*
Y217708D01*
X640542Y218042D01*
X640375Y218250D01*
X640042Y218333D01*
X639709Y218250D01*
X639500Y218000D01*
X639375Y217708D01*
Y216667D01*
G01Y217708D02*
X638167Y218333D01*
G01Y220600D02*
X640667D01*
X640167Y220100D01*
G01X638167D02*
Y221100D01*
G01X640250Y222908D02*
X640500Y223158D01*
X640625Y223450D01*
X640667Y223783D01*
X640584Y224200D01*
X640375Y224492D01*
X640125Y224575D01*
X639875Y224533D01*
X639667Y224367D01*
X639250Y223533D01*
X638959Y223158D01*
X638542Y222908D01*
X638167Y222825D01*
Y224575D01*
G01X643136Y211200D02*
Y207638D01*
X655932D01*
Y211200D01*
G01X678500Y208500D02*
X655925D01*
G01X631377Y277982D02*
X633877D01*
Y279023D01*
X633752Y279357D01*
X633585Y279565D01*
X633252Y279648D01*
X632919Y279565D01*
X632710Y279315D01*
X632585Y279023D01*
Y277982D01*
G01Y279023D02*
X631377Y279648D01*
G01X632419Y281123D02*
X632710Y281415D01*
X632877Y281665D01*
X632960Y281998D01*
X632877Y282290D01*
X632710Y282498D01*
X632460Y282665D01*
X632169Y282707D01*
X631919Y282665D01*
X631669Y282498D01*
X631460Y282248D01*
X631377Y281957D01*
X631460Y281623D01*
X631710Y281332D01*
X632085Y281165D01*
X632502Y281123D01*
X633044Y281207D01*
X633335Y281332D01*
X633627Y281540D01*
X633835Y281832D01*
X633877Y282123D01*
X633794Y282415D01*
X633585Y282623D01*
G01X631377Y284182D02*
X633877D01*
Y285182D01*
X633752Y285515D01*
X633460Y285765D01*
X633127Y285848D01*
X632794Y285765D01*
X632544Y285557D01*
X632419Y285182D01*
Y284182D01*
G01X631377Y288615D02*
X633877D01*
X632085Y287073D01*
Y289157D01*
G01X632419Y290423D02*
X632710Y290715D01*
X632877Y290965D01*
X632960Y291298D01*
X632877Y291590D01*
X632710Y291798D01*
X632460Y291965D01*
X632169Y292007D01*
X631919Y291965D01*
X631669Y291798D01*
X631460Y291548D01*
X631377Y291257D01*
X631460Y290923D01*
X631710Y290632D01*
X632085Y290465D01*
X632502Y290423D01*
X633044Y290507D01*
X633335Y290632D01*
X633627Y290840D01*
X633835Y291132D01*
X633877Y291423D01*
X633794Y291715D01*
X633585Y291923D01*
G01X627056Y278254D02*
X629556D01*
Y279295D01*
X629431Y279629D01*
X629264Y279837D01*
X628931Y279920D01*
X628598Y279837D01*
X628389Y279587D01*
X628264Y279295D01*
Y278254D01*
G01Y279295D02*
X627056Y279920D01*
G01Y282104D02*
X627598Y282187D01*
X628056Y282312D01*
X628473Y282479D01*
X628931Y282687D01*
X629556Y283020D01*
Y281354D01*
G01X627056Y284454D02*
X629556D01*
Y285454D01*
X629431Y285787D01*
X629139Y286037D01*
X628806Y286120D01*
X628473Y286037D01*
X628223Y285829D01*
X628098Y285454D01*
Y284454D01*
G01X627556Y287470D02*
X627264Y287720D01*
X627098Y288054D01*
X627056Y288429D01*
X627098Y288762D01*
X627306Y289095D01*
X627556Y289304D01*
X627806Y289345D01*
X628098Y289262D01*
X628306Y288970D01*
X628389Y288679D01*
Y288304D01*
G01Y288679D02*
X628514Y288929D01*
X628723Y289137D01*
X628973Y289220D01*
X629223Y289137D01*
X629431Y288929D01*
X629556Y288554D01*
X629514Y288179D01*
X629348Y287804D01*
G01X629556Y291487D02*
X629473Y291154D01*
X629264Y290904D01*
X629014Y290737D01*
X628681Y290612D01*
X628306Y290570D01*
X627931Y290612D01*
X627598Y290737D01*
X627348Y290904D01*
X627139Y291154D01*
X627056Y291487D01*
X627139Y291820D01*
X627348Y292070D01*
X627598Y292237D01*
X627931Y292362D01*
X628306Y292404D01*
X628681Y292362D01*
X629014Y292237D01*
X629264Y292070D01*
X629473Y291820D01*
X629556Y291487D01*
G01X630584Y270339D02*
Y272839D01*
X629543D01*
X629209Y272714D01*
X629001Y272547D01*
X628918Y272214D01*
X629001Y271881D01*
X629251Y271672D01*
X629543Y271547D01*
X630584D01*
G01X629543D02*
X628918Y270339D01*
G01X626734D02*
X626651Y270881D01*
X626526Y271339D01*
X626359Y271756D01*
X626151Y272214D01*
X625818Y272839D01*
X627484D01*
G01X624384Y270339D02*
Y272839D01*
X623384D01*
X623051Y272714D01*
X622801Y272422D01*
X622718Y272089D01*
X622801Y271756D01*
X623009Y271506D01*
X623384Y271381D01*
X624384D01*
G01X621243Y272422D02*
X620993Y272672D01*
X620701Y272797D01*
X620368Y272839D01*
X619951Y272756D01*
X619659Y272547D01*
X619576Y272297D01*
X619618Y272047D01*
X619784Y271839D01*
X620618Y271422D01*
X620993Y271131D01*
X621243Y270714D01*
X621326Y270339D01*
X619576D01*
G01X617351Y272839D02*
X617684Y272756D01*
X617934Y272547D01*
X618101Y272297D01*
X618226Y271964D01*
X618268Y271589D01*
X618226Y271214D01*
X618101Y270881D01*
X617934Y270631D01*
X617684Y270422D01*
X617351Y270339D01*
X617018Y270422D01*
X616768Y270631D01*
X616601Y270881D01*
X616476Y271214D01*
X616434Y271589D01*
X616476Y271964D01*
X616601Y272297D01*
X616768Y272547D01*
X617018Y272756D01*
X617351Y272839D01*
G01X630718Y274226D02*
Y276726D01*
X629677D01*
X629343Y276601D01*
X629135Y276434D01*
X629052Y276101D01*
X629135Y275768D01*
X629385Y275559D01*
X629677Y275434D01*
X630718D01*
G01X629677D02*
X629052Y274226D01*
G01X626868D02*
X626785Y274768D01*
X626660Y275226D01*
X626493Y275643D01*
X626285Y276101D01*
X625952Y276726D01*
X627618D01*
G01X624518Y274226D02*
Y276726D01*
X623518D01*
X623185Y276601D01*
X622935Y276309D01*
X622852Y275976D01*
X622935Y275643D01*
X623143Y275393D01*
X623518Y275268D01*
X624518D01*
G01X620585Y274226D02*
Y276726D01*
X621085Y276226D01*
G01Y274226D02*
X620085D01*
G01X617485D02*
X617193Y274268D01*
X616860Y274393D01*
X616652Y274601D01*
X616568Y274893D01*
X616652Y275184D01*
X616902Y275434D01*
X617277Y275559D01*
X617693D01*
X617943Y275643D01*
X618152Y275851D01*
X618235Y276143D01*
X618110Y276434D01*
X617818Y276643D01*
X617485Y276726D01*
X617152Y276643D01*
X616860Y276434D01*
X616735Y276143D01*
X616818Y275851D01*
X617027Y275643D01*
X617277Y275559D01*
X617693D01*
X618068Y275434D01*
X618318Y275184D01*
X618402Y274893D01*
X618318Y274601D01*
X618110Y274393D01*
X617777Y274268D01*
X617485Y274226D01*
G01X662466Y259879D02*
X664966D01*
Y260920D01*
X664841Y261254D01*
X664674Y261462D01*
X664341Y261545D01*
X664008Y261462D01*
X663799Y261212D01*
X663674Y260920D01*
Y259879D01*
G01Y260920D02*
X662466Y261545D01*
G01Y263020D02*
X664966D01*
Y264604D01*
G01X663758Y264020D02*
Y263020D01*
G01X662466Y266912D02*
X664966D01*
X664466Y266412D01*
G01X662466D02*
Y267412D01*
G01Y270512D02*
X664966D01*
X663174Y268970D01*
Y271054D01*
G01X634012Y246947D02*
X636512D01*
Y247988D01*
X636387Y248322D01*
X636220Y248530D01*
X635887Y248613D01*
X635554Y248530D01*
X635345Y248280D01*
X635220Y247988D01*
Y246947D01*
G01Y247988D02*
X634012Y248613D01*
G01Y250797D02*
X634554Y250880D01*
X635012Y251005D01*
X635429Y251172D01*
X635887Y251380D01*
X636512Y251713D01*
Y250047D01*
G01X634012Y253147D02*
X636512D01*
Y254188D01*
X636387Y254522D01*
X636220Y254730D01*
X635887Y254813D01*
X635554Y254730D01*
X635345Y254480D01*
X635220Y254188D01*
Y253147D01*
G01Y254188D02*
X634012Y254813D01*
G01Y257080D02*
X636512D01*
X636012Y256580D01*
G01X634012D02*
Y257580D01*
G01X629984Y257958D02*
Y260458D01*
X628943D01*
X628609Y260333D01*
X628401Y260166D01*
X628318Y259833D01*
X628401Y259500D01*
X628651Y259291D01*
X628943Y259166D01*
X629984D01*
G01X628943D02*
X628318Y257958D01*
G01X626843Y259000D02*
X626551Y259291D01*
X626301Y259458D01*
X625968Y259541D01*
X625676Y259458D01*
X625468Y259291D01*
X625301Y259041D01*
X625259Y258750D01*
X625301Y258500D01*
X625468Y258250D01*
X625718Y258041D01*
X626009Y257958D01*
X626343Y258041D01*
X626634Y258291D01*
X626801Y258666D01*
X626843Y259083D01*
X626759Y259625D01*
X626634Y259916D01*
X626426Y260208D01*
X626134Y260416D01*
X625843Y260458D01*
X625551Y260375D01*
X625343Y260166D01*
G01X623784Y257958D02*
Y260458D01*
X622784D01*
X622451Y260333D01*
X622201Y260041D01*
X622118Y259708D01*
X622201Y259375D01*
X622409Y259125D01*
X622784Y259000D01*
X623784D01*
G01X619351Y257958D02*
Y260458D01*
X620893Y258666D01*
X618809D01*
G01X616751Y260458D02*
X617084Y260375D01*
X617334Y260166D01*
X617501Y259916D01*
X617626Y259583D01*
X617668Y259208D01*
X617626Y258833D01*
X617501Y258500D01*
X617334Y258250D01*
X617084Y258041D01*
X616751Y257958D01*
X616418Y258041D01*
X616168Y258250D01*
X616001Y258500D01*
X615876Y258833D01*
X615834Y259208D01*
X615876Y259583D01*
X616001Y259916D01*
X616168Y260166D01*
X616418Y260375D01*
X616751Y260458D01*
G01X629984Y254458D02*
Y256958D01*
X628943D01*
X628609Y256833D01*
X628401Y256666D01*
X628318Y256333D01*
X628401Y256000D01*
X628651Y255791D01*
X628943Y255666D01*
X629984D01*
G01X628943D02*
X628318Y254458D01*
G01X626843Y255500D02*
X626551Y255791D01*
X626301Y255958D01*
X625968Y256041D01*
X625676Y255958D01*
X625468Y255791D01*
X625301Y255541D01*
X625259Y255250D01*
X625301Y255000D01*
X625468Y254750D01*
X625718Y254541D01*
X626009Y254458D01*
X626343Y254541D01*
X626634Y254791D01*
X626801Y255166D01*
X626843Y255583D01*
X626759Y256125D01*
X626634Y256416D01*
X626426Y256708D01*
X626134Y256916D01*
X625843Y256958D01*
X625551Y256875D01*
X625343Y256666D01*
G01X623784Y254458D02*
Y256958D01*
X622784D01*
X622451Y256833D01*
X622201Y256541D01*
X622118Y256208D01*
X622201Y255875D01*
X622409Y255625D01*
X622784Y255500D01*
X623784D01*
G01X619351Y254458D02*
Y256958D01*
X620893Y255166D01*
X618809D01*
G01X616751Y254458D02*
Y256958D01*
X617251Y256458D01*
G01Y254458D02*
X616251D01*
G01X629984Y264958D02*
Y267458D01*
X628943D01*
X628609Y267333D01*
X628401Y267166D01*
X628318Y266833D01*
X628401Y266500D01*
X628651Y266291D01*
X628943Y266166D01*
X629984D01*
G01X628943D02*
X628318Y264958D01*
G01X626843Y266000D02*
X626551Y266291D01*
X626301Y266458D01*
X625968Y266541D01*
X625676Y266458D01*
X625468Y266291D01*
X625301Y266041D01*
X625259Y265750D01*
X625301Y265500D01*
X625468Y265250D01*
X625718Y265041D01*
X626009Y264958D01*
X626343Y265041D01*
X626634Y265291D01*
X626801Y265666D01*
X626843Y266083D01*
X626759Y266625D01*
X626634Y266916D01*
X626426Y267208D01*
X626134Y267416D01*
X625843Y267458D01*
X625551Y267375D01*
X625343Y267166D01*
G01X623784Y264958D02*
Y267458D01*
X622784D01*
X622451Y267333D01*
X622201Y267041D01*
X622118Y266708D01*
X622201Y266375D01*
X622409Y266125D01*
X622784Y266000D01*
X623784D01*
G01X620768Y265458D02*
X620518Y265166D01*
X620184Y265000D01*
X619809Y264958D01*
X619476Y265000D01*
X619143Y265208D01*
X618934Y265458D01*
X618893Y265708D01*
X618976Y266000D01*
X619268Y266208D01*
X619559Y266291D01*
X619934D01*
G01X619559D02*
X619309Y266416D01*
X619101Y266625D01*
X619018Y266875D01*
X619101Y267125D01*
X619309Y267333D01*
X619684Y267458D01*
X620059Y267416D01*
X620434Y267250D01*
G01X617668Y265458D02*
X617418Y265166D01*
X617084Y265000D01*
X616709Y264958D01*
X616376Y265000D01*
X616043Y265208D01*
X615834Y265458D01*
X615793Y265708D01*
X615876Y266000D01*
X616168Y266208D01*
X616459Y266291D01*
X616834D01*
G01X616459D02*
X616209Y266416D01*
X616001Y266625D01*
X615918Y266875D01*
X616001Y267125D01*
X616209Y267333D01*
X616584Y267458D01*
X616959Y267416D01*
X617334Y267250D01*
G01X629984Y261458D02*
Y263958D01*
X628943D01*
X628609Y263833D01*
X628401Y263666D01*
X628318Y263333D01*
X628401Y263000D01*
X628651Y262791D01*
X628943Y262666D01*
X629984D01*
G01X628943D02*
X628318Y261458D01*
G01X626843Y262500D02*
X626551Y262791D01*
X626301Y262958D01*
X625968Y263041D01*
X625676Y262958D01*
X625468Y262791D01*
X625301Y262541D01*
X625259Y262250D01*
X625301Y262000D01*
X625468Y261750D01*
X625718Y261541D01*
X626009Y261458D01*
X626343Y261541D01*
X626634Y261791D01*
X626801Y262166D01*
X626843Y262583D01*
X626759Y263125D01*
X626634Y263416D01*
X626426Y263708D01*
X626134Y263916D01*
X625843Y263958D01*
X625551Y263875D01*
X625343Y263666D01*
G01X623784Y261458D02*
Y263958D01*
X622784D01*
X622451Y263833D01*
X622201Y263541D01*
X622118Y263208D01*
X622201Y262875D01*
X622409Y262625D01*
X622784Y262500D01*
X623784D01*
G01X620768Y261958D02*
X620518Y261666D01*
X620184Y261500D01*
X619809Y261458D01*
X619476Y261500D01*
X619143Y261708D01*
X618934Y261958D01*
X618893Y262208D01*
X618976Y262500D01*
X619268Y262708D01*
X619559Y262791D01*
X619934D01*
G01X619559D02*
X619309Y262916D01*
X619101Y263125D01*
X619018Y263375D01*
X619101Y263625D01*
X619309Y263833D01*
X619684Y263958D01*
X620059Y263916D01*
X620434Y263750D01*
G01X617668Y261833D02*
X617418Y261625D01*
X617126Y261500D01*
X616751Y261458D01*
X616376Y261541D01*
X616084Y261708D01*
X615876Y262000D01*
X615834Y262333D01*
X615918Y262666D01*
X616126Y262875D01*
X616418Y263041D01*
X616709Y263083D01*
X617001Y263041D01*
X617376Y262875D01*
X617251Y263958D01*
X616126D01*
G01X651092Y276466D02*
X653592D01*
Y277507D01*
X653467Y277841D01*
X653300Y278049D01*
X652967Y278132D01*
X652634Y278049D01*
X652425Y277799D01*
X652300Y277507D01*
Y276466D01*
G01Y277507D02*
X651092Y278132D01*
G01X652134Y279607D02*
X652425Y279899D01*
X652592Y280149D01*
X652675Y280482D01*
X652592Y280774D01*
X652425Y280982D01*
X652175Y281149D01*
X651884Y281191D01*
X651634Y281149D01*
X651384Y280982D01*
X651175Y280732D01*
X651092Y280441D01*
X651175Y280107D01*
X651425Y279816D01*
X651800Y279649D01*
X652217Y279607D01*
X652759Y279691D01*
X653050Y279816D01*
X653342Y280024D01*
X653550Y280316D01*
X653592Y280607D01*
X653509Y280899D01*
X653300Y281107D01*
G01X651092Y282666D02*
X653592D01*
Y283666D01*
X653467Y283999D01*
X653175Y284249D01*
X652842Y284332D01*
X652509Y284249D01*
X652259Y284041D01*
X652134Y283666D01*
Y282666D01*
G01X653175Y285807D02*
X653425Y286057D01*
X653550Y286349D01*
X653592Y286682D01*
X653509Y287099D01*
X653300Y287391D01*
X653050Y287474D01*
X652800Y287432D01*
X652592Y287266D01*
X652175Y286432D01*
X651884Y286057D01*
X651467Y285807D01*
X651092Y285724D01*
Y287474D01*
G01X653175Y288907D02*
X653425Y289157D01*
X653550Y289449D01*
X653592Y289782D01*
X653509Y290199D01*
X653300Y290491D01*
X653050Y290574D01*
X652800Y290532D01*
X652592Y290366D01*
X652175Y289532D01*
X651884Y289157D01*
X651467Y288907D01*
X651092Y288824D01*
Y290574D01*
G01X611724Y254327D02*
X614224D01*
Y255368D01*
X614099Y255702D01*
X613932Y255910D01*
X613599Y255993D01*
X613266Y255910D01*
X613057Y255660D01*
X612932Y255368D01*
Y254327D01*
G01Y255368D02*
X611724Y255993D01*
G01X612766Y257468D02*
X613057Y257760D01*
X613224Y258010D01*
X613307Y258343D01*
X613224Y258635D01*
X613057Y258843D01*
X612807Y259010D01*
X612516Y259052D01*
X612266Y259010D01*
X612016Y258843D01*
X611807Y258593D01*
X611724Y258302D01*
X611807Y257968D01*
X612057Y257677D01*
X612432Y257510D01*
X612849Y257468D01*
X613391Y257552D01*
X613682Y257677D01*
X613974Y257885D01*
X614182Y258177D01*
X614224Y258468D01*
X614141Y258760D01*
X613932Y258968D01*
G01X611724Y260527D02*
X614224D01*
Y261527D01*
X614099Y261860D01*
X613807Y262110D01*
X613474Y262193D01*
X613141Y262110D01*
X612891Y261902D01*
X612766Y261527D01*
Y260527D01*
G01X612224Y263543D02*
X611932Y263793D01*
X611766Y264127D01*
X611724Y264502D01*
X611766Y264835D01*
X611974Y265168D01*
X612224Y265377D01*
X612474Y265418D01*
X612766Y265335D01*
X612974Y265043D01*
X613057Y264752D01*
Y264377D01*
G01Y264752D02*
X613182Y265002D01*
X613391Y265210D01*
X613641Y265293D01*
X613891Y265210D01*
X614099Y265002D01*
X614224Y264627D01*
X614182Y264252D01*
X614016Y263877D01*
G01X612016Y266852D02*
X611807Y267143D01*
X611724Y267477D01*
X611807Y267810D01*
X612057Y268102D01*
X612432Y268310D01*
X612807Y268393D01*
X613266D01*
X613641Y268310D01*
X613974Y268102D01*
X614141Y267852D01*
X614224Y267560D01*
X614141Y267227D01*
X613974Y266977D01*
X613724Y266810D01*
X613391Y266727D01*
X613099Y266810D01*
X612807Y267018D01*
X612641Y267268D01*
X612599Y267560D01*
X612682Y267893D01*
X612891Y268143D01*
X613266Y268393D01*
G01X657822Y272246D02*
X660322D01*
Y273287D01*
X660197Y273621D01*
X660030Y273829D01*
X659697Y273912D01*
X659364Y273829D01*
X659155Y273579D01*
X659030Y273287D01*
Y272246D01*
G01Y273287D02*
X657822Y273912D01*
G01Y276679D02*
X660322D01*
X658530Y275137D01*
Y277221D01*
G01X660322Y278029D02*
X657822Y278612D01*
X660322Y279279D01*
X657822Y279946D01*
X660322Y280529D01*
G01X658864Y281587D02*
X659155Y281879D01*
X659322Y282129D01*
X659405Y282462D01*
X659322Y282754D01*
X659155Y282962D01*
X658905Y283129D01*
X658614Y283171D01*
X658364Y283129D01*
X658114Y282962D01*
X657905Y282712D01*
X657822Y282421D01*
X657905Y282087D01*
X658155Y281796D01*
X658530Y281629D01*
X658947Y281587D01*
X659489Y281671D01*
X659780Y281796D01*
X660072Y282004D01*
X660280Y282296D01*
X660322Y282587D01*
X660239Y282879D01*
X660030Y283087D01*
G01X662544Y272976D02*
X665044D01*
Y274017D01*
X664919Y274351D01*
X664752Y274559D01*
X664419Y274642D01*
X664086Y274559D01*
X663877Y274309D01*
X663752Y274017D01*
Y272976D01*
G01Y274017D02*
X662544Y274642D01*
G01X663586Y276117D02*
X663877Y276409D01*
X664044Y276659D01*
X664127Y276992D01*
X664044Y277284D01*
X663877Y277492D01*
X663627Y277659D01*
X663336Y277701D01*
X663086Y277659D01*
X662836Y277492D01*
X662627Y277242D01*
X662544Y276951D01*
X662627Y276617D01*
X662877Y276326D01*
X663252Y276159D01*
X663669Y276117D01*
X664211Y276201D01*
X664502Y276326D01*
X664794Y276534D01*
X665002Y276826D01*
X665044Y277117D01*
X664961Y277409D01*
X664752Y277617D01*
G01X662544Y279176D02*
X665044D01*
Y280176D01*
X664919Y280509D01*
X664627Y280759D01*
X664294Y280842D01*
X663961Y280759D01*
X663711Y280551D01*
X663586Y280176D01*
Y279176D01*
G01X664627Y282317D02*
X664877Y282567D01*
X665002Y282859D01*
X665044Y283192D01*
X664961Y283609D01*
X664752Y283901D01*
X664502Y283984D01*
X664252Y283942D01*
X664044Y283776D01*
X663627Y282942D01*
X663336Y282567D01*
X662919Y282317D01*
X662544Y282234D01*
Y283984D01*
G01X662919Y285292D02*
X662711Y285542D01*
X662586Y285834D01*
X662544Y286209D01*
X662627Y286584D01*
X662794Y286876D01*
X663086Y287084D01*
X663419Y287126D01*
X663752Y287042D01*
X663961Y286834D01*
X664127Y286542D01*
X664169Y286251D01*
X664127Y285959D01*
X663961Y285584D01*
X665044Y285709D01*
Y286834D01*
G01X637776Y234695D02*
X637901Y234445D01*
X637984Y234153D01*
Y233820D01*
X637859Y233445D01*
X637651Y233153D01*
X637401Y232945D01*
X636984Y232778D01*
X636609Y232736D01*
X636234Y232820D01*
X635984Y232945D01*
X635734Y233195D01*
X635567Y233486D01*
X635484Y233778D01*
Y234070D01*
X635567Y234361D01*
X635692Y234611D01*
X635859Y234820D01*
G01X636526Y236086D02*
X636817Y236378D01*
X636984Y236628D01*
X637067Y236961D01*
X636984Y237253D01*
X636817Y237461D01*
X636567Y237628D01*
X636276Y237670D01*
X636026Y237628D01*
X635776Y237461D01*
X635567Y237211D01*
X635484Y236920D01*
X635567Y236586D01*
X635817Y236295D01*
X636192Y236128D01*
X636609Y236086D01*
X637151Y236170D01*
X637442Y236295D01*
X637734Y236503D01*
X637942Y236795D01*
X637984Y237086D01*
X637901Y237378D01*
X637692Y237586D01*
G01X635484Y239145D02*
X637984D01*
Y240186D01*
X637859Y240520D01*
X637692Y240728D01*
X637359Y240811D01*
X637026Y240728D01*
X636817Y240478D01*
X636692Y240186D01*
Y239145D01*
G01Y240186D02*
X635484Y240811D01*
G01X635859Y242161D02*
X635651Y242411D01*
X635526Y242703D01*
X635484Y243078D01*
X635567Y243453D01*
X635734Y243745D01*
X636026Y243953D01*
X636359Y243995D01*
X636692Y243911D01*
X636901Y243703D01*
X637067Y243411D01*
X637109Y243120D01*
X637067Y242828D01*
X636901Y242453D01*
X637984Y242578D01*
Y243703D01*
G01X643136Y245100D02*
Y248891D01*
X655932D01*
Y245100D01*
G01X643136Y232500D02*
Y228938D01*
X655932D01*
Y232500D01*
G01X678500Y247800D02*
X655928D01*
G01X678500Y229800D02*
X655925D01*
G01X643136Y223800D02*
Y227591D01*
X655932D01*
Y223800D01*
G01X678500Y226500D02*
X655928D01*
G01X634244Y310649D02*
Y313149D01*
X633203D01*
X632869Y313024D01*
X632661Y312857D01*
X632578Y312524D01*
X632661Y312191D01*
X632911Y311982D01*
X633203Y311857D01*
X634244D01*
G01X633203D02*
X632578Y310649D01*
G01X630394D02*
X630311Y311191D01*
X630186Y311649D01*
X630019Y312066D01*
X629811Y312524D01*
X629478Y313149D01*
X631144D01*
G01X628044Y310649D02*
Y313149D01*
X627044D01*
X626711Y313024D01*
X626461Y312732D01*
X626378Y312399D01*
X626461Y312066D01*
X626669Y311816D01*
X627044Y311691D01*
X628044D01*
G01X624111Y310649D02*
Y313149D01*
X624611Y312649D01*
G01Y310649D02*
X623611D01*
G01X621803Y312732D02*
X621553Y312982D01*
X621261Y313107D01*
X620928Y313149D01*
X620511Y313066D01*
X620219Y312857D01*
X620136Y312607D01*
X620178Y312357D01*
X620344Y312149D01*
X621178Y311732D01*
X621553Y311441D01*
X621803Y311024D01*
X621886Y310649D01*
X620136D01*
G01X634244Y321149D02*
Y323649D01*
X633203D01*
X632869Y323524D01*
X632661Y323357D01*
X632578Y323024D01*
X632661Y322691D01*
X632911Y322482D01*
X633203Y322357D01*
X634244D01*
G01X633203D02*
X632578Y321149D01*
G01X630394D02*
X630311Y321691D01*
X630186Y322149D01*
X630019Y322566D01*
X629811Y323024D01*
X629478Y323649D01*
X631144D01*
G01X628044Y321149D02*
Y323649D01*
X627044D01*
X626711Y323524D01*
X626461Y323232D01*
X626378Y322899D01*
X626461Y322566D01*
X626669Y322316D01*
X627044Y322191D01*
X628044D01*
G01X624903D02*
X624611Y322482D01*
X624361Y322649D01*
X624028Y322732D01*
X623736Y322649D01*
X623528Y322482D01*
X623361Y322232D01*
X623319Y321941D01*
X623361Y321691D01*
X623528Y321441D01*
X623778Y321232D01*
X624069Y321149D01*
X624403Y321232D01*
X624694Y321482D01*
X624861Y321857D01*
X624903Y322274D01*
X624819Y322816D01*
X624694Y323107D01*
X624486Y323399D01*
X624194Y323607D01*
X623903Y323649D01*
X623611Y323566D01*
X623403Y323357D01*
G01X634244Y328149D02*
Y330649D01*
X633203D01*
X632869Y330524D01*
X632661Y330357D01*
X632578Y330024D01*
X632661Y329691D01*
X632911Y329482D01*
X633203Y329357D01*
X634244D01*
G01X633203D02*
X632578Y328149D01*
G01X630394D02*
X630311Y328691D01*
X630186Y329149D01*
X630019Y329566D01*
X629811Y330024D01*
X629478Y330649D01*
X631144D01*
G01X628044Y328149D02*
Y330649D01*
X627044D01*
X626711Y330524D01*
X626461Y330232D01*
X626378Y329899D01*
X626461Y329566D01*
X626669Y329316D01*
X627044Y329191D01*
X628044D01*
G01X625028Y328649D02*
X624778Y328357D01*
X624444Y328191D01*
X624069Y328149D01*
X623736Y328191D01*
X623403Y328399D01*
X623194Y328649D01*
X623153Y328899D01*
X623236Y329191D01*
X623528Y329399D01*
X623819Y329482D01*
X624194D01*
G01X623819D02*
X623569Y329607D01*
X623361Y329816D01*
X623278Y330066D01*
X623361Y330316D01*
X623569Y330524D01*
X623944Y330649D01*
X624319Y330607D01*
X624694Y330441D01*
G01X634244Y335149D02*
Y337649D01*
X633203D01*
X632869Y337524D01*
X632661Y337357D01*
X632578Y337024D01*
X632661Y336691D01*
X632911Y336482D01*
X633203Y336357D01*
X634244D01*
G01X633203D02*
X632578Y335149D01*
G01X630394D02*
X630311Y335691D01*
X630186Y336149D01*
X630019Y336566D01*
X629811Y337024D01*
X629478Y337649D01*
X631144D01*
G01X628044Y335149D02*
Y337649D01*
X627044D01*
X626711Y337524D01*
X626461Y337232D01*
X626378Y336899D01*
X626461Y336566D01*
X626669Y336316D01*
X627044Y336191D01*
X628044D01*
G01X624111Y335149D02*
Y337649D01*
X624611Y337149D01*
G01Y335149D02*
X623611D01*
G01X634244Y331649D02*
Y334149D01*
X633203D01*
X632869Y334024D01*
X632661Y333857D01*
X632578Y333524D01*
X632661Y333191D01*
X632911Y332982D01*
X633203Y332857D01*
X634244D01*
G01X633203D02*
X632578Y331649D01*
G01X630394D02*
X630311Y332191D01*
X630186Y332649D01*
X630019Y333066D01*
X629811Y333524D01*
X629478Y334149D01*
X631144D01*
G01X628044Y331649D02*
Y334149D01*
X627044D01*
X626711Y334024D01*
X626461Y333732D01*
X626378Y333399D01*
X626461Y333066D01*
X626669Y332816D01*
X627044Y332691D01*
X628044D01*
G01X624903Y333732D02*
X624653Y333982D01*
X624361Y334107D01*
X624028Y334149D01*
X623611Y334066D01*
X623319Y333857D01*
X623236Y333607D01*
X623278Y333357D01*
X623444Y333149D01*
X624278Y332732D01*
X624653Y332441D01*
X624903Y332024D01*
X624986Y331649D01*
X623236D01*
G01X634244Y324649D02*
Y327149D01*
X633203D01*
X632869Y327024D01*
X632661Y326857D01*
X632578Y326524D01*
X632661Y326191D01*
X632911Y325982D01*
X633203Y325857D01*
X634244D01*
G01X633203D02*
X632578Y324649D01*
G01X630394D02*
X630311Y325191D01*
X630186Y325649D01*
X630019Y326066D01*
X629811Y326524D01*
X629478Y327149D01*
X631144D01*
G01X628044Y324649D02*
Y327149D01*
X627044D01*
X626711Y327024D01*
X626461Y326732D01*
X626378Y326399D01*
X626461Y326066D01*
X626669Y325816D01*
X627044Y325691D01*
X628044D01*
G01X623611Y324649D02*
Y327149D01*
X625153Y325357D01*
X623069D01*
G01X646282Y281677D02*
X648782D01*
Y282718D01*
X648657Y283052D01*
X648490Y283260D01*
X648157Y283343D01*
X647824Y283260D01*
X647615Y283010D01*
X647490Y282718D01*
Y281677D01*
G01Y282718D02*
X646282Y283343D01*
G01X647324Y284818D02*
X647615Y285110D01*
X647782Y285360D01*
X647865Y285693D01*
X647782Y285985D01*
X647615Y286193D01*
X647365Y286360D01*
X647074Y286402D01*
X646824Y286360D01*
X646574Y286193D01*
X646365Y285943D01*
X646282Y285652D01*
X646365Y285318D01*
X646615Y285027D01*
X646990Y284860D01*
X647407Y284818D01*
X647949Y284902D01*
X648240Y285027D01*
X648532Y285235D01*
X648740Y285527D01*
X648782Y285818D01*
X648699Y286110D01*
X648490Y286318D01*
G01X646282Y287877D02*
X648782D01*
Y288877D01*
X648657Y289210D01*
X648365Y289460D01*
X648032Y289543D01*
X647699Y289460D01*
X647449Y289252D01*
X647324Y288877D01*
Y287877D01*
G01X648365Y291018D02*
X648615Y291268D01*
X648740Y291560D01*
X648782Y291893D01*
X648699Y292310D01*
X648490Y292602D01*
X648240Y292685D01*
X647990Y292643D01*
X647782Y292477D01*
X647365Y291643D01*
X647074Y291268D01*
X646657Y291018D01*
X646282Y290935D01*
Y292685D01*
G01X646782Y293993D02*
X646490Y294243D01*
X646324Y294577D01*
X646282Y294952D01*
X646324Y295285D01*
X646532Y295618D01*
X646782Y295827D01*
X647032Y295868D01*
X647324Y295785D01*
X647532Y295493D01*
X647615Y295202D01*
Y294827D01*
G01Y295202D02*
X647740Y295452D01*
X647949Y295660D01*
X648199Y295743D01*
X648449Y295660D01*
X648657Y295452D01*
X648782Y295077D01*
X648740Y294702D01*
X648574Y294327D01*
G01X634244Y317649D02*
Y320149D01*
X633203D01*
X632869Y320024D01*
X632661Y319857D01*
X632578Y319524D01*
X632661Y319191D01*
X632911Y318982D01*
X633203Y318857D01*
X634244D01*
G01X633203D02*
X632578Y317649D01*
G01X630394D02*
X630311Y318191D01*
X630186Y318649D01*
X630019Y319066D01*
X629811Y319524D01*
X629478Y320149D01*
X631144D01*
G01X628044Y317649D02*
Y320149D01*
X627044D01*
X626711Y320024D01*
X626461Y319732D01*
X626378Y319399D01*
X626461Y319066D01*
X626669Y318816D01*
X627044Y318691D01*
X628044D01*
G01X624194Y317649D02*
X624111Y318191D01*
X623986Y318649D01*
X623819Y319066D01*
X623611Y319524D01*
X623278Y320149D01*
X624944D01*
G01X634244Y314149D02*
Y316649D01*
X633203D01*
X632869Y316524D01*
X632661Y316357D01*
X632578Y316024D01*
X632661Y315691D01*
X632911Y315482D01*
X633203Y315357D01*
X634244D01*
G01X633203D02*
X632578Y314149D01*
G01X630394D02*
X630311Y314691D01*
X630186Y315149D01*
X630019Y315566D01*
X629811Y316024D01*
X629478Y316649D01*
X631144D01*
G01X628044Y314149D02*
Y316649D01*
X627044D01*
X626711Y316524D01*
X626461Y316232D01*
X626378Y315899D01*
X626461Y315566D01*
X626669Y315316D01*
X627044Y315191D01*
X628044D01*
G01X624819Y314441D02*
X624528Y314232D01*
X624194Y314149D01*
X623861Y314232D01*
X623569Y314482D01*
X623361Y314857D01*
X623278Y315232D01*
Y315691D01*
X623361Y316066D01*
X623569Y316399D01*
X623819Y316566D01*
X624111Y316649D01*
X624444Y316566D01*
X624694Y316399D01*
X624861Y316149D01*
X624944Y315816D01*
X624861Y315524D01*
X624653Y315232D01*
X624403Y315066D01*
X624111Y315024D01*
X623778Y315107D01*
X623528Y315316D01*
X623278Y315691D01*
G01X658823Y305618D02*
X659073Y305743D01*
X659365Y305826D01*
X659698D01*
X660073Y305701D01*
X660365Y305493D01*
X660573Y305243D01*
X660740Y304826D01*
X660782Y304451D01*
X660698Y304076D01*
X660573Y303826D01*
X660323Y303576D01*
X660032Y303409D01*
X659740Y303326D01*
X659448D01*
X659157Y303409D01*
X658907Y303534D01*
X658698Y303701D01*
G01X657432Y304368D02*
X657140Y304659D01*
X656890Y304826D01*
X656557Y304909D01*
X656265Y304826D01*
X656057Y304659D01*
X655890Y304409D01*
X655848Y304118D01*
X655890Y303868D01*
X656057Y303618D01*
X656307Y303409D01*
X656598Y303326D01*
X656932Y303409D01*
X657223Y303659D01*
X657390Y304034D01*
X657432Y304451D01*
X657348Y304993D01*
X657223Y305284D01*
X657015Y305576D01*
X656723Y305784D01*
X656432Y305826D01*
X656140Y305743D01*
X655932Y305534D01*
G01X654373Y303326D02*
Y305826D01*
X653373D01*
X653040Y305701D01*
X652790Y305409D01*
X652707Y305076D01*
X652790Y304743D01*
X652998Y304493D01*
X653373Y304368D01*
X654373D01*
G01X650440Y303326D02*
Y305826D01*
X650940Y305326D01*
G01Y303326D02*
X649940D01*
G01X647340Y305826D02*
X647673Y305743D01*
X647923Y305534D01*
X648090Y305284D01*
X648215Y304951D01*
X648257Y304576D01*
X648215Y304201D01*
X648090Y303868D01*
X647923Y303618D01*
X647673Y303409D01*
X647340Y303326D01*
X647007Y303409D01*
X646757Y303618D01*
X646590Y303868D01*
X646465Y304201D01*
X646423Y304576D01*
X646465Y304951D01*
X646590Y305284D01*
X646757Y305534D01*
X647007Y305743D01*
X647340Y305826D01*
G01X658621Y301803D02*
X658871Y301928D01*
X659163Y302011D01*
X659496D01*
X659871Y301886D01*
X660163Y301678D01*
X660371Y301428D01*
X660538Y301011D01*
X660580Y300636D01*
X660496Y300261D01*
X660371Y300011D01*
X660121Y299761D01*
X659830Y299594D01*
X659538Y299511D01*
X659246D01*
X658955Y299594D01*
X658705Y299719D01*
X658496Y299886D01*
G01X657230Y300553D02*
X656938Y300844D01*
X656688Y301011D01*
X656355Y301094D01*
X656063Y301011D01*
X655855Y300844D01*
X655688Y300594D01*
X655646Y300303D01*
X655688Y300053D01*
X655855Y299803D01*
X656105Y299594D01*
X656396Y299511D01*
X656730Y299594D01*
X657021Y299844D01*
X657188Y300219D01*
X657230Y300636D01*
X657146Y301178D01*
X657021Y301469D01*
X656813Y301761D01*
X656521Y301969D01*
X656230Y302011D01*
X655938Y301928D01*
X655730Y301719D01*
G01X654171Y299511D02*
Y302011D01*
X653171D01*
X652838Y301886D01*
X652588Y301594D01*
X652505Y301261D01*
X652588Y300928D01*
X652796Y300678D01*
X653171Y300553D01*
X654171D01*
G01X650238Y299511D02*
Y302011D01*
X650738Y301511D01*
G01Y299511D02*
X649738D01*
G01X647930Y301594D02*
X647680Y301844D01*
X647388Y301969D01*
X647055Y302011D01*
X646638Y301928D01*
X646346Y301719D01*
X646263Y301469D01*
X646305Y301219D01*
X646471Y301011D01*
X647305Y300594D01*
X647680Y300303D01*
X647930Y299886D01*
X648013Y299511D01*
X646263D01*
G01X664149Y334807D02*
X664399Y334932D01*
X664691Y335015D01*
X665024D01*
X665399Y334890D01*
X665691Y334682D01*
X665899Y334432D01*
X666066Y334015D01*
X666108Y333640D01*
X666024Y333265D01*
X665899Y333015D01*
X665649Y332765D01*
X665358Y332598D01*
X665066Y332515D01*
X664774D01*
X664483Y332598D01*
X664233Y332723D01*
X664024Y332890D01*
G01X662758Y333557D02*
X662466Y333848D01*
X662216Y334015D01*
X661883Y334098D01*
X661591Y334015D01*
X661383Y333848D01*
X661216Y333598D01*
X661174Y333307D01*
X661216Y333057D01*
X661383Y332807D01*
X661633Y332598D01*
X661924Y332515D01*
X662258Y332598D01*
X662549Y332848D01*
X662716Y333223D01*
X662758Y333640D01*
X662674Y334182D01*
X662549Y334473D01*
X662341Y334765D01*
X662049Y334973D01*
X661758Y335015D01*
X661466Y334932D01*
X661258Y334723D01*
G01X659699Y332515D02*
Y335015D01*
X658699D01*
X658366Y334890D01*
X658116Y334598D01*
X658033Y334265D01*
X658116Y333932D01*
X658324Y333682D01*
X658699Y333557D01*
X659699D01*
G01X656683Y332890D02*
X656433Y332682D01*
X656141Y332557D01*
X655766Y332515D01*
X655391Y332598D01*
X655099Y332765D01*
X654891Y333057D01*
X654849Y333390D01*
X654933Y333723D01*
X655141Y333932D01*
X655433Y334098D01*
X655724Y334140D01*
X656016Y334098D01*
X656391Y333932D01*
X656266Y335015D01*
X655141D01*
G01X643793Y343596D02*
X646293D01*
Y344637D01*
X646168Y344971D01*
X646001Y345179D01*
X645668Y345262D01*
X645335Y345179D01*
X645126Y344929D01*
X645001Y344637D01*
Y343596D01*
G01Y344637D02*
X643793Y345262D01*
G01X644835Y346737D02*
X645126Y347029D01*
X645293Y347279D01*
X645376Y347612D01*
X645293Y347904D01*
X645126Y348112D01*
X644876Y348279D01*
X644585Y348321D01*
X644335Y348279D01*
X644085Y348112D01*
X643876Y347862D01*
X643793Y347571D01*
X643876Y347237D01*
X644126Y346946D01*
X644501Y346779D01*
X644918Y346737D01*
X645460Y346821D01*
X645751Y346946D01*
X646043Y347154D01*
X646251Y347446D01*
X646293Y347737D01*
X646210Y348029D01*
X646001Y348237D01*
G01X643793Y349796D02*
X646293D01*
Y350796D01*
X646168Y351129D01*
X645876Y351379D01*
X645543Y351462D01*
X645210Y351379D01*
X644960Y351171D01*
X644835Y350796D01*
Y349796D01*
G01X643793Y353729D02*
X646293D01*
X645793Y353229D01*
G01X643793D02*
Y354229D01*
G01X635793Y343596D02*
X638293D01*
Y344637D01*
X638168Y344971D01*
X638001Y345179D01*
X637668Y345262D01*
X637335Y345179D01*
X637126Y344929D01*
X637001Y344637D01*
Y343596D01*
G01Y344637D02*
X635793Y345262D01*
G01X636835Y346737D02*
X637126Y347029D01*
X637293Y347279D01*
X637376Y347612D01*
X637293Y347904D01*
X637126Y348112D01*
X636876Y348279D01*
X636585Y348321D01*
X636335Y348279D01*
X636085Y348112D01*
X635876Y347862D01*
X635793Y347571D01*
X635876Y347237D01*
X636126Y346946D01*
X636501Y346779D01*
X636918Y346737D01*
X637460Y346821D01*
X637751Y346946D01*
X638043Y347154D01*
X638251Y347446D01*
X638293Y347737D01*
X638210Y348029D01*
X638001Y348237D01*
G01X635793Y349796D02*
X638293D01*
Y350796D01*
X638168Y351129D01*
X637876Y351379D01*
X637543Y351462D01*
X637210Y351379D01*
X636960Y351171D01*
X636835Y350796D01*
Y349796D01*
G01X636293Y352812D02*
X636001Y353062D01*
X635835Y353396D01*
X635793Y353771D01*
X635835Y354104D01*
X636043Y354437D01*
X636293Y354646D01*
X636543Y354687D01*
X636835Y354604D01*
X637043Y354312D01*
X637126Y354021D01*
Y353646D01*
G01Y354021D02*
X637251Y354271D01*
X637460Y354479D01*
X637710Y354562D01*
X637960Y354479D01*
X638168Y354271D01*
X638293Y353896D01*
X638251Y353521D01*
X638085Y353146D01*
G01X639793Y343596D02*
X642293D01*
Y344637D01*
X642168Y344971D01*
X642001Y345179D01*
X641668Y345262D01*
X641335Y345179D01*
X641126Y344929D01*
X641001Y344637D01*
Y343596D01*
G01Y344637D02*
X639793Y345262D01*
G01X640835Y346737D02*
X641126Y347029D01*
X641293Y347279D01*
X641376Y347612D01*
X641293Y347904D01*
X641126Y348112D01*
X640876Y348279D01*
X640585Y348321D01*
X640335Y348279D01*
X640085Y348112D01*
X639876Y347862D01*
X639793Y347571D01*
X639876Y347237D01*
X640126Y346946D01*
X640501Y346779D01*
X640918Y346737D01*
X641460Y346821D01*
X641751Y346946D01*
X642043Y347154D01*
X642251Y347446D01*
X642293Y347737D01*
X642210Y348029D01*
X642001Y348237D01*
G01X639793Y349796D02*
X642293D01*
Y350796D01*
X642168Y351129D01*
X641876Y351379D01*
X641543Y351462D01*
X641210Y351379D01*
X640960Y351171D01*
X640835Y350796D01*
Y349796D01*
G01X641876Y352937D02*
X642126Y353187D01*
X642251Y353479D01*
X642293Y353812D01*
X642210Y354229D01*
X642001Y354521D01*
X641751Y354604D01*
X641501Y354562D01*
X641293Y354396D01*
X640876Y353562D01*
X640585Y353187D01*
X640168Y352937D01*
X639793Y352854D01*
Y354604D01*
G01X631793Y343596D02*
X634293D01*
Y344637D01*
X634168Y344971D01*
X634001Y345179D01*
X633668Y345262D01*
X633335Y345179D01*
X633126Y344929D01*
X633001Y344637D01*
Y343596D01*
G01Y344637D02*
X631793Y345262D01*
G01X632835Y346737D02*
X633126Y347029D01*
X633293Y347279D01*
X633376Y347612D01*
X633293Y347904D01*
X633126Y348112D01*
X632876Y348279D01*
X632585Y348321D01*
X632335Y348279D01*
X632085Y348112D01*
X631876Y347862D01*
X631793Y347571D01*
X631876Y347237D01*
X632126Y346946D01*
X632501Y346779D01*
X632918Y346737D01*
X633460Y346821D01*
X633751Y346946D01*
X634043Y347154D01*
X634251Y347446D01*
X634293Y347737D01*
X634210Y348029D01*
X634001Y348237D01*
G01X631793Y349796D02*
X634293D01*
Y350796D01*
X634168Y351129D01*
X633876Y351379D01*
X633543Y351462D01*
X633210Y351379D01*
X632960Y351171D01*
X632835Y350796D01*
Y349796D01*
G01X631793Y354229D02*
X634293D01*
X632501Y352687D01*
Y354771D01*
G01X627393Y343396D02*
X629893D01*
Y344437D01*
X629768Y344771D01*
X629601Y344979D01*
X629268Y345062D01*
X628935Y344979D01*
X628726Y344729D01*
X628601Y344437D01*
Y343396D01*
G01Y344437D02*
X627393Y345062D01*
G01X628435Y346537D02*
X628726Y346829D01*
X628893Y347079D01*
X628976Y347412D01*
X628893Y347704D01*
X628726Y347912D01*
X628476Y348079D01*
X628185Y348121D01*
X627935Y348079D01*
X627685Y347912D01*
X627476Y347662D01*
X627393Y347371D01*
X627476Y347037D01*
X627726Y346746D01*
X628101Y346579D01*
X628518Y346537D01*
X629060Y346621D01*
X629351Y346746D01*
X629643Y346954D01*
X629851Y347246D01*
X629893Y347537D01*
X629810Y347829D01*
X629601Y348037D01*
G01X627393Y349596D02*
X629893D01*
Y350596D01*
X629768Y350929D01*
X629476Y351179D01*
X629143Y351262D01*
X628810Y351179D01*
X628560Y350971D01*
X628435Y350596D01*
Y349596D01*
G01X627768Y352612D02*
X627560Y352862D01*
X627435Y353154D01*
X627393Y353529D01*
X627476Y353904D01*
X627643Y354196D01*
X627935Y354404D01*
X628268Y354446D01*
X628601Y354362D01*
X628810Y354154D01*
X628976Y353862D01*
X629018Y353571D01*
X628976Y353279D01*
X628810Y352904D01*
X629893Y353029D01*
Y354154D01*
G01X619393Y343396D02*
X621893D01*
Y344437D01*
X621768Y344771D01*
X621601Y344979D01*
X621268Y345062D01*
X620935Y344979D01*
X620726Y344729D01*
X620601Y344437D01*
Y343396D01*
G01Y344437D02*
X619393Y345062D01*
G01X620435Y346537D02*
X620726Y346829D01*
X620893Y347079D01*
X620976Y347412D01*
X620893Y347704D01*
X620726Y347912D01*
X620476Y348079D01*
X620185Y348121D01*
X619935Y348079D01*
X619685Y347912D01*
X619476Y347662D01*
X619393Y347371D01*
X619476Y347037D01*
X619726Y346746D01*
X620101Y346579D01*
X620518Y346537D01*
X621060Y346621D01*
X621351Y346746D01*
X621643Y346954D01*
X621851Y347246D01*
X621893Y347537D01*
X621810Y347829D01*
X621601Y348037D01*
G01X619393Y349596D02*
X621893D01*
Y350596D01*
X621768Y350929D01*
X621476Y351179D01*
X621143Y351262D01*
X620810Y351179D01*
X620560Y350971D01*
X620435Y350596D01*
Y349596D01*
G01X619393Y353446D02*
X619935Y353529D01*
X620393Y353654D01*
X620810Y353821D01*
X621268Y354029D01*
X621893Y354362D01*
Y352696D01*
G01X623393Y343396D02*
X625893D01*
Y344437D01*
X625768Y344771D01*
X625601Y344979D01*
X625268Y345062D01*
X624935Y344979D01*
X624726Y344729D01*
X624601Y344437D01*
Y343396D01*
G01Y344437D02*
X623393Y345062D01*
G01X624435Y346537D02*
X624726Y346829D01*
X624893Y347079D01*
X624976Y347412D01*
X624893Y347704D01*
X624726Y347912D01*
X624476Y348079D01*
X624185Y348121D01*
X623935Y348079D01*
X623685Y347912D01*
X623476Y347662D01*
X623393Y347371D01*
X623476Y347037D01*
X623726Y346746D01*
X624101Y346579D01*
X624518Y346537D01*
X625060Y346621D01*
X625351Y346746D01*
X625643Y346954D01*
X625851Y347246D01*
X625893Y347537D01*
X625810Y347829D01*
X625601Y348037D01*
G01X623393Y349596D02*
X625893D01*
Y350596D01*
X625768Y350929D01*
X625476Y351179D01*
X625143Y351262D01*
X624810Y351179D01*
X624560Y350971D01*
X624435Y350596D01*
Y349596D01*
G01Y352737D02*
X624726Y353029D01*
X624893Y353279D01*
X624976Y353612D01*
X624893Y353904D01*
X624726Y354112D01*
X624476Y354279D01*
X624185Y354321D01*
X623935Y354279D01*
X623685Y354112D01*
X623476Y353862D01*
X623393Y353571D01*
X623476Y353237D01*
X623726Y352946D01*
X624101Y352779D01*
X624518Y352737D01*
X625060Y352821D01*
X625351Y352946D01*
X625643Y353154D01*
X625851Y353446D01*
X625893Y353737D01*
X625810Y354029D01*
X625601Y354237D01*
G01X615393Y343396D02*
X617893D01*
Y344437D01*
X617768Y344771D01*
X617601Y344979D01*
X617268Y345062D01*
X616935Y344979D01*
X616726Y344729D01*
X616601Y344437D01*
Y343396D01*
G01Y344437D02*
X615393Y345062D01*
G01X616435Y346537D02*
X616726Y346829D01*
X616893Y347079D01*
X616976Y347412D01*
X616893Y347704D01*
X616726Y347912D01*
X616476Y348079D01*
X616185Y348121D01*
X615935Y348079D01*
X615685Y347912D01*
X615476Y347662D01*
X615393Y347371D01*
X615476Y347037D01*
X615726Y346746D01*
X616101Y346579D01*
X616518Y346537D01*
X617060Y346621D01*
X617351Y346746D01*
X617643Y346954D01*
X617851Y347246D01*
X617893Y347537D01*
X617810Y347829D01*
X617601Y348037D01*
G01X615393Y349596D02*
X617893D01*
Y350596D01*
X617768Y350929D01*
X617476Y351179D01*
X617143Y351262D01*
X616810Y351179D01*
X616560Y350971D01*
X616435Y350596D01*
Y349596D01*
G01X615393Y353529D02*
X615435Y353821D01*
X615560Y354154D01*
X615768Y354362D01*
X616060Y354446D01*
X616351Y354362D01*
X616601Y354112D01*
X616726Y353737D01*
Y353321D01*
X616810Y353071D01*
X617018Y352862D01*
X617310Y352779D01*
X617601Y352904D01*
X617810Y353196D01*
X617893Y353529D01*
X617810Y353862D01*
X617601Y354154D01*
X617310Y354279D01*
X617018Y354196D01*
X616810Y353987D01*
X616726Y353737D01*
Y353321D01*
X616601Y352946D01*
X616351Y352696D01*
X616060Y352612D01*
X615768Y352696D01*
X615560Y352904D01*
X615435Y353237D01*
X615393Y353529D01*
G01X611282Y456862D02*
X613782D01*
Y457903D01*
X613657Y458237D01*
X613490Y458445D01*
X613157Y458528D01*
X612824Y458445D01*
X612615Y458195D01*
X612490Y457903D01*
Y456862D01*
G01Y457903D02*
X611282Y458528D01*
G01Y460712D02*
X611824Y460795D01*
X612282Y460920D01*
X612699Y461087D01*
X613157Y461295D01*
X613782Y461628D01*
Y459962D01*
G01X611282Y462812D02*
X613782D01*
X611699Y463895D01*
X613782Y464978D01*
X611282D01*
G01X611574Y466287D02*
X611365Y466578D01*
X611282Y466912D01*
X611365Y467245D01*
X611615Y467537D01*
X611990Y467745D01*
X612365Y467828D01*
X612824D01*
X613199Y467745D01*
X613532Y467537D01*
X613699Y467287D01*
X613782Y466995D01*
X613699Y466662D01*
X613532Y466412D01*
X613282Y466245D01*
X612949Y466162D01*
X612657Y466245D01*
X612365Y466453D01*
X612199Y466703D01*
X612157Y466995D01*
X612240Y467328D01*
X612449Y467578D01*
X612824Y467828D01*
G01X657481Y479999D02*
X659981D01*
Y481040D01*
X659856Y481374D01*
X659689Y481582D01*
X659356Y481665D01*
X659023Y481582D01*
X658814Y481332D01*
X658689Y481040D01*
Y479999D01*
G01Y481040D02*
X657481Y481665D01*
G01X658523Y483140D02*
X658814Y483432D01*
X658981Y483682D01*
X659064Y484015D01*
X658981Y484307D01*
X658814Y484515D01*
X658564Y484682D01*
X658273Y484724D01*
X658023Y484682D01*
X657773Y484515D01*
X657564Y484265D01*
X657481Y483974D01*
X657564Y483640D01*
X657814Y483349D01*
X658189Y483182D01*
X658606Y483140D01*
X659148Y483224D01*
X659439Y483349D01*
X659731Y483557D01*
X659939Y483849D01*
X659981Y484140D01*
X659898Y484432D01*
X659689Y484640D01*
G01X657481Y485949D02*
X659981D01*
X657898Y487032D01*
X659981Y488115D01*
X657481D01*
G01X657773Y489424D02*
X657564Y489715D01*
X657481Y490049D01*
X657564Y490382D01*
X657814Y490674D01*
X658189Y490882D01*
X658564Y490965D01*
X659023D01*
X659398Y490882D01*
X659731Y490674D01*
X659898Y490424D01*
X659981Y490132D01*
X659898Y489799D01*
X659731Y489549D01*
X659481Y489382D01*
X659148Y489299D01*
X658856Y489382D01*
X658564Y489590D01*
X658398Y489840D01*
X658356Y490132D01*
X658439Y490465D01*
X658648Y490715D01*
X659023Y490965D01*
G01X647200Y480317D02*
X649700D01*
Y481358D01*
X649575Y481692D01*
X649408Y481900D01*
X649075Y481983D01*
X648742Y481900D01*
X648533Y481650D01*
X648408Y481358D01*
Y480317D01*
G01Y481358D02*
X647200Y481983D01*
G01Y484167D02*
X647742Y484250D01*
X648200Y484375D01*
X648617Y484542D01*
X649075Y484750D01*
X649700Y485083D01*
Y483417D01*
G01X647200Y486267D02*
X649700D01*
X647617Y487350D01*
X649700Y488433D01*
X647200D01*
G01Y490950D02*
X649700D01*
X647908Y489408D01*
Y491492D01*
G01X626644Y483246D02*
X629144D01*
Y484287D01*
X629019Y484621D01*
X628852Y484829D01*
X628519Y484912D01*
X628186Y484829D01*
X627977Y484579D01*
X627852Y484287D01*
Y483246D01*
G01Y484287D02*
X626644Y484912D01*
G01Y487096D02*
X627186Y487179D01*
X627644Y487304D01*
X628061Y487471D01*
X628519Y487679D01*
X629144Y488012D01*
Y486346D01*
G01X626644Y489196D02*
X629144D01*
X627061Y490279D01*
X629144Y491362D01*
X626644D01*
G01X627686Y492587D02*
X627977Y492879D01*
X628144Y493129D01*
X628227Y493462D01*
X628144Y493754D01*
X627977Y493962D01*
X627727Y494129D01*
X627436Y494171D01*
X627186Y494129D01*
X626936Y493962D01*
X626727Y493712D01*
X626644Y493421D01*
X626727Y493087D01*
X626977Y492796D01*
X627352Y492629D01*
X627769Y492587D01*
X628311Y492671D01*
X628602Y492796D01*
X628894Y493004D01*
X629102Y493296D01*
X629144Y493587D01*
X629061Y493879D01*
X628852Y494087D01*
G01X643200Y480317D02*
X645700D01*
Y481358D01*
X645575Y481692D01*
X645408Y481900D01*
X645075Y481983D01*
X644742Y481900D01*
X644533Y481650D01*
X644408Y481358D01*
Y480317D01*
G01Y481358D02*
X643200Y481983D01*
G01Y484167D02*
X643742Y484250D01*
X644200Y484375D01*
X644617Y484542D01*
X645075Y484750D01*
X645700Y485083D01*
Y483417D01*
G01X643200Y486267D02*
X645700D01*
X643617Y487350D01*
X645700Y488433D01*
X643200D01*
G01Y490450D02*
X645700D01*
X645200Y489950D01*
G01X643200D02*
Y490950D01*
G01X608830Y486567D02*
X611330D01*
Y487608D01*
X611205Y487942D01*
X611038Y488150D01*
X610705Y488233D01*
X610372Y488150D01*
X610163Y487900D01*
X610038Y487608D01*
Y486567D01*
G01Y487608D02*
X608830Y488233D01*
G01Y490417D02*
X609372Y490500D01*
X609830Y490625D01*
X610247Y490792D01*
X610705Y491000D01*
X611330Y491333D01*
Y489667D01*
G01X608830Y492517D02*
X611330D01*
X609247Y493600D01*
X611330Y494683D01*
X608830D01*
G01X610913Y495908D02*
X611163Y496158D01*
X611288Y496450D01*
X611330Y496783D01*
X611247Y497200D01*
X611038Y497492D01*
X610788Y497575D01*
X610538Y497533D01*
X610330Y497367D01*
X609913Y496533D01*
X609622Y496158D01*
X609205Y495908D01*
X608830Y495825D01*
Y497575D01*
G01X604530Y489367D02*
X607030D01*
Y490408D01*
X606905Y490742D01*
X606738Y490950D01*
X606405Y491033D01*
X606072Y490950D01*
X605863Y490700D01*
X605738Y490408D01*
Y489367D01*
G01Y490408D02*
X604530Y491033D01*
G01Y493217D02*
X605072Y493300D01*
X605530Y493425D01*
X605947Y493592D01*
X606405Y493800D01*
X607030Y494133D01*
Y492467D01*
G01X604530Y495317D02*
X607030D01*
X604947Y496400D01*
X607030Y497483D01*
X604530D01*
G01X605030Y498583D02*
X604738Y498833D01*
X604572Y499167D01*
X604530Y499542D01*
X604572Y499875D01*
X604780Y500208D01*
X605030Y500417D01*
X605280Y500458D01*
X605572Y500375D01*
X605780Y500083D01*
X605863Y499792D01*
Y499417D01*
G01Y499792D02*
X605988Y500042D01*
X606197Y500250D01*
X606447Y500333D01*
X606697Y500250D01*
X606905Y500042D01*
X607030Y499667D01*
X606988Y499292D01*
X606822Y498917D01*
G01X625350Y465217D02*
X627850D01*
Y466258D01*
X627725Y466592D01*
X627558Y466800D01*
X627225Y466883D01*
X626892Y466800D01*
X626683Y466550D01*
X626558Y466258D01*
Y465217D01*
G01Y466258D02*
X625350Y466883D01*
G01Y469067D02*
X625892Y469150D01*
X626350Y469275D01*
X626767Y469442D01*
X627225Y469650D01*
X627850Y469983D01*
Y468317D01*
G01X625350Y471167D02*
X627850D01*
X625767Y472250D01*
X627850Y473333D01*
X625350D01*
G01X625725Y474433D02*
X625517Y474683D01*
X625392Y474975D01*
X625350Y475350D01*
X625433Y475725D01*
X625600Y476017D01*
X625892Y476225D01*
X626225Y476267D01*
X626558Y476183D01*
X626767Y475975D01*
X626933Y475683D01*
X626975Y475392D01*
X626933Y475100D01*
X626767Y474725D01*
X627850Y474850D01*
Y475975D01*
G01X620227Y480665D02*
X622727D01*
Y481706D01*
X622602Y482040D01*
X622435Y482248D01*
X622102Y482331D01*
X621769Y482248D01*
X621560Y481998D01*
X621435Y481706D01*
Y480665D01*
G01Y481706D02*
X620227Y482331D01*
G01Y484515D02*
X620769Y484598D01*
X621227Y484723D01*
X621644Y484890D01*
X622102Y485098D01*
X622727Y485431D01*
Y483765D01*
G01X620227Y486615D02*
X622727D01*
X620644Y487698D01*
X622727Y488781D01*
X620227D01*
G01Y490798D02*
X620269Y491090D01*
X620394Y491423D01*
X620602Y491631D01*
X620894Y491715D01*
X621185Y491631D01*
X621435Y491381D01*
X621560Y491006D01*
Y490590D01*
X621644Y490340D01*
X621852Y490131D01*
X622144Y490048D01*
X622435Y490173D01*
X622644Y490465D01*
X622727Y490798D01*
X622644Y491131D01*
X622435Y491423D01*
X622144Y491548D01*
X621852Y491465D01*
X621644Y491256D01*
X621560Y491006D01*
Y490590D01*
X621435Y490215D01*
X621185Y489965D01*
X620894Y489881D01*
X620602Y489965D01*
X620394Y490173D01*
X620269Y490506D01*
X620227Y490798D01*
G01X620950Y467917D02*
X623450D01*
Y468958D01*
X623325Y469292D01*
X623158Y469500D01*
X622825Y469583D01*
X622492Y469500D01*
X622283Y469250D01*
X622158Y468958D01*
Y467917D01*
G01Y468958D02*
X620950Y469583D01*
G01Y471767D02*
X621492Y471850D01*
X621950Y471975D01*
X622367Y472142D01*
X622825Y472350D01*
X623450Y472683D01*
Y471017D01*
G01X620950Y473867D02*
X623450D01*
X621367Y474950D01*
X623450Y476033D01*
X620950D01*
G01Y477967D02*
X621492Y478050D01*
X621950Y478175D01*
X622367Y478342D01*
X622825Y478550D01*
X623450Y478883D01*
Y477217D01*
G01X657450Y499833D02*
X655658D01*
X655283Y500000D01*
X655033Y500333D01*
X654950Y500750D01*
X655033Y501167D01*
X655283Y501500D01*
X655658Y501667D01*
X657450D01*
G01X655992Y503058D02*
X656283Y503350D01*
X656450Y503600D01*
X656533Y503933D01*
X656450Y504225D01*
X656283Y504433D01*
X656033Y504600D01*
X655742Y504642D01*
X655492Y504600D01*
X655242Y504433D01*
X655033Y504183D01*
X654950Y503892D01*
X655033Y503558D01*
X655283Y503267D01*
X655658Y503100D01*
X656075Y503058D01*
X656617Y503142D01*
X656908Y503267D01*
X657200Y503475D01*
X657408Y503767D01*
X657450Y504058D01*
X657367Y504350D01*
X657158Y504558D01*
G01X654950Y505867D02*
X657450D01*
X655367Y506950D01*
X657450Y508033D01*
X654950D01*
G01Y510050D02*
X657450D01*
X656950Y509550D01*
G01X654950D02*
Y510550D01*
G01X654732Y496479D02*
X654982Y496604D01*
X655274Y496687D01*
X655607D01*
X655982Y496562D01*
X656274Y496354D01*
X656482Y496104D01*
X656649Y495687D01*
X656691Y495312D01*
X656607Y494937D01*
X656482Y494687D01*
X656232Y494437D01*
X655941Y494270D01*
X655649Y494187D01*
X655357D01*
X655066Y494270D01*
X654816Y494395D01*
X654607Y494562D01*
G01X653341Y495229D02*
X653049Y495520D01*
X652799Y495687D01*
X652466Y495770D01*
X652174Y495687D01*
X651966Y495520D01*
X651799Y495270D01*
X651757Y494979D01*
X651799Y494729D01*
X651966Y494479D01*
X652216Y494270D01*
X652507Y494187D01*
X652841Y494270D01*
X653132Y494520D01*
X653299Y494895D01*
X653341Y495312D01*
X653257Y495854D01*
X653132Y496145D01*
X652924Y496437D01*
X652632Y496645D01*
X652341Y496687D01*
X652049Y496604D01*
X651841Y496395D01*
G01X650532Y494187D02*
Y496687D01*
X649449Y494604D01*
X648366Y496687D01*
Y494187D01*
G01X647141Y495229D02*
X646849Y495520D01*
X646599Y495687D01*
X646266Y495770D01*
X645974Y495687D01*
X645766Y495520D01*
X645599Y495270D01*
X645557Y494979D01*
X645599Y494729D01*
X645766Y494479D01*
X646016Y494270D01*
X646307Y494187D01*
X646641Y494270D01*
X646932Y494520D01*
X647099Y494895D01*
X647141Y495312D01*
X647057Y495854D01*
X646932Y496145D01*
X646724Y496437D01*
X646432Y496645D01*
X646141Y496687D01*
X645849Y496604D01*
X645641Y496395D01*
G01X655078Y521084D02*
X654848Y521394D01*
X654580Y521549D01*
X654273Y521601D01*
X653890Y521498D01*
X653622Y521239D01*
X653545Y520929D01*
X653583Y520619D01*
X653737Y520361D01*
X654503Y519844D01*
X654848Y519483D01*
X655078Y518966D01*
X655155Y518501D01*
X653545D01*
G01X651250D02*
X650982Y518553D01*
X650675Y518708D01*
X650483Y518966D01*
X650407Y519328D01*
X650483Y519689D01*
X650713Y519999D01*
X651058Y520154D01*
X651442D01*
X651672Y520258D01*
X651863Y520516D01*
X651940Y520878D01*
X651825Y521239D01*
X651557Y521498D01*
X651250Y521601D01*
X650943Y521498D01*
X650675Y521239D01*
X650560Y520878D01*
X650637Y520516D01*
X650828Y520258D01*
X651058Y520154D01*
X651442D01*
X651787Y519999D01*
X652017Y519689D01*
X652093Y519328D01*
X652017Y518966D01*
X651825Y518708D01*
X651518Y518553D01*
X651250Y518501D01*
G01X648150D02*
X647882Y518553D01*
X647575Y518708D01*
X647383Y518966D01*
X647307Y519328D01*
X647383Y519689D01*
X647613Y519999D01*
X647958Y520154D01*
X648342D01*
X648572Y520258D01*
X648763Y520516D01*
X648840Y520878D01*
X648725Y521239D01*
X648457Y521498D01*
X648150Y521601D01*
X647843Y521498D01*
X647575Y521239D01*
X647460Y520878D01*
X647537Y520516D01*
X647728Y520258D01*
X647958Y520154D01*
X648342D01*
X648687Y519999D01*
X648917Y519689D01*
X648993Y519328D01*
X648917Y518966D01*
X648725Y518708D01*
X648418Y518553D01*
X648150Y518501D01*
G01X654850Y511501D02*
Y514601D01*
X655310Y513981D01*
G01Y511501D02*
X654390D01*
G01X651290D02*
Y514601D01*
X652708Y512379D01*
X650792D01*
G01X648190Y511501D02*
Y514601D01*
X649608Y512379D01*
X647692D01*
G01X627578Y499584D02*
X627348Y499894D01*
X627080Y500049D01*
X626773Y500101D01*
X626390Y499998D01*
X626122Y499739D01*
X626045Y499429D01*
X626083Y499119D01*
X626237Y498861D01*
X627003Y498344D01*
X627348Y497983D01*
X627578Y497466D01*
X627655Y497001D01*
X626045D01*
G01X623750D02*
X623482Y497053D01*
X623175Y497208D01*
X622983Y497466D01*
X622907Y497828D01*
X622983Y498189D01*
X623213Y498499D01*
X623558Y498654D01*
X623942D01*
X624172Y498758D01*
X624363Y499016D01*
X624440Y499378D01*
X624325Y499739D01*
X624057Y499998D01*
X623750Y500101D01*
X623443Y499998D01*
X623175Y499739D01*
X623060Y499378D01*
X623137Y499016D01*
X623328Y498758D01*
X623558Y498654D01*
X623942D01*
X624287Y498499D01*
X624517Y498189D01*
X624593Y497828D01*
X624517Y497466D01*
X624325Y497208D01*
X624018Y497053D01*
X623750Y497001D01*
G01X620650D02*
X620382Y497053D01*
X620075Y497208D01*
X619883Y497466D01*
X619807Y497828D01*
X619883Y498189D01*
X620113Y498499D01*
X620458Y498654D01*
X620842D01*
X621072Y498758D01*
X621263Y499016D01*
X621340Y499378D01*
X621225Y499739D01*
X620957Y499998D01*
X620650Y500101D01*
X620343Y499998D01*
X620075Y499739D01*
X619960Y499378D01*
X620037Y499016D01*
X620228Y498758D01*
X620458Y498654D01*
X620842D01*
X621187Y498499D01*
X621417Y498189D01*
X621493Y497828D01*
X621417Y497466D01*
X621225Y497208D01*
X620918Y497053D01*
X620650Y497001D01*
G01X621376Y501284D02*
X645766D01*
Y526874D01*
X621376D01*
G01X657348Y559555D02*
X657473Y559305D01*
X657556Y559013D01*
Y558680D01*
X657431Y558305D01*
X657223Y558013D01*
X656973Y557805D01*
X656556Y557638D01*
X656181Y557596D01*
X655806Y557680D01*
X655556Y557805D01*
X655306Y558055D01*
X655139Y558346D01*
X655056Y558638D01*
Y558930D01*
X655139Y559221D01*
X655264Y559471D01*
X655431Y559680D01*
G01X656098Y560946D02*
X656389Y561238D01*
X656556Y561488D01*
X656639Y561821D01*
X656556Y562113D01*
X656389Y562321D01*
X656139Y562488D01*
X655848Y562530D01*
X655598Y562488D01*
X655348Y562321D01*
X655139Y562071D01*
X655056Y561780D01*
X655139Y561446D01*
X655389Y561155D01*
X655764Y560988D01*
X656181Y560946D01*
X656723Y561030D01*
X657014Y561155D01*
X657306Y561363D01*
X657514Y561655D01*
X657556Y561946D01*
X657473Y562238D01*
X657264Y562446D01*
G01X657556Y563588D02*
X655056Y564171D01*
X657556Y564838D01*
X655056Y565505D01*
X657556Y566088D01*
G01X655056Y567938D02*
X657556D01*
X657056Y567438D01*
G01X655056D02*
Y568438D01*
G01X655556Y570121D02*
X655264Y570371D01*
X655098Y570705D01*
X655056Y571080D01*
X655098Y571413D01*
X655306Y571746D01*
X655556Y571955D01*
X655806Y571996D01*
X656098Y571913D01*
X656306Y571621D01*
X656389Y571330D01*
Y570955D01*
G01Y571330D02*
X656514Y571580D01*
X656723Y571788D01*
X656973Y571871D01*
X657223Y571788D01*
X657431Y571580D01*
X657556Y571205D01*
X657514Y570830D01*
X657348Y570455D01*
G01X669233Y582959D02*
X669483Y583084D01*
X669775Y583167D01*
X670108D01*
X670483Y583042D01*
X670775Y582834D01*
X670983Y582584D01*
X671150Y582167D01*
X671192Y581792D01*
X671108Y581417D01*
X670983Y581167D01*
X670733Y580917D01*
X670442Y580750D01*
X670150Y580667D01*
X669858D01*
X669567Y580750D01*
X669317Y580875D01*
X669108Y581042D01*
G01X667842Y581709D02*
X667550Y582000D01*
X667300Y582167D01*
X666967Y582250D01*
X666675Y582167D01*
X666467Y582000D01*
X666300Y581750D01*
X666258Y581459D01*
X666300Y581209D01*
X666467Y580959D01*
X666717Y580750D01*
X667008Y580667D01*
X667342Y580750D01*
X667633Y581000D01*
X667800Y581375D01*
X667842Y581792D01*
X667758Y582334D01*
X667633Y582625D01*
X667425Y582917D01*
X667133Y583125D01*
X666842Y583167D01*
X666550Y583084D01*
X666342Y582875D01*
G01X664783Y583167D02*
Y580667D01*
X663117D01*
G01X661767Y581042D02*
X661517Y580834D01*
X661225Y580709D01*
X660850Y580667D01*
X660475Y580750D01*
X660183Y580917D01*
X659975Y581209D01*
X659933Y581542D01*
X660017Y581875D01*
X660225Y582084D01*
X660517Y582250D01*
X660808Y582292D01*
X661100Y582250D01*
X661475Y582084D01*
X661350Y583167D01*
X660225D01*
G01X652748Y536356D02*
X652873Y536106D01*
X652956Y535814D01*
Y535481D01*
X652831Y535106D01*
X652623Y534814D01*
X652373Y534606D01*
X651956Y534439D01*
X651581Y534397D01*
X651206Y534481D01*
X650956Y534606D01*
X650706Y534856D01*
X650539Y535147D01*
X650456Y535439D01*
Y535731D01*
X650539Y536022D01*
X650664Y536272D01*
X650831Y536481D01*
G01X650456Y538456D02*
X650998Y538539D01*
X651456Y538664D01*
X651873Y538831D01*
X652331Y539039D01*
X652956Y539372D01*
Y537706D01*
G01X650456Y540556D02*
X652956D01*
X650873Y541639D01*
X652956Y542722D01*
X650456D01*
G01X650956Y543822D02*
X650664Y544072D01*
X650498Y544406D01*
X650456Y544781D01*
X650498Y545114D01*
X650706Y545447D01*
X650956Y545656D01*
X651206Y545697D01*
X651498Y545614D01*
X651706Y545322D01*
X651789Y545031D01*
Y544656D01*
G01Y545031D02*
X651914Y545281D01*
X652123Y545489D01*
X652373Y545572D01*
X652623Y545489D01*
X652831Y545281D01*
X652956Y544906D01*
X652914Y544531D01*
X652748Y544156D01*
G01X649217Y529055D02*
X649342Y528805D01*
X649425Y528513D01*
Y528180D01*
X649300Y527805D01*
X649092Y527513D01*
X648842Y527305D01*
X648425Y527138D01*
X648050Y527096D01*
X647675Y527180D01*
X647425Y527305D01*
X647175Y527555D01*
X647008Y527846D01*
X646925Y528138D01*
Y528430D01*
X647008Y528721D01*
X647133Y528971D01*
X647300Y529180D01*
G01X646925Y531155D02*
X647467Y531238D01*
X647925Y531363D01*
X648342Y531530D01*
X648800Y531738D01*
X649425Y532071D01*
Y530405D01*
G01X646925Y533255D02*
X649425D01*
X647342Y534338D01*
X649425Y535421D01*
X646925D01*
G01Y537938D02*
X649425D01*
X647633Y536396D01*
Y538480D01*
G01X661900Y569100D02*
Y570300D01*
X673900D01*
Y569100D01*
G01X661900Y555500D02*
Y554300D01*
X673900D01*
Y555500D01*
G01X627578Y575584D02*
X627348Y575894D01*
X627080Y576049D01*
X626773Y576101D01*
X626390Y575998D01*
X626122Y575739D01*
X626045Y575429D01*
X626083Y575119D01*
X626237Y574861D01*
X627003Y574344D01*
X627348Y573983D01*
X627578Y573466D01*
X627655Y573001D01*
X626045D01*
G01X623750D02*
X623482Y573053D01*
X623175Y573208D01*
X622983Y573466D01*
X622907Y573828D01*
X622983Y574189D01*
X623213Y574499D01*
X623558Y574654D01*
X623942D01*
X624172Y574758D01*
X624363Y575016D01*
X624440Y575378D01*
X624325Y575739D01*
X624057Y575998D01*
X623750Y576101D01*
X623443Y575998D01*
X623175Y575739D01*
X623060Y575378D01*
X623137Y575016D01*
X623328Y574758D01*
X623558Y574654D01*
X623942D01*
X624287Y574499D01*
X624517Y574189D01*
X624593Y573828D01*
X624517Y573466D01*
X624325Y573208D01*
X624018Y573053D01*
X623750Y573001D01*
G01X620650D02*
X620382Y573053D01*
X620075Y573208D01*
X619883Y573466D01*
X619807Y573828D01*
X619883Y574189D01*
X620113Y574499D01*
X620458Y574654D01*
X620842D01*
X621072Y574758D01*
X621263Y575016D01*
X621340Y575378D01*
X621225Y575739D01*
X620957Y575998D01*
X620650Y576101D01*
X620343Y575998D01*
X620075Y575739D01*
X619960Y575378D01*
X620037Y575016D01*
X620228Y574758D01*
X620458Y574654D01*
X620842D01*
X621187Y574499D01*
X621417Y574189D01*
X621493Y573828D01*
X621417Y573466D01*
X621225Y573208D01*
X620918Y573053D01*
X620650Y573001D01*
G01X621376Y576884D02*
X645766D01*
Y602474D01*
X621376D01*
G01X627350Y566001D02*
Y569101D01*
X627810Y568481D01*
G01Y566001D02*
X626890D01*
G01X623790D02*
Y569101D01*
X625208Y566879D01*
X623292D01*
G01X620690Y566001D02*
Y569101D01*
X622108Y566879D01*
X620192D01*
G01X621376Y539084D02*
X645766D01*
Y564674D01*
X621376D01*
G01X674030Y590389D02*
Y592889D01*
X672989D01*
X672655Y592764D01*
X672447Y592597D01*
X672364Y592264D01*
X672447Y591931D01*
X672697Y591722D01*
X672989Y591597D01*
X674030D01*
G01X672989D02*
X672364Y590389D01*
G01X670889Y591431D02*
X670597Y591722D01*
X670347Y591889D01*
X670014Y591972D01*
X669722Y591889D01*
X669514Y591722D01*
X669347Y591472D01*
X669305Y591181D01*
X669347Y590931D01*
X669514Y590681D01*
X669764Y590472D01*
X670055Y590389D01*
X670389Y590472D01*
X670680Y590722D01*
X670847Y591097D01*
X670889Y591514D01*
X670805Y592056D01*
X670680Y592347D01*
X670472Y592639D01*
X670180Y592847D01*
X669889Y592889D01*
X669597Y592806D01*
X669389Y592597D01*
G01X667830Y592889D02*
Y590389D01*
X666164D01*
G01X664814Y590764D02*
X664564Y590556D01*
X664272Y590431D01*
X663897Y590389D01*
X663522Y590472D01*
X663230Y590639D01*
X663022Y590931D01*
X662980Y591264D01*
X663064Y591597D01*
X663272Y591806D01*
X663564Y591972D01*
X663855Y592014D01*
X664147Y591972D01*
X664522Y591806D01*
X664397Y592889D01*
X663272D01*
G01X618633Y616992D02*
X618883Y617117D01*
X619175Y617200D01*
X619508D01*
X619883Y617075D01*
X620175Y616867D01*
X620383Y616617D01*
X620550Y616200D01*
X620592Y615825D01*
X620508Y615450D01*
X620383Y615200D01*
X620133Y614950D01*
X619842Y614783D01*
X619550Y614700D01*
X619258D01*
X618967Y614783D01*
X618717Y614908D01*
X618508Y615075D01*
G01X616533Y614700D02*
X616450Y615242D01*
X616325Y615700D01*
X616158Y616117D01*
X615950Y616575D01*
X615617Y617200D01*
X617283D01*
G01X614183D02*
Y614700D01*
X612517D01*
G01X611042Y616783D02*
X610792Y617033D01*
X610500Y617158D01*
X610167Y617200D01*
X609750Y617117D01*
X609458Y616908D01*
X609375Y616658D01*
X609417Y616408D01*
X609583Y616200D01*
X610417Y615783D01*
X610792Y615492D01*
X611042Y615075D01*
X611125Y614700D01*
X609375D01*
G01X624850Y603501D02*
Y606601D01*
X625310Y605981D01*
G01Y603501D02*
X624390D01*
G01X621290D02*
Y606601D01*
X622708Y604379D01*
X620792D01*
G01X618190Y603501D02*
Y606601D01*
X619608Y604379D01*
X617692D01*
G01X602598Y639831D02*
X635298D01*
Y658531D01*
X602598D01*
Y639831D01*
G01X725652Y-16929D02*
X725902Y-16804D01*
X726194Y-16721D01*
X726527D01*
X726902Y-16846D01*
X727194Y-17054D01*
X727402Y-17304D01*
X727569Y-17721D01*
X727611Y-18096D01*
X727527Y-18471D01*
X727402Y-18721D01*
X727152Y-18971D01*
X726861Y-19138D01*
X726569Y-19221D01*
X726277D01*
X725986Y-19138D01*
X725736Y-19013D01*
X725527Y-18846D01*
G01X724261Y-18179D02*
X723969Y-17888D01*
X723719Y-17721D01*
X723386Y-17638D01*
X723094Y-17721D01*
X722886Y-17888D01*
X722719Y-18138D01*
X722677Y-18429D01*
X722719Y-18679D01*
X722886Y-18929D01*
X723136Y-19138D01*
X723427Y-19221D01*
X723761Y-19138D01*
X724052Y-18888D01*
X724219Y-18513D01*
X724261Y-18096D01*
X724177Y-17554D01*
X724052Y-17263D01*
X723844Y-16971D01*
X723552Y-16763D01*
X723261Y-16721D01*
X722969Y-16804D01*
X722761Y-17013D01*
G01X721619Y-16721D02*
X721036Y-19221D01*
X720369Y-16721D01*
X719702Y-19221D01*
X719119Y-16721D01*
G01X717269Y-19221D02*
Y-16721D01*
X717769Y-17221D01*
G01Y-19221D02*
X716769D01*
G01X714169D02*
Y-16721D01*
X714669Y-17221D01*
G01Y-19221D02*
X713669D01*
G01X700483Y11250D02*
Y13750D01*
X699442D01*
X699108Y13625D01*
X698900Y13458D01*
X698817Y13125D01*
X698900Y12792D01*
X699150Y12583D01*
X699442Y12458D01*
X700483D01*
G01X699442D02*
X698817Y11250D01*
G01X697342Y12292D02*
X697050Y12583D01*
X696800Y12750D01*
X696467Y12833D01*
X696175Y12750D01*
X695967Y12583D01*
X695800Y12333D01*
X695758Y12042D01*
X695800Y11792D01*
X695967Y11542D01*
X696217Y11333D01*
X696508Y11250D01*
X696842Y11333D01*
X697133Y11583D01*
X697300Y11958D01*
X697342Y12375D01*
X697258Y12917D01*
X697133Y13208D01*
X696925Y13500D01*
X696633Y13708D01*
X696342Y13750D01*
X696050Y13667D01*
X695842Y13458D01*
G01X694367Y13750D02*
Y11958D01*
X694200Y11583D01*
X693867Y11333D01*
X693450Y11250D01*
X693033Y11333D01*
X692700Y11583D01*
X692533Y11958D01*
Y13750D01*
G01X690433Y11250D02*
X690350Y11792D01*
X690225Y12250D01*
X690058Y12667D01*
X689850Y13125D01*
X689517Y13750D01*
X691183D01*
G01X709050Y-10333D02*
X711550D01*
Y-9292D01*
X711425Y-8958D01*
X711258Y-8750D01*
X710925Y-8667D01*
X710592Y-8750D01*
X710383Y-9000D01*
X710258Y-9292D01*
Y-10333D01*
G01Y-9292D02*
X709050Y-8667D01*
G01X710092Y-7192D02*
X710383Y-6900D01*
X710550Y-6650D01*
X710633Y-6317D01*
X710550Y-6025D01*
X710383Y-5817D01*
X710133Y-5650D01*
X709842Y-5608D01*
X709592Y-5650D01*
X709342Y-5817D01*
X709133Y-6067D01*
X709050Y-6358D01*
X709133Y-6692D01*
X709383Y-6983D01*
X709758Y-7150D01*
X710175Y-7192D01*
X710717Y-7108D01*
X711008Y-6983D01*
X711300Y-6775D01*
X711508Y-6483D01*
X711550Y-6192D01*
X711467Y-5900D01*
X711258Y-5692D01*
G01X711550Y-4217D02*
X709758D01*
X709383Y-4050D01*
X709133Y-3717D01*
X709050Y-3300D01*
X709133Y-2883D01*
X709383Y-2550D01*
X709758Y-2383D01*
X711550D01*
G01X709050Y-200D02*
X711550D01*
X711050Y-700D01*
G01X709050D02*
Y300D01*
G01X709425Y1983D02*
X709217Y2233D01*
X709092Y2525D01*
X709050Y2900D01*
X709133Y3275D01*
X709300Y3567D01*
X709592Y3775D01*
X709925Y3817D01*
X710258Y3733D01*
X710467Y3525D01*
X710633Y3233D01*
X710675Y2942D01*
X710633Y2650D01*
X710467Y2275D01*
X711550Y2400D01*
Y3525D01*
G01X701709Y16615D02*
Y19115D01*
X700668D01*
X700334Y18990D01*
X700126Y18823D01*
X700043Y18490D01*
X700126Y18157D01*
X700376Y17948D01*
X700668Y17823D01*
X701709D01*
G01X700668D02*
X700043Y16615D01*
G01X698568Y17657D02*
X698276Y17948D01*
X698026Y18115D01*
X697693Y18198D01*
X697401Y18115D01*
X697193Y17948D01*
X697026Y17698D01*
X696984Y17407D01*
X697026Y17157D01*
X697193Y16907D01*
X697443Y16698D01*
X697734Y16615D01*
X698068Y16698D01*
X698359Y16948D01*
X698526Y17323D01*
X698568Y17740D01*
X698484Y18282D01*
X698359Y18573D01*
X698151Y18865D01*
X697859Y19073D01*
X697568Y19115D01*
X697276Y19032D01*
X697068Y18823D01*
G01X695593Y19115D02*
Y17323D01*
X695426Y16948D01*
X695093Y16698D01*
X694676Y16615D01*
X694259Y16698D01*
X693926Y16948D01*
X693759Y17323D01*
Y19115D01*
G01X692368Y17657D02*
X692076Y17948D01*
X691826Y18115D01*
X691493Y18198D01*
X691201Y18115D01*
X690993Y17948D01*
X690826Y17698D01*
X690784Y17407D01*
X690826Y17157D01*
X690993Y16907D01*
X691243Y16698D01*
X691534Y16615D01*
X691868Y16698D01*
X692159Y16948D01*
X692326Y17323D01*
X692368Y17740D01*
X692284Y18282D01*
X692159Y18573D01*
X691951Y18865D01*
X691659Y19073D01*
X691368Y19115D01*
X691076Y19032D01*
X690868Y18823D01*
G01X709042Y6617D02*
X709167Y6367D01*
X709250Y6075D01*
Y5742D01*
X709125Y5367D01*
X708917Y5075D01*
X708667Y4867D01*
X708250Y4700D01*
X707875Y4658D01*
X707500Y4742D01*
X707250Y4867D01*
X707000Y5117D01*
X706833Y5408D01*
X706750Y5700D01*
Y5992D01*
X706833Y6283D01*
X706958Y6533D01*
X707125Y6742D01*
G01X707792Y8008D02*
X708083Y8300D01*
X708250Y8550D01*
X708333Y8883D01*
X708250Y9175D01*
X708083Y9383D01*
X707833Y9550D01*
X707542Y9592D01*
X707292Y9550D01*
X707042Y9383D01*
X706833Y9133D01*
X706750Y8842D01*
X706833Y8508D01*
X707083Y8217D01*
X707458Y8050D01*
X707875Y8008D01*
X708417Y8092D01*
X708708Y8217D01*
X709000Y8425D01*
X709208Y8717D01*
X709250Y9008D01*
X709167Y9300D01*
X708958Y9508D01*
G01X709250Y10983D02*
X707458D01*
X707083Y11150D01*
X706833Y11483D01*
X706750Y11900D01*
X706833Y12317D01*
X707083Y12650D01*
X707458Y12817D01*
X709250D01*
G01X706750Y15000D02*
X709250D01*
X708750Y14500D01*
G01X706750D02*
Y15500D01*
G01X708833Y17308D02*
X709083Y17558D01*
X709208Y17850D01*
X709250Y18183D01*
X709167Y18600D01*
X708958Y18892D01*
X708708Y18975D01*
X708458Y18933D01*
X708250Y18767D01*
X707833Y17933D01*
X707542Y17558D01*
X707125Y17308D01*
X706750Y17225D01*
Y18975D01*
G01X697483Y25142D02*
X697733Y25267D01*
X698025Y25350D01*
X698358D01*
X698733Y25225D01*
X699025Y25017D01*
X699233Y24767D01*
X699400Y24350D01*
X699442Y23975D01*
X699358Y23600D01*
X699233Y23350D01*
X698983Y23100D01*
X698692Y22933D01*
X698400Y22850D01*
X698108D01*
X697817Y22933D01*
X697567Y23058D01*
X697358Y23225D01*
G01X696092Y23892D02*
X695800Y24183D01*
X695550Y24350D01*
X695217Y24433D01*
X694925Y24350D01*
X694717Y24183D01*
X694550Y23933D01*
X694508Y23642D01*
X694550Y23392D01*
X694717Y23142D01*
X694967Y22933D01*
X695258Y22850D01*
X695592Y22933D01*
X695883Y23183D01*
X696050Y23558D01*
X696092Y23975D01*
X696008Y24517D01*
X695883Y24808D01*
X695675Y25100D01*
X695383Y25308D01*
X695092Y25350D01*
X694800Y25267D01*
X694592Y25058D01*
G01X693117Y25350D02*
Y23558D01*
X692950Y23183D01*
X692617Y22933D01*
X692200Y22850D01*
X691783Y22933D01*
X691450Y23183D01*
X691283Y23558D01*
Y25350D01*
G01X689100Y22850D02*
Y25350D01*
X689600Y24850D01*
G01Y22850D02*
X688600D01*
G01X686000D02*
Y25350D01*
X686500Y24850D01*
G01Y22850D02*
X685500D01*
G01X716151Y35894D02*
X716401Y36019D01*
X716693Y36102D01*
X717026D01*
X717401Y35977D01*
X717693Y35769D01*
X717901Y35519D01*
X718068Y35102D01*
X718110Y34727D01*
X718026Y34352D01*
X717901Y34102D01*
X717651Y33852D01*
X717360Y33685D01*
X717068Y33602D01*
X716776D01*
X716485Y33685D01*
X716235Y33810D01*
X716026Y33977D01*
G01X714760Y35685D02*
X714510Y35935D01*
X714218Y36060D01*
X713885Y36102D01*
X713468Y36019D01*
X713176Y35810D01*
X713093Y35560D01*
X713135Y35310D01*
X713301Y35102D01*
X714135Y34685D01*
X714510Y34394D01*
X714760Y33977D01*
X714843Y33602D01*
X713093D01*
G01X711660Y35685D02*
X711410Y35935D01*
X711118Y36060D01*
X710785Y36102D01*
X710368Y36019D01*
X710076Y35810D01*
X709993Y35560D01*
X710035Y35310D01*
X710201Y35102D01*
X711035Y34685D01*
X711410Y34394D01*
X711660Y33977D01*
X711743Y33602D01*
X709993D01*
G01X709018Y36102D02*
X708435Y33602D01*
X707768Y36102D01*
X707101Y33602D01*
X706518Y36102D01*
G01X705460Y34644D02*
X705168Y34935D01*
X704918Y35102D01*
X704585Y35185D01*
X704293Y35102D01*
X704085Y34935D01*
X703918Y34685D01*
X703876Y34394D01*
X703918Y34144D01*
X704085Y33894D01*
X704335Y33685D01*
X704626Y33602D01*
X704960Y33685D01*
X705251Y33935D01*
X705418Y34310D01*
X705460Y34727D01*
X705376Y35269D01*
X705251Y35560D01*
X705043Y35852D01*
X704751Y36060D01*
X704460Y36102D01*
X704168Y36019D01*
X703960Y35810D01*
G01X713407Y44959D02*
X713657Y45084D01*
X713949Y45167D01*
X714282D01*
X714657Y45042D01*
X714949Y44834D01*
X715157Y44584D01*
X715324Y44167D01*
X715366Y43792D01*
X715282Y43417D01*
X715157Y43167D01*
X714907Y42917D01*
X714616Y42750D01*
X714324Y42667D01*
X714032D01*
X713741Y42750D01*
X713491Y42875D01*
X713282Y43042D01*
G01X712016Y43709D02*
X711724Y44000D01*
X711474Y44167D01*
X711141Y44250D01*
X710849Y44167D01*
X710641Y44000D01*
X710474Y43750D01*
X710432Y43459D01*
X710474Y43209D01*
X710641Y42959D01*
X710891Y42750D01*
X711182Y42667D01*
X711516Y42750D01*
X711807Y43000D01*
X711974Y43375D01*
X712016Y43792D01*
X711932Y44334D01*
X711807Y44625D01*
X711599Y44917D01*
X711307Y45125D01*
X711016Y45167D01*
X710724Y45084D01*
X710516Y44875D01*
G01X709041Y45167D02*
Y43375D01*
X708874Y43000D01*
X708541Y42750D01*
X708124Y42667D01*
X707707Y42750D01*
X707374Y43000D01*
X707207Y43375D01*
Y45167D01*
G01X705107Y42667D02*
X705024Y43209D01*
X704899Y43667D01*
X704732Y44084D01*
X704524Y44542D01*
X704191Y45167D01*
X705857D01*
G01X677133Y62692D02*
X677383Y62817D01*
X677675Y62900D01*
X678008D01*
X678383Y62775D01*
X678675Y62567D01*
X678883Y62317D01*
X679050Y61900D01*
X679092Y61525D01*
X679008Y61150D01*
X678883Y60900D01*
X678633Y60650D01*
X678342Y60483D01*
X678050Y60400D01*
X677758D01*
X677467Y60483D01*
X677217Y60608D01*
X677008Y60775D01*
G01X675742Y61442D02*
X675450Y61733D01*
X675200Y61900D01*
X674867Y61983D01*
X674575Y61900D01*
X674367Y61733D01*
X674200Y61483D01*
X674158Y61192D01*
X674200Y60942D01*
X674367Y60692D01*
X674617Y60483D01*
X674908Y60400D01*
X675242Y60483D01*
X675533Y60733D01*
X675700Y61108D01*
X675742Y61525D01*
X675658Y62067D01*
X675533Y62358D01*
X675325Y62650D01*
X675033Y62858D01*
X674742Y62900D01*
X674450Y62817D01*
X674242Y62608D01*
G01X672767Y62900D02*
Y61108D01*
X672600Y60733D01*
X672267Y60483D01*
X671850Y60400D01*
X671433Y60483D01*
X671100Y60733D01*
X670933Y61108D01*
Y62900D01*
G01X669542Y62483D02*
X669292Y62733D01*
X669000Y62858D01*
X668667Y62900D01*
X668250Y62817D01*
X667958Y62608D01*
X667875Y62358D01*
X667917Y62108D01*
X668083Y61900D01*
X668917Y61483D01*
X669292Y61192D01*
X669542Y60775D01*
X669625Y60400D01*
X667875D01*
G01X677133Y58692D02*
X677383Y58817D01*
X677675Y58900D01*
X678008D01*
X678383Y58775D01*
X678675Y58567D01*
X678883Y58317D01*
X679050Y57900D01*
X679092Y57525D01*
X679008Y57150D01*
X678883Y56900D01*
X678633Y56650D01*
X678342Y56483D01*
X678050Y56400D01*
X677758D01*
X677467Y56483D01*
X677217Y56608D01*
X677008Y56775D01*
G01X675742Y57442D02*
X675450Y57733D01*
X675200Y57900D01*
X674867Y57983D01*
X674575Y57900D01*
X674367Y57733D01*
X674200Y57483D01*
X674158Y57192D01*
X674200Y56942D01*
X674367Y56692D01*
X674617Y56483D01*
X674908Y56400D01*
X675242Y56483D01*
X675533Y56733D01*
X675700Y57108D01*
X675742Y57525D01*
X675658Y58067D01*
X675533Y58358D01*
X675325Y58650D01*
X675033Y58858D01*
X674742Y58900D01*
X674450Y58817D01*
X674242Y58608D01*
G01X672767Y58900D02*
Y57108D01*
X672600Y56733D01*
X672267Y56483D01*
X671850Y56400D01*
X671433Y56483D01*
X671100Y56733D01*
X670933Y57108D01*
Y58900D01*
G01X669667Y56900D02*
X669417Y56608D01*
X669083Y56442D01*
X668708Y56400D01*
X668375Y56442D01*
X668042Y56650D01*
X667833Y56900D01*
X667792Y57150D01*
X667875Y57442D01*
X668167Y57650D01*
X668458Y57733D01*
X668833D01*
G01X668458D02*
X668208Y57858D01*
X668000Y58067D01*
X667917Y58317D01*
X668000Y58567D01*
X668208Y58775D01*
X668583Y58900D01*
X668958Y58858D01*
X669333Y58692D01*
G01X717407Y66780D02*
X719907D01*
Y67821D01*
X719782Y68155D01*
X719615Y68363D01*
X719282Y68446D01*
X718949Y68363D01*
X718740Y68113D01*
X718615Y67821D01*
Y66780D01*
G01Y67821D02*
X717407Y68446D01*
G01X718449Y69921D02*
X718740Y70213D01*
X718907Y70463D01*
X718990Y70796D01*
X718907Y71088D01*
X718740Y71296D01*
X718490Y71463D01*
X718199Y71505D01*
X717949Y71463D01*
X717699Y71296D01*
X717490Y71046D01*
X717407Y70755D01*
X717490Y70421D01*
X717740Y70130D01*
X718115Y69963D01*
X718532Y69921D01*
X719074Y70005D01*
X719365Y70130D01*
X719657Y70338D01*
X719865Y70630D01*
X719907Y70921D01*
X719824Y71213D01*
X719615Y71421D01*
G01X719907Y73813D02*
X717407D01*
G01X719907Y72855D02*
Y74771D01*
G01X717407Y76913D02*
X717449Y77205D01*
X717574Y77538D01*
X717782Y77746D01*
X718074Y77830D01*
X718365Y77746D01*
X718615Y77496D01*
X718740Y77121D01*
Y76705D01*
X718824Y76455D01*
X719032Y76246D01*
X719324Y76163D01*
X719615Y76288D01*
X719824Y76580D01*
X719907Y76913D01*
X719824Y77246D01*
X719615Y77538D01*
X719324Y77663D01*
X719032Y77580D01*
X718824Y77371D01*
X718740Y77121D01*
Y76705D01*
X718615Y76330D01*
X718365Y76080D01*
X718074Y75996D01*
X717782Y76080D01*
X717574Y76288D01*
X717449Y76621D01*
X717407Y76913D01*
G01X713907Y66780D02*
X716407D01*
Y67821D01*
X716282Y68155D01*
X716115Y68363D01*
X715782Y68446D01*
X715449Y68363D01*
X715240Y68113D01*
X715115Y67821D01*
Y66780D01*
G01Y67821D02*
X713907Y68446D01*
G01X714949Y69921D02*
X715240Y70213D01*
X715407Y70463D01*
X715490Y70796D01*
X715407Y71088D01*
X715240Y71296D01*
X714990Y71463D01*
X714699Y71505D01*
X714449Y71463D01*
X714199Y71296D01*
X713990Y71046D01*
X713907Y70755D01*
X713990Y70421D01*
X714240Y70130D01*
X714615Y69963D01*
X715032Y69921D01*
X715574Y70005D01*
X715865Y70130D01*
X716157Y70338D01*
X716365Y70630D01*
X716407Y70921D01*
X716324Y71213D01*
X716115Y71421D01*
G01X716407Y73813D02*
X713907D01*
G01X716407Y72855D02*
Y74771D01*
G01X714199Y76205D02*
X713990Y76496D01*
X713907Y76830D01*
X713990Y77163D01*
X714240Y77455D01*
X714615Y77663D01*
X714990Y77746D01*
X715449D01*
X715824Y77663D01*
X716157Y77455D01*
X716324Y77205D01*
X716407Y76913D01*
X716324Y76580D01*
X716157Y76330D01*
X715907Y76163D01*
X715574Y76080D01*
X715282Y76163D01*
X714990Y76371D01*
X714824Y76621D01*
X714782Y76913D01*
X714865Y77246D01*
X715074Y77496D01*
X715449Y77746D01*
G01X712236Y71007D02*
Y73507D01*
X711195D01*
X710861Y73382D01*
X710653Y73215D01*
X710570Y72882D01*
X710653Y72549D01*
X710903Y72340D01*
X711195Y72215D01*
X712236D01*
G01X711195D02*
X710570Y71007D01*
G01X709095Y72049D02*
X708803Y72340D01*
X708553Y72507D01*
X708220Y72590D01*
X707928Y72507D01*
X707720Y72340D01*
X707553Y72090D01*
X707511Y71799D01*
X707553Y71549D01*
X707720Y71299D01*
X707970Y71090D01*
X708261Y71007D01*
X708595Y71090D01*
X708886Y71340D01*
X709053Y71715D01*
X709095Y72132D01*
X709011Y72674D01*
X708886Y72965D01*
X708678Y73257D01*
X708386Y73465D01*
X708095Y73507D01*
X707803Y73424D01*
X707595Y73215D01*
G01X705203Y73507D02*
Y71007D01*
G01X706161Y73507D02*
X704245D01*
G01X702186Y71007D02*
X702103Y71549D01*
X701978Y72007D01*
X701811Y72424D01*
X701603Y72882D01*
X701270Y73507D01*
X702936D01*
G01X706883Y74300D02*
Y76800D01*
X705842D01*
X705508Y76675D01*
X705300Y76508D01*
X705217Y76175D01*
X705300Y75842D01*
X705550Y75633D01*
X705842Y75508D01*
X706883D01*
G01X705842D02*
X705217Y74300D01*
G01X703742Y75342D02*
X703450Y75633D01*
X703200Y75800D01*
X702867Y75883D01*
X702575Y75800D01*
X702367Y75633D01*
X702200Y75383D01*
X702158Y75092D01*
X702200Y74842D01*
X702367Y74592D01*
X702617Y74383D01*
X702908Y74300D01*
X703242Y74383D01*
X703533Y74633D01*
X703700Y75008D01*
X703742Y75425D01*
X703658Y75967D01*
X703533Y76258D01*
X703325Y76550D01*
X703033Y76758D01*
X702742Y76800D01*
X702450Y76717D01*
X702242Y76508D01*
G01X699850Y76800D02*
Y74300D01*
G01X700808Y76800D02*
X698892D01*
G01X697542Y75342D02*
X697250Y75633D01*
X697000Y75800D01*
X696667Y75883D01*
X696375Y75800D01*
X696167Y75633D01*
X696000Y75383D01*
X695958Y75092D01*
X696000Y74842D01*
X696167Y74592D01*
X696417Y74383D01*
X696708Y74300D01*
X697042Y74383D01*
X697333Y74633D01*
X697500Y75008D01*
X697542Y75425D01*
X697458Y75967D01*
X697333Y76258D01*
X697125Y76550D01*
X696833Y76758D01*
X696542Y76800D01*
X696250Y76717D01*
X696042Y76508D01*
G01X688900Y71917D02*
X691400D01*
Y72958D01*
X691275Y73292D01*
X691108Y73500D01*
X690775Y73583D01*
X690442Y73500D01*
X690233Y73250D01*
X690108Y72958D01*
Y71917D01*
G01Y72958D02*
X688900Y73583D01*
G01X689942Y75058D02*
X690233Y75350D01*
X690400Y75600D01*
X690483Y75933D01*
X690400Y76225D01*
X690233Y76433D01*
X689983Y76600D01*
X689692Y76642D01*
X689442Y76600D01*
X689192Y76433D01*
X688983Y76183D01*
X688900Y75892D01*
X688983Y75558D01*
X689233Y75267D01*
X689608Y75100D01*
X690025Y75058D01*
X690567Y75142D01*
X690858Y75267D01*
X691150Y75475D01*
X691358Y75767D01*
X691400Y76058D01*
X691317Y76350D01*
X691108Y76558D01*
G01X691400Y78950D02*
X688900D01*
G01X691400Y77992D02*
Y79908D01*
G01X689275Y81133D02*
X689067Y81383D01*
X688942Y81675D01*
X688900Y82050D01*
X688983Y82425D01*
X689150Y82717D01*
X689442Y82925D01*
X689775Y82967D01*
X690108Y82883D01*
X690317Y82675D01*
X690483Y82383D01*
X690525Y82092D01*
X690483Y81800D01*
X690317Y81425D01*
X691400Y81550D01*
Y82675D01*
G01X677392Y41717D02*
X677517Y41467D01*
X677600Y41175D01*
Y40842D01*
X677475Y40467D01*
X677267Y40175D01*
X677017Y39967D01*
X676600Y39800D01*
X676225Y39758D01*
X675850Y39842D01*
X675600Y39967D01*
X675350Y40217D01*
X675183Y40508D01*
X675100Y40800D01*
Y41092D01*
X675183Y41383D01*
X675308Y41633D01*
X675475Y41842D01*
G01X676142Y43108D02*
X676433Y43400D01*
X676600Y43650D01*
X676683Y43983D01*
X676600Y44275D01*
X676433Y44483D01*
X676183Y44650D01*
X675892Y44692D01*
X675642Y44650D01*
X675392Y44483D01*
X675183Y44233D01*
X675100Y43942D01*
X675183Y43608D01*
X675433Y43317D01*
X675808Y43150D01*
X676225Y43108D01*
X676767Y43192D01*
X677058Y43317D01*
X677350Y43525D01*
X677558Y43817D01*
X677600Y44108D01*
X677517Y44400D01*
X677308Y44608D01*
G01X677600Y46083D02*
X675808D01*
X675433Y46250D01*
X675183Y46583D01*
X675100Y47000D01*
X675183Y47417D01*
X675433Y47750D01*
X675808Y47917D01*
X677600D01*
G01X676142Y49308D02*
X676433Y49600D01*
X676600Y49850D01*
X676683Y50183D01*
X676600Y50475D01*
X676433Y50683D01*
X676183Y50850D01*
X675892Y50892D01*
X675642Y50850D01*
X675392Y50683D01*
X675183Y50433D01*
X675100Y50142D01*
X675183Y49808D01*
X675433Y49517D01*
X675808Y49350D01*
X676225Y49308D01*
X676767Y49392D01*
X677058Y49517D01*
X677350Y49725D01*
X677558Y50017D01*
X677600Y50308D01*
X677517Y50600D01*
X677308Y50808D01*
G01X727292Y53567D02*
X727417Y53317D01*
X727500Y53025D01*
Y52692D01*
X727375Y52317D01*
X727167Y52025D01*
X726917Y51817D01*
X726500Y51650D01*
X726125Y51608D01*
X725750Y51692D01*
X725500Y51817D01*
X725250Y52067D01*
X725083Y52358D01*
X725000Y52650D01*
Y52942D01*
X725083Y53233D01*
X725208Y53483D01*
X725375Y53692D01*
G01X726042Y54958D02*
X726333Y55250D01*
X726500Y55500D01*
X726583Y55833D01*
X726500Y56125D01*
X726333Y56333D01*
X726083Y56500D01*
X725792Y56542D01*
X725542Y56500D01*
X725292Y56333D01*
X725083Y56083D01*
X725000Y55792D01*
X725083Y55458D01*
X725333Y55167D01*
X725708Y55000D01*
X726125Y54958D01*
X726667Y55042D01*
X726958Y55167D01*
X727250Y55375D01*
X727458Y55667D01*
X727500Y55958D01*
X727417Y56250D01*
X727208Y56458D01*
G01X727500Y57933D02*
X725708D01*
X725333Y58100D01*
X725083Y58433D01*
X725000Y58850D01*
X725083Y59267D01*
X725333Y59600D01*
X725708Y59767D01*
X727500D01*
G01X725375Y61033D02*
X725167Y61283D01*
X725042Y61575D01*
X725000Y61950D01*
X725083Y62325D01*
X725250Y62617D01*
X725542Y62825D01*
X725875Y62867D01*
X726208Y62783D01*
X726417Y62575D01*
X726583Y62283D01*
X726625Y61992D01*
X726583Y61700D01*
X726417Y61325D01*
X727500Y61450D01*
Y62575D01*
G01X694127Y184110D02*
X694377Y184235D01*
X694669Y184318D01*
X695002D01*
X695377Y184193D01*
X695669Y183985D01*
X695877Y183735D01*
X696044Y183318D01*
X696086Y182943D01*
X696002Y182568D01*
X695877Y182318D01*
X695627Y182068D01*
X695336Y181901D01*
X695044Y181818D01*
X694752D01*
X694461Y181901D01*
X694211Y182026D01*
X694002Y182193D01*
G01X692736Y182860D02*
X692444Y183151D01*
X692194Y183318D01*
X691861Y183401D01*
X691569Y183318D01*
X691361Y183151D01*
X691194Y182901D01*
X691152Y182610D01*
X691194Y182360D01*
X691361Y182110D01*
X691611Y181901D01*
X691902Y181818D01*
X692236Y181901D01*
X692527Y182151D01*
X692694Y182526D01*
X692736Y182943D01*
X692652Y183485D01*
X692527Y183776D01*
X692319Y184068D01*
X692027Y184276D01*
X691736Y184318D01*
X691444Y184235D01*
X691236Y184026D01*
G01X689677Y181818D02*
Y184318D01*
X688636D01*
X688302Y184193D01*
X688094Y184026D01*
X688011Y183693D01*
X688094Y183360D01*
X688344Y183151D01*
X688636Y183026D01*
X689677D01*
G01X688636D02*
X688011Y181818D01*
G01X685744D02*
Y184318D01*
X686244Y183818D01*
G01Y181818D02*
X685244D01*
G01X682144D02*
Y184318D01*
X683686Y182526D01*
X681602D01*
G01X694127Y191110D02*
X694377Y191235D01*
X694669Y191318D01*
X695002D01*
X695377Y191193D01*
X695669Y190985D01*
X695877Y190735D01*
X696044Y190318D01*
X696086Y189943D01*
X696002Y189568D01*
X695877Y189318D01*
X695627Y189068D01*
X695336Y188901D01*
X695044Y188818D01*
X694752D01*
X694461Y188901D01*
X694211Y189026D01*
X694002Y189193D01*
G01X692736Y189860D02*
X692444Y190151D01*
X692194Y190318D01*
X691861Y190401D01*
X691569Y190318D01*
X691361Y190151D01*
X691194Y189901D01*
X691152Y189610D01*
X691194Y189360D01*
X691361Y189110D01*
X691611Y188901D01*
X691902Y188818D01*
X692236Y188901D01*
X692527Y189151D01*
X692694Y189526D01*
X692736Y189943D01*
X692652Y190485D01*
X692527Y190776D01*
X692319Y191068D01*
X692027Y191276D01*
X691736Y191318D01*
X691444Y191235D01*
X691236Y191026D01*
G01X689677Y188818D02*
Y191318D01*
X688636D01*
X688302Y191193D01*
X688094Y191026D01*
X688011Y190693D01*
X688094Y190360D01*
X688344Y190151D01*
X688636Y190026D01*
X689677D01*
G01X688636D02*
X688011Y188818D01*
G01X685744D02*
X685452Y188860D01*
X685119Y188985D01*
X684911Y189193D01*
X684827Y189485D01*
X684911Y189776D01*
X685161Y190026D01*
X685536Y190151D01*
X685952D01*
X686202Y190235D01*
X686411Y190443D01*
X686494Y190735D01*
X686369Y191026D01*
X686077Y191235D01*
X685744Y191318D01*
X685411Y191235D01*
X685119Y191026D01*
X684994Y190735D01*
X685077Y190443D01*
X685286Y190235D01*
X685536Y190151D01*
X685952D01*
X686327Y190026D01*
X686577Y189776D01*
X686661Y189485D01*
X686577Y189193D01*
X686369Y188985D01*
X686036Y188860D01*
X685744Y188818D01*
G01X694127Y187610D02*
X694377Y187735D01*
X694669Y187818D01*
X695002D01*
X695377Y187693D01*
X695669Y187485D01*
X695877Y187235D01*
X696044Y186818D01*
X696086Y186443D01*
X696002Y186068D01*
X695877Y185818D01*
X695627Y185568D01*
X695336Y185401D01*
X695044Y185318D01*
X694752D01*
X694461Y185401D01*
X694211Y185526D01*
X694002Y185693D01*
G01X692736Y186360D02*
X692444Y186651D01*
X692194Y186818D01*
X691861Y186901D01*
X691569Y186818D01*
X691361Y186651D01*
X691194Y186401D01*
X691152Y186110D01*
X691194Y185860D01*
X691361Y185610D01*
X691611Y185401D01*
X691902Y185318D01*
X692236Y185401D01*
X692527Y185651D01*
X692694Y186026D01*
X692736Y186443D01*
X692652Y186985D01*
X692527Y187276D01*
X692319Y187568D01*
X692027Y187776D01*
X691736Y187818D01*
X691444Y187735D01*
X691236Y187526D01*
G01X689677Y185318D02*
Y187818D01*
X688636D01*
X688302Y187693D01*
X688094Y187526D01*
X688011Y187193D01*
X688094Y186860D01*
X688344Y186651D01*
X688636Y186526D01*
X689677D01*
G01X688636D02*
X688011Y185318D01*
G01X685744D02*
Y187818D01*
X686244Y187318D01*
G01Y185318D02*
X685244D01*
G01X682644Y187818D02*
X682977Y187735D01*
X683227Y187526D01*
X683394Y187276D01*
X683519Y186943D01*
X683561Y186568D01*
X683519Y186193D01*
X683394Y185860D01*
X683227Y185610D01*
X682977Y185401D01*
X682644Y185318D01*
X682311Y185401D01*
X682061Y185610D01*
X681894Y185860D01*
X681769Y186193D01*
X681727Y186568D01*
X681769Y186943D01*
X681894Y187276D01*
X682061Y187526D01*
X682311Y187735D01*
X682644Y187818D01*
G01X695877Y192318D02*
Y194818D01*
X694836D01*
X694502Y194693D01*
X694294Y194526D01*
X694211Y194193D01*
X694294Y193860D01*
X694544Y193651D01*
X694836Y193526D01*
X695877D01*
G01X694836D02*
X694211Y192318D01*
G01X692736Y193360D02*
X692444Y193651D01*
X692194Y193818D01*
X691861Y193901D01*
X691569Y193818D01*
X691361Y193651D01*
X691194Y193401D01*
X691152Y193110D01*
X691194Y192860D01*
X691361Y192610D01*
X691611Y192401D01*
X691902Y192318D01*
X692236Y192401D01*
X692527Y192651D01*
X692694Y193026D01*
X692736Y193443D01*
X692652Y193985D01*
X692527Y194276D01*
X692319Y194568D01*
X692027Y194776D01*
X691736Y194818D01*
X691444Y194735D01*
X691236Y194526D01*
G01X689677Y192318D02*
Y194818D01*
X688636D01*
X688302Y194693D01*
X688094Y194526D01*
X688011Y194193D01*
X688094Y193860D01*
X688344Y193651D01*
X688636Y193526D01*
X689677D01*
G01X688636D02*
X688011Y192318D01*
G01X686661Y192693D02*
X686411Y192485D01*
X686119Y192360D01*
X685744Y192318D01*
X685369Y192401D01*
X685077Y192568D01*
X684869Y192860D01*
X684827Y193193D01*
X684911Y193526D01*
X685119Y193735D01*
X685411Y193901D01*
X685702Y193943D01*
X685994Y193901D01*
X686369Y193735D01*
X686244Y194818D01*
X685119D01*
G01X723636Y202000D02*
Y205791D01*
X736432D01*
Y202000D01*
G01X723636Y189400D02*
Y185838D01*
X736432D01*
Y189400D01*
G01X678500Y208500D02*
Y211198D01*
G01X670209Y276279D02*
X672709D01*
Y277320D01*
X672584Y277654D01*
X672417Y277862D01*
X672084Y277945D01*
X671751Y277862D01*
X671542Y277612D01*
X671417Y277320D01*
Y276279D01*
G01Y277320D02*
X670209Y277945D01*
G01X671251Y279420D02*
X671542Y279712D01*
X671709Y279962D01*
X671792Y280295D01*
X671709Y280587D01*
X671542Y280795D01*
X671292Y280962D01*
X671001Y281004D01*
X670751Y280962D01*
X670501Y280795D01*
X670292Y280545D01*
X670209Y280254D01*
X670292Y279920D01*
X670542Y279629D01*
X670917Y279462D01*
X671334Y279420D01*
X671876Y279504D01*
X672167Y279629D01*
X672459Y279837D01*
X672667Y280129D01*
X672709Y280420D01*
X672626Y280712D01*
X672417Y280920D01*
G01X670209Y282479D02*
X672709D01*
Y283479D01*
X672584Y283812D01*
X672292Y284062D01*
X671959Y284145D01*
X671626Y284062D01*
X671376Y283854D01*
X671251Y283479D01*
Y282479D01*
G01X672292Y285620D02*
X672542Y285870D01*
X672667Y286162D01*
X672709Y286495D01*
X672626Y286912D01*
X672417Y287204D01*
X672167Y287287D01*
X671917Y287245D01*
X671709Y287079D01*
X671292Y286245D01*
X671001Y285870D01*
X670584Y285620D01*
X670209Y285537D01*
Y287287D01*
G01Y289512D02*
X672709D01*
X672209Y289012D01*
G01X670209D02*
Y290012D01*
G01X706000Y248767D02*
X708500D01*
Y249808D01*
X708375Y250142D01*
X708208Y250350D01*
X707875Y250433D01*
X707542Y250350D01*
X707333Y250100D01*
X707208Y249808D01*
Y248767D01*
G01Y249808D02*
X706000Y250433D01*
G01X707042Y251908D02*
X707333Y252200D01*
X707500Y252450D01*
X707583Y252783D01*
X707500Y253075D01*
X707333Y253283D01*
X707083Y253450D01*
X706792Y253492D01*
X706542Y253450D01*
X706292Y253283D01*
X706083Y253033D01*
X706000Y252742D01*
X706083Y252408D01*
X706333Y252117D01*
X706708Y251950D01*
X707125Y251908D01*
X707667Y251992D01*
X707958Y252117D01*
X708250Y252325D01*
X708458Y252617D01*
X708500Y252908D01*
X708417Y253200D01*
X708208Y253408D01*
G01X706000Y254967D02*
X708500D01*
Y255967D01*
X708375Y256300D01*
X708083Y256550D01*
X707750Y256633D01*
X707417Y256550D01*
X707167Y256342D01*
X707042Y255967D01*
Y254967D01*
G01X706000Y259400D02*
X708500D01*
X706708Y257858D01*
Y259942D01*
G01X706375Y261083D02*
X706167Y261333D01*
X706042Y261625D01*
X706000Y262000D01*
X706083Y262375D01*
X706250Y262667D01*
X706542Y262875D01*
X706875Y262917D01*
X707208Y262833D01*
X707417Y262625D01*
X707583Y262333D01*
X707625Y262042D01*
X707583Y261750D01*
X707417Y261375D01*
X708500Y261500D01*
Y262625D01*
G01X702865Y254924D02*
Y257424D01*
X701824D01*
X701490Y257299D01*
X701282Y257132D01*
X701199Y256799D01*
X701282Y256466D01*
X701532Y256257D01*
X701824Y256132D01*
X702865D01*
G01X701824D02*
X701199Y254924D01*
G01X699724Y255966D02*
X699432Y256257D01*
X699182Y256424D01*
X698849Y256507D01*
X698557Y256424D01*
X698349Y256257D01*
X698182Y256007D01*
X698140Y255716D01*
X698182Y255466D01*
X698349Y255216D01*
X698599Y255007D01*
X698890Y254924D01*
X699224Y255007D01*
X699515Y255257D01*
X699682Y255632D01*
X699724Y256049D01*
X699640Y256591D01*
X699515Y256882D01*
X699307Y257174D01*
X699015Y257382D01*
X698724Y257424D01*
X698432Y257341D01*
X698224Y257132D01*
G01X696665Y254924D02*
Y257424D01*
X695665D01*
X695332Y257299D01*
X695082Y257007D01*
X694999Y256674D01*
X695082Y256341D01*
X695290Y256091D01*
X695665Y255966D01*
X696665D01*
G01X692232Y254924D02*
Y257424D01*
X693774Y255632D01*
X691690D01*
G01X690340Y255216D02*
X690049Y255007D01*
X689715Y254924D01*
X689382Y255007D01*
X689090Y255257D01*
X688882Y255632D01*
X688799Y256007D01*
Y256466D01*
X688882Y256841D01*
X689090Y257174D01*
X689340Y257341D01*
X689632Y257424D01*
X689965Y257341D01*
X690215Y257174D01*
X690382Y256924D01*
X690465Y256591D01*
X690382Y256299D01*
X690174Y256007D01*
X689924Y255841D01*
X689632Y255799D01*
X689299Y255882D01*
X689049Y256091D01*
X688799Y256466D01*
G01X721300Y267110D02*
X723800D01*
Y268151D01*
X723675Y268485D01*
X723508Y268693D01*
X723175Y268776D01*
X722842Y268693D01*
X722633Y268443D01*
X722508Y268151D01*
Y267110D01*
G01Y268151D02*
X721300Y268776D01*
G01X722342Y270251D02*
X722633Y270543D01*
X722800Y270793D01*
X722883Y271126D01*
X722800Y271418D01*
X722633Y271626D01*
X722383Y271793D01*
X722092Y271835D01*
X721842Y271793D01*
X721592Y271626D01*
X721383Y271376D01*
X721300Y271085D01*
X721383Y270751D01*
X721633Y270460D01*
X722008Y270293D01*
X722425Y270251D01*
X722967Y270335D01*
X723258Y270460D01*
X723550Y270668D01*
X723758Y270960D01*
X723800Y271251D01*
X723717Y271543D01*
X723508Y271751D01*
G01X721300Y273310D02*
X723800D01*
Y274310D01*
X723675Y274643D01*
X723383Y274893D01*
X723050Y274976D01*
X722717Y274893D01*
X722467Y274685D01*
X722342Y274310D01*
Y273310D01*
G01X723383Y276451D02*
X723633Y276701D01*
X723758Y276993D01*
X723800Y277326D01*
X723717Y277743D01*
X723508Y278035D01*
X723258Y278118D01*
X723008Y278076D01*
X722800Y277910D01*
X722383Y277076D01*
X722092Y276701D01*
X721675Y276451D01*
X721300Y276368D01*
Y278118D01*
G01Y280343D02*
X721342Y280635D01*
X721467Y280968D01*
X721675Y281176D01*
X721967Y281260D01*
X722258Y281176D01*
X722508Y280926D01*
X722633Y280551D01*
Y280135D01*
X722717Y279885D01*
X722925Y279676D01*
X723217Y279593D01*
X723508Y279718D01*
X723717Y280010D01*
X723800Y280343D01*
X723717Y280676D01*
X723508Y280968D01*
X723217Y281093D01*
X722925Y281010D01*
X722717Y280801D01*
X722633Y280551D01*
Y280135D01*
X722508Y279760D01*
X722258Y279510D01*
X721967Y279426D01*
X721675Y279510D01*
X721467Y279718D01*
X721342Y280051D01*
X721300Y280343D01*
G01X717922Y264034D02*
Y266534D01*
X716881D01*
X716547Y266409D01*
X716339Y266242D01*
X716256Y265909D01*
X716339Y265576D01*
X716589Y265367D01*
X716881Y265242D01*
X717922D01*
G01X716881D02*
X716256Y264034D01*
G01X714781Y265076D02*
X714489Y265367D01*
X714239Y265534D01*
X713906Y265617D01*
X713614Y265534D01*
X713406Y265367D01*
X713239Y265117D01*
X713197Y264826D01*
X713239Y264576D01*
X713406Y264326D01*
X713656Y264117D01*
X713947Y264034D01*
X714281Y264117D01*
X714572Y264367D01*
X714739Y264742D01*
X714781Y265159D01*
X714697Y265701D01*
X714572Y265992D01*
X714364Y266284D01*
X714072Y266492D01*
X713781Y266534D01*
X713489Y266451D01*
X713281Y266242D01*
G01X711722Y264034D02*
Y266534D01*
X710722D01*
X710389Y266409D01*
X710139Y266117D01*
X710056Y265784D01*
X710139Y265451D01*
X710347Y265201D01*
X710722Y265076D01*
X711722D01*
G01X708706Y264534D02*
X708456Y264242D01*
X708122Y264076D01*
X707747Y264034D01*
X707414Y264076D01*
X707081Y264284D01*
X706872Y264534D01*
X706831Y264784D01*
X706914Y265076D01*
X707206Y265284D01*
X707497Y265367D01*
X707872D01*
G01X707497D02*
X707247Y265492D01*
X707039Y265701D01*
X706956Y265951D01*
X707039Y266201D01*
X707247Y266409D01*
X707622Y266534D01*
X707997Y266492D01*
X708372Y266326D01*
G01X704772Y264034D02*
X704689Y264576D01*
X704564Y265034D01*
X704397Y265451D01*
X704189Y265909D01*
X703856Y266534D01*
X705522D01*
G01X704821Y276394D02*
Y278894D01*
X703780D01*
X703446Y278769D01*
X703238Y278602D01*
X703155Y278269D01*
X703238Y277936D01*
X703488Y277727D01*
X703780Y277602D01*
X704821D01*
G01X703780D02*
X703155Y276394D01*
G01X701680Y277436D02*
X701388Y277727D01*
X701138Y277894D01*
X700805Y277977D01*
X700513Y277894D01*
X700305Y277727D01*
X700138Y277477D01*
X700096Y277186D01*
X700138Y276936D01*
X700305Y276686D01*
X700555Y276477D01*
X700846Y276394D01*
X701180Y276477D01*
X701471Y276727D01*
X701638Y277102D01*
X701680Y277519D01*
X701596Y278061D01*
X701471Y278352D01*
X701263Y278644D01*
X700971Y278852D01*
X700680Y278894D01*
X700388Y278811D01*
X700180Y278602D01*
G01X698621Y276394D02*
Y278894D01*
X697621D01*
X697288Y278769D01*
X697038Y278477D01*
X696955Y278144D01*
X697038Y277811D01*
X697246Y277561D01*
X697621Y277436D01*
X698621D01*
G01X695605Y276894D02*
X695355Y276602D01*
X695021Y276436D01*
X694646Y276394D01*
X694313Y276436D01*
X693980Y276644D01*
X693771Y276894D01*
X693730Y277144D01*
X693813Y277436D01*
X694105Y277644D01*
X694396Y277727D01*
X694771D01*
G01X694396D02*
X694146Y277852D01*
X693938Y278061D01*
X693855Y278311D01*
X693938Y278561D01*
X694146Y278769D01*
X694521Y278894D01*
X694896Y278852D01*
X695271Y278686D01*
G01X692380Y278477D02*
X692130Y278727D01*
X691838Y278852D01*
X691505Y278894D01*
X691088Y278811D01*
X690796Y278602D01*
X690713Y278352D01*
X690755Y278102D01*
X690921Y277894D01*
X691755Y277477D01*
X692130Y277186D01*
X692380Y276769D01*
X692463Y276394D01*
X690713D01*
G01X678500Y229800D02*
Y232498D01*
G01Y247800D02*
Y245105D01*
G01Y226500D02*
Y223805D01*
G01X692498Y264072D02*
X692831Y264114D01*
X693123Y264280D01*
X693373Y264530D01*
X693540Y264822D01*
X693623Y265155D01*
Y265489D01*
X693540Y265822D01*
X693373Y266114D01*
X693123Y266364D01*
X692831Y266530D01*
X692498Y266572D01*
X692165Y266530D01*
X691873Y266364D01*
X691623Y266114D01*
X691456Y265822D01*
X691373Y265489D01*
Y265155D01*
X691456Y264822D01*
X691623Y264530D01*
X691873Y264280D01*
X692165Y264114D01*
X692498Y264072D01*
G01X692165Y264739D02*
X691665Y264072D01*
G01X688898D02*
Y266572D01*
X690440Y264780D01*
X688356D01*
G01X687548Y266572D02*
X686965Y264072D01*
X686298Y266572D01*
X685631Y264072D01*
X685048Y266572D01*
G01X683990Y266155D02*
X683740Y266405D01*
X683448Y266530D01*
X683115Y266572D01*
X682698Y266489D01*
X682406Y266280D01*
X682323Y266030D01*
X682365Y265780D01*
X682531Y265572D01*
X683365Y265155D01*
X683740Y264864D01*
X683990Y264447D01*
X684073Y264072D01*
X682323D01*
G01X683704Y272776D02*
Y275276D01*
G01X685954Y268026D02*
X689204D01*
Y271526D01*
G01X685954Y280026D02*
X689204D01*
Y276526D01*
G01X668102Y262375D02*
X668227Y262125D01*
X668310Y261833D01*
Y261500D01*
X668185Y261125D01*
X667977Y260833D01*
X667727Y260625D01*
X667310Y260458D01*
X666935Y260416D01*
X666560Y260500D01*
X666310Y260625D01*
X666060Y260875D01*
X665893Y261166D01*
X665810Y261458D01*
Y261750D01*
X665893Y262041D01*
X666018Y262291D01*
X666185Y262500D01*
G01X665810Y263766D02*
X668310D01*
Y265350D01*
G01X667102Y264766D02*
Y263766D01*
G01X665810Y267658D02*
X668310D01*
X667810Y267158D01*
G01X665810D02*
Y268158D01*
G01Y271258D02*
X668310D01*
X666518Y269716D01*
Y271800D01*
G01X702972Y231127D02*
X703222Y231252D01*
X703514Y231335D01*
X703847D01*
X704222Y231210D01*
X704514Y231002D01*
X704722Y230752D01*
X704889Y230335D01*
X704931Y229960D01*
X704847Y229585D01*
X704722Y229335D01*
X704472Y229085D01*
X704181Y228918D01*
X703889Y228835D01*
X703597D01*
X703306Y228918D01*
X703056Y229043D01*
X702847Y229210D01*
G01X700289Y228835D02*
Y231335D01*
X701831Y229543D01*
X699747D01*
G01X696856Y228835D02*
X698522D01*
Y231335D01*
X696856D01*
G01X697522Y230127D02*
X698522D01*
G01X695381Y230918D02*
X695131Y231168D01*
X694839Y231293D01*
X694506Y231335D01*
X694089Y231252D01*
X693797Y231043D01*
X693714Y230793D01*
X693756Y230543D01*
X693922Y230335D01*
X694756Y229918D01*
X695131Y229627D01*
X695381Y229210D01*
X695464Y228835D01*
X693714D01*
G01X691489D02*
X691197Y228877D01*
X690864Y229002D01*
X690656Y229210D01*
X690572Y229502D01*
X690656Y229793D01*
X690906Y230043D01*
X691281Y230168D01*
X691697D01*
X691947Y230252D01*
X692156Y230460D01*
X692239Y230752D01*
X692114Y231043D01*
X691822Y231252D01*
X691489Y231335D01*
X691156Y231252D01*
X690864Y231043D01*
X690739Y230752D01*
X690822Y230460D01*
X691031Y230252D01*
X691281Y230168D01*
X691697D01*
X692072Y230043D01*
X692322Y229793D01*
X692406Y229502D01*
X692322Y229210D01*
X692114Y229002D01*
X691781Y228877D01*
X691489Y228835D01*
G01X695834Y236216D02*
X695959Y235966D01*
X696042Y235674D01*
Y235341D01*
X695917Y234966D01*
X695709Y234674D01*
X695459Y234466D01*
X695042Y234299D01*
X694667Y234257D01*
X694292Y234341D01*
X694042Y234466D01*
X693792Y234716D01*
X693625Y235007D01*
X693542Y235299D01*
Y235591D01*
X693625Y235882D01*
X693750Y236132D01*
X693917Y236341D01*
G01X695625Y237607D02*
X695875Y237857D01*
X696000Y238149D01*
X696042Y238482D01*
X695959Y238899D01*
X695750Y239191D01*
X695500Y239274D01*
X695250Y239232D01*
X695042Y239066D01*
X694625Y238232D01*
X694334Y237857D01*
X693917Y237607D01*
X693542Y237524D01*
Y239274D01*
G01X695625Y240707D02*
X695875Y240957D01*
X696000Y241249D01*
X696042Y241582D01*
X695959Y241999D01*
X695750Y242291D01*
X695500Y242374D01*
X695250Y242332D01*
X695042Y242166D01*
X694625Y241332D01*
X694334Y240957D01*
X693917Y240707D01*
X693542Y240624D01*
Y242374D01*
G01X696042Y243349D02*
X693542Y243932D01*
X696042Y244599D01*
X693542Y245266D01*
X696042Y245849D01*
G01X695625Y246907D02*
X695875Y247157D01*
X696000Y247449D01*
X696042Y247782D01*
X695959Y248199D01*
X695750Y248491D01*
X695500Y248574D01*
X695250Y248532D01*
X695042Y248366D01*
X694625Y247532D01*
X694334Y247157D01*
X693917Y246907D01*
X693542Y246824D01*
Y248574D01*
G01X696042Y250799D02*
X695959Y250466D01*
X695750Y250216D01*
X695500Y250049D01*
X695167Y249924D01*
X694792Y249882D01*
X694417Y249924D01*
X694084Y250049D01*
X693834Y250216D01*
X693625Y250466D01*
X693542Y250799D01*
X693625Y251132D01*
X693834Y251382D01*
X694084Y251549D01*
X694417Y251674D01*
X694792Y251716D01*
X695167Y251674D01*
X695500Y251549D01*
X695750Y251382D01*
X695959Y251132D01*
X696042Y250799D01*
G01X700455Y236927D02*
X700580Y236677D01*
X700663Y236385D01*
Y236052D01*
X700538Y235677D01*
X700330Y235385D01*
X700080Y235177D01*
X699663Y235010D01*
X699288Y234968D01*
X698913Y235052D01*
X698663Y235177D01*
X698413Y235427D01*
X698246Y235718D01*
X698163Y236010D01*
Y236302D01*
X698246Y236593D01*
X698371Y236843D01*
X698538Y237052D01*
G01X700246Y238318D02*
X700496Y238568D01*
X700621Y238860D01*
X700663Y239193D01*
X700580Y239610D01*
X700371Y239902D01*
X700121Y239985D01*
X699871Y239943D01*
X699663Y239777D01*
X699246Y238943D01*
X698955Y238568D01*
X698538Y238318D01*
X698163Y238235D01*
Y239985D01*
G01X700246Y241418D02*
X700496Y241668D01*
X700621Y241960D01*
X700663Y242293D01*
X700580Y242710D01*
X700371Y243002D01*
X700121Y243085D01*
X699871Y243043D01*
X699663Y242877D01*
X699246Y242043D01*
X698955Y241668D01*
X698538Y241418D01*
X698163Y241335D01*
Y243085D01*
G01X700663Y244060D02*
X698163Y244643D01*
X700663Y245310D01*
X698163Y245977D01*
X700663Y246560D01*
G01X698163Y248410D02*
X700663D01*
X700163Y247910D01*
G01X698163D02*
Y248910D01*
G01Y251510D02*
X698205Y251802D01*
X698330Y252135D01*
X698538Y252343D01*
X698830Y252427D01*
X699121Y252343D01*
X699371Y252093D01*
X699496Y251718D01*
Y251302D01*
X699580Y251052D01*
X699788Y250843D01*
X700080Y250760D01*
X700371Y250885D01*
X700580Y251177D01*
X700663Y251510D01*
X700580Y251843D01*
X700371Y252135D01*
X700080Y252260D01*
X699788Y252177D01*
X699580Y251968D01*
X699496Y251718D01*
Y251302D01*
X699371Y250927D01*
X699121Y250677D01*
X698830Y250593D01*
X698538Y250677D01*
X698330Y250885D01*
X698205Y251218D01*
X698163Y251510D01*
G01X728020Y244060D02*
X728145Y243810D01*
X728228Y243518D01*
Y243185D01*
X728103Y242810D01*
X727895Y242518D01*
X727645Y242310D01*
X727228Y242143D01*
X726853Y242101D01*
X726478Y242185D01*
X726228Y242310D01*
X725978Y242560D01*
X725811Y242851D01*
X725728Y243143D01*
Y243435D01*
X725811Y243726D01*
X725936Y243976D01*
X726103Y244185D01*
G01X727811Y245451D02*
X728061Y245701D01*
X728186Y245993D01*
X728228Y246326D01*
X728145Y246743D01*
X727936Y247035D01*
X727686Y247118D01*
X727436Y247076D01*
X727228Y246910D01*
X726811Y246076D01*
X726520Y245701D01*
X726103Y245451D01*
X725728Y245368D01*
Y247118D01*
G01X727811Y248551D02*
X728061Y248801D01*
X728186Y249093D01*
X728228Y249426D01*
X728145Y249843D01*
X727936Y250135D01*
X727686Y250218D01*
X727436Y250176D01*
X727228Y250010D01*
X726811Y249176D01*
X726520Y248801D01*
X726103Y248551D01*
X725728Y248468D01*
Y250218D01*
G01X728228Y251193D02*
X725728Y251776D01*
X728228Y252443D01*
X725728Y253110D01*
X728228Y253693D01*
G01X725728Y255543D02*
X728228D01*
X727728Y255043D01*
G01X725728D02*
Y256043D01*
G01Y259143D02*
X728228D01*
X726436Y257601D01*
Y259685D01*
G01X728483Y312600D02*
Y315100D01*
X727442D01*
X727108Y314975D01*
X726900Y314808D01*
X726817Y314475D01*
X726900Y314142D01*
X727150Y313933D01*
X727442Y313808D01*
X728483D01*
G01X727442D02*
X726817Y312600D01*
G01X725342Y313642D02*
X725050Y313933D01*
X724800Y314100D01*
X724467Y314183D01*
X724175Y314100D01*
X723967Y313933D01*
X723800Y313683D01*
X723758Y313392D01*
X723800Y313142D01*
X723967Y312892D01*
X724217Y312683D01*
X724508Y312600D01*
X724842Y312683D01*
X725133Y312933D01*
X725300Y313308D01*
X725342Y313725D01*
X725258Y314267D01*
X725133Y314558D01*
X724925Y314850D01*
X724633Y315058D01*
X724342Y315100D01*
X724050Y315017D01*
X723842Y314808D01*
G01X722283Y312600D02*
Y315100D01*
X721283D01*
X720950Y314975D01*
X720700Y314683D01*
X720617Y314350D01*
X720700Y314017D01*
X720908Y313767D01*
X721283Y313642D01*
X722283D01*
G01X718350Y312600D02*
Y315100D01*
X718850Y314600D01*
G01Y312600D02*
X717850D01*
G01X715333D02*
X715250Y313142D01*
X715125Y313600D01*
X714958Y314017D01*
X714750Y314475D01*
X714417Y315100D01*
X716083D01*
G01X677598Y287597D02*
X680098D01*
Y288638D01*
X679973Y288972D01*
X679806Y289180D01*
X679473Y289263D01*
X679140Y289180D01*
X678931Y288930D01*
X678806Y288638D01*
Y287597D01*
G01Y288638D02*
X677598Y289263D01*
G01X678640Y290738D02*
X678931Y291030D01*
X679098Y291280D01*
X679181Y291613D01*
X679098Y291905D01*
X678931Y292113D01*
X678681Y292280D01*
X678390Y292322D01*
X678140Y292280D01*
X677890Y292113D01*
X677681Y291863D01*
X677598Y291572D01*
X677681Y291238D01*
X677931Y290947D01*
X678306Y290780D01*
X678723Y290738D01*
X679265Y290822D01*
X679556Y290947D01*
X679848Y291155D01*
X680056Y291447D01*
X680098Y291738D01*
X680015Y292030D01*
X679806Y292238D01*
G01X677598Y293797D02*
X680098D01*
Y294797D01*
X679973Y295130D01*
X679681Y295380D01*
X679348Y295463D01*
X679015Y295380D01*
X678765Y295172D01*
X678640Y294797D01*
Y293797D01*
G01X679681Y296938D02*
X679931Y297188D01*
X680056Y297480D01*
X680098Y297813D01*
X680015Y298230D01*
X679806Y298522D01*
X679556Y298605D01*
X679306Y298563D01*
X679098Y298397D01*
X678681Y297563D01*
X678390Y297188D01*
X677973Y296938D01*
X677598Y296855D01*
Y298605D01*
G01X680098Y300830D02*
X680015Y300497D01*
X679806Y300247D01*
X679556Y300080D01*
X679223Y299955D01*
X678848Y299913D01*
X678473Y299955D01*
X678140Y300080D01*
X677890Y300247D01*
X677681Y300497D01*
X677598Y300830D01*
X677681Y301163D01*
X677890Y301413D01*
X678140Y301580D01*
X678473Y301705D01*
X678848Y301747D01*
X679223Y301705D01*
X679556Y301580D01*
X679806Y301413D01*
X680015Y301163D01*
X680098Y300830D01*
G01X728483Y330100D02*
Y332600D01*
X727442D01*
X727108Y332475D01*
X726900Y332308D01*
X726817Y331975D01*
X726900Y331642D01*
X727150Y331433D01*
X727442Y331308D01*
X728483D01*
G01X727442D02*
X726817Y330100D01*
G01X725342Y331142D02*
X725050Y331433D01*
X724800Y331600D01*
X724467Y331683D01*
X724175Y331600D01*
X723967Y331433D01*
X723800Y331183D01*
X723758Y330892D01*
X723800Y330642D01*
X723967Y330392D01*
X724217Y330183D01*
X724508Y330100D01*
X724842Y330183D01*
X725133Y330433D01*
X725300Y330808D01*
X725342Y331225D01*
X725258Y331767D01*
X725133Y332058D01*
X724925Y332350D01*
X724633Y332558D01*
X724342Y332600D01*
X724050Y332517D01*
X723842Y332308D01*
G01X722283Y330100D02*
Y332600D01*
X721283D01*
X720950Y332475D01*
X720700Y332183D01*
X720617Y331850D01*
X720700Y331517D01*
X720908Y331267D01*
X721283Y331142D01*
X722283D01*
G01X718350Y330100D02*
Y332600D01*
X718850Y332100D01*
G01Y330100D02*
X717850D01*
G01X715250D02*
Y332600D01*
X715750Y332100D01*
G01Y330100D02*
X714750D01*
G01X728281Y333532D02*
Y336032D01*
X727240D01*
X726906Y335907D01*
X726698Y335740D01*
X726615Y335407D01*
X726698Y335074D01*
X726948Y334865D01*
X727240Y334740D01*
X728281D01*
G01X727240D02*
X726615Y333532D01*
G01X725140Y334574D02*
X724848Y334865D01*
X724598Y335032D01*
X724265Y335115D01*
X723973Y335032D01*
X723765Y334865D01*
X723598Y334615D01*
X723556Y334324D01*
X723598Y334074D01*
X723765Y333824D01*
X724015Y333615D01*
X724306Y333532D01*
X724640Y333615D01*
X724931Y333865D01*
X725098Y334240D01*
X725140Y334657D01*
X725056Y335199D01*
X724931Y335490D01*
X724723Y335782D01*
X724431Y335990D01*
X724140Y336032D01*
X723848Y335949D01*
X723640Y335740D01*
G01X722081Y333532D02*
Y336032D01*
X721081D01*
X720748Y335907D01*
X720498Y335615D01*
X720415Y335282D01*
X720498Y334949D01*
X720706Y334699D01*
X721081Y334574D01*
X722081D01*
G01X718856Y333824D02*
X718565Y333615D01*
X718231Y333532D01*
X717898Y333615D01*
X717606Y333865D01*
X717398Y334240D01*
X717315Y334615D01*
Y335074D01*
X717398Y335449D01*
X717606Y335782D01*
X717856Y335949D01*
X718148Y336032D01*
X718481Y335949D01*
X718731Y335782D01*
X718898Y335532D01*
X718981Y335199D01*
X718898Y334907D01*
X718690Y334615D01*
X718440Y334449D01*
X718148Y334407D01*
X717815Y334490D01*
X717565Y334699D01*
X717315Y335074D01*
G01X728483Y326600D02*
Y329100D01*
X727442D01*
X727108Y328975D01*
X726900Y328808D01*
X726817Y328475D01*
X726900Y328142D01*
X727150Y327933D01*
X727442Y327808D01*
X728483D01*
G01X727442D02*
X726817Y326600D01*
G01X725342Y327642D02*
X725050Y327933D01*
X724800Y328100D01*
X724467Y328183D01*
X724175Y328100D01*
X723967Y327933D01*
X723800Y327683D01*
X723758Y327392D01*
X723800Y327142D01*
X723967Y326892D01*
X724217Y326683D01*
X724508Y326600D01*
X724842Y326683D01*
X725133Y326933D01*
X725300Y327308D01*
X725342Y327725D01*
X725258Y328267D01*
X725133Y328558D01*
X724925Y328850D01*
X724633Y329058D01*
X724342Y329100D01*
X724050Y329017D01*
X723842Y328808D01*
G01X722283Y326600D02*
Y329100D01*
X721283D01*
X720950Y328975D01*
X720700Y328683D01*
X720617Y328350D01*
X720700Y328017D01*
X720908Y327767D01*
X721283Y327642D01*
X722283D01*
G01X718350Y326600D02*
Y329100D01*
X718850Y328600D01*
G01Y326600D02*
X717850D01*
G01X716042Y328683D02*
X715792Y328933D01*
X715500Y329058D01*
X715167Y329100D01*
X714750Y329017D01*
X714458Y328808D01*
X714375Y328558D01*
X714417Y328308D01*
X714583Y328100D01*
X715417Y327683D01*
X715792Y327392D01*
X716042Y326975D01*
X716125Y326600D01*
X714375D01*
G01X729433Y302100D02*
Y304600D01*
X728392D01*
X728058Y304475D01*
X727850Y304308D01*
X727767Y303975D01*
X727850Y303642D01*
X728100Y303433D01*
X728392Y303308D01*
X729433D01*
G01X728392D02*
X727767Y302100D01*
G01X726292Y303142D02*
X726000Y303433D01*
X725750Y303600D01*
X725417Y303683D01*
X725125Y303600D01*
X724917Y303433D01*
X724750Y303183D01*
X724708Y302892D01*
X724750Y302642D01*
X724917Y302392D01*
X725167Y302183D01*
X725458Y302100D01*
X725792Y302183D01*
X726083Y302433D01*
X726250Y302808D01*
X726292Y303225D01*
X726208Y303767D01*
X726083Y304058D01*
X725875Y304350D01*
X725583Y304558D01*
X725292Y304600D01*
X725000Y304517D01*
X724792Y304308D01*
G01X723233Y302100D02*
Y304600D01*
X722233D01*
X721900Y304475D01*
X721650Y304183D01*
X721567Y303850D01*
X721650Y303517D01*
X721858Y303267D01*
X722233Y303142D01*
X723233D01*
G01X719300Y302100D02*
Y304600D01*
X719800Y304100D01*
G01Y302100D02*
X718800D01*
G01X716992Y303142D02*
X716700Y303433D01*
X716450Y303600D01*
X716117Y303683D01*
X715825Y303600D01*
X715617Y303433D01*
X715450Y303183D01*
X715408Y302892D01*
X715450Y302642D01*
X715617Y302392D01*
X715867Y302183D01*
X716158Y302100D01*
X716492Y302183D01*
X716783Y302433D01*
X716950Y302808D01*
X716992Y303225D01*
X716908Y303767D01*
X716783Y304058D01*
X716575Y304350D01*
X716283Y304558D01*
X715992Y304600D01*
X715700Y304517D01*
X715492Y304308D01*
G01X729433Y298600D02*
Y301100D01*
X728392D01*
X728058Y300975D01*
X727850Y300808D01*
X727767Y300475D01*
X727850Y300142D01*
X728100Y299933D01*
X728392Y299808D01*
X729433D01*
G01X728392D02*
X727767Y298600D01*
G01X726292Y299642D02*
X726000Y299933D01*
X725750Y300100D01*
X725417Y300183D01*
X725125Y300100D01*
X724917Y299933D01*
X724750Y299683D01*
X724708Y299392D01*
X724750Y299142D01*
X724917Y298892D01*
X725167Y298683D01*
X725458Y298600D01*
X725792Y298683D01*
X726083Y298933D01*
X726250Y299308D01*
X726292Y299725D01*
X726208Y300267D01*
X726083Y300558D01*
X725875Y300850D01*
X725583Y301058D01*
X725292Y301100D01*
X725000Y301017D01*
X724792Y300808D01*
G01X723233Y298600D02*
Y301100D01*
X722233D01*
X721900Y300975D01*
X721650Y300683D01*
X721567Y300350D01*
X721650Y300017D01*
X721858Y299767D01*
X722233Y299642D01*
X723233D01*
G01X719300Y298600D02*
Y301100D01*
X719800Y300600D01*
G01Y298600D02*
X718800D01*
G01X716200D02*
X715908Y298642D01*
X715575Y298767D01*
X715367Y298975D01*
X715283Y299267D01*
X715367Y299558D01*
X715617Y299808D01*
X715992Y299933D01*
X716408D01*
X716658Y300017D01*
X716867Y300225D01*
X716950Y300517D01*
X716825Y300808D01*
X716533Y301017D01*
X716200Y301100D01*
X715867Y301017D01*
X715575Y300808D01*
X715450Y300517D01*
X715533Y300225D01*
X715742Y300017D01*
X715992Y299933D01*
X716408D01*
X716783Y299808D01*
X717033Y299558D01*
X717117Y299267D01*
X717033Y298975D01*
X716825Y298767D01*
X716492Y298642D01*
X716200Y298600D01*
G01X728483Y323100D02*
Y325600D01*
X727442D01*
X727108Y325475D01*
X726900Y325308D01*
X726817Y324975D01*
X726900Y324642D01*
X727150Y324433D01*
X727442Y324308D01*
X728483D01*
G01X727442D02*
X726817Y323100D01*
G01X725342Y324142D02*
X725050Y324433D01*
X724800Y324600D01*
X724467Y324683D01*
X724175Y324600D01*
X723967Y324433D01*
X723800Y324183D01*
X723758Y323892D01*
X723800Y323642D01*
X723967Y323392D01*
X724217Y323183D01*
X724508Y323100D01*
X724842Y323183D01*
X725133Y323433D01*
X725300Y323808D01*
X725342Y324225D01*
X725258Y324767D01*
X725133Y325058D01*
X724925Y325350D01*
X724633Y325558D01*
X724342Y325600D01*
X724050Y325517D01*
X723842Y325308D01*
G01X722283Y323100D02*
Y325600D01*
X721283D01*
X720950Y325475D01*
X720700Y325183D01*
X720617Y324850D01*
X720700Y324517D01*
X720908Y324267D01*
X721283Y324142D01*
X722283D01*
G01X718350Y323100D02*
Y325600D01*
X718850Y325100D01*
G01Y323100D02*
X717850D01*
G01X716167Y323600D02*
X715917Y323308D01*
X715583Y323142D01*
X715208Y323100D01*
X714875Y323142D01*
X714542Y323350D01*
X714333Y323600D01*
X714292Y323850D01*
X714375Y324142D01*
X714667Y324350D01*
X714958Y324433D01*
X715333D01*
G01X714958D02*
X714708Y324558D01*
X714500Y324767D01*
X714417Y325017D01*
X714500Y325267D01*
X714708Y325475D01*
X715083Y325600D01*
X715458Y325558D01*
X715833Y325392D01*
G01X728483Y316100D02*
Y318600D01*
X727442D01*
X727108Y318475D01*
X726900Y318308D01*
X726817Y317975D01*
X726900Y317642D01*
X727150Y317433D01*
X727442Y317308D01*
X728483D01*
G01X727442D02*
X726817Y316100D01*
G01X725342Y317142D02*
X725050Y317433D01*
X724800Y317600D01*
X724467Y317683D01*
X724175Y317600D01*
X723967Y317433D01*
X723800Y317183D01*
X723758Y316892D01*
X723800Y316642D01*
X723967Y316392D01*
X724217Y316183D01*
X724508Y316100D01*
X724842Y316183D01*
X725133Y316433D01*
X725300Y316808D01*
X725342Y317225D01*
X725258Y317767D01*
X725133Y318058D01*
X724925Y318350D01*
X724633Y318558D01*
X724342Y318600D01*
X724050Y318517D01*
X723842Y318308D01*
G01X722283Y316100D02*
Y318600D01*
X721283D01*
X720950Y318475D01*
X720700Y318183D01*
X720617Y317850D01*
X720700Y317517D01*
X720908Y317267D01*
X721283Y317142D01*
X722283D01*
G01X718350Y316100D02*
Y318600D01*
X718850Y318100D01*
G01Y316100D02*
X717850D01*
G01X716167Y316475D02*
X715917Y316267D01*
X715625Y316142D01*
X715250Y316100D01*
X714875Y316183D01*
X714583Y316350D01*
X714375Y316642D01*
X714333Y316975D01*
X714417Y317308D01*
X714625Y317517D01*
X714917Y317683D01*
X715208Y317725D01*
X715500Y317683D01*
X715875Y317517D01*
X715750Y318600D01*
X714625D01*
G01X702857Y290837D02*
Y293337D01*
X701816D01*
X701482Y293212D01*
X701274Y293045D01*
X701191Y292712D01*
X701274Y292379D01*
X701524Y292170D01*
X701816Y292045D01*
X702857D01*
G01X701816D02*
X701191Y290837D01*
G01X698424D02*
Y293337D01*
X699966Y291545D01*
X697882D01*
G01X697074Y293337D02*
X696491Y290837D01*
X695824Y293337D01*
X695157Y290837D01*
X694574Y293337D01*
G01X693516Y292920D02*
X693266Y293170D01*
X692974Y293295D01*
X692641Y293337D01*
X692224Y293254D01*
X691932Y293045D01*
X691849Y292795D01*
X691891Y292545D01*
X692057Y292337D01*
X692891Y291920D01*
X693266Y291629D01*
X693516Y291212D01*
X693599Y290837D01*
X691849D01*
G01X711194Y322346D02*
X711444Y322471D01*
X711736Y322554D01*
X712069D01*
X712444Y322429D01*
X712736Y322221D01*
X712944Y321971D01*
X713111Y321554D01*
X713153Y321179D01*
X713069Y320804D01*
X712944Y320554D01*
X712694Y320304D01*
X712403Y320137D01*
X712111Y320054D01*
X711819D01*
X711528Y320137D01*
X711278Y320262D01*
X711069Y320429D01*
G01X709803Y321096D02*
X709511Y321387D01*
X709261Y321554D01*
X708928Y321637D01*
X708636Y321554D01*
X708428Y321387D01*
X708261Y321137D01*
X708219Y320846D01*
X708261Y320596D01*
X708428Y320346D01*
X708678Y320137D01*
X708969Y320054D01*
X709303Y320137D01*
X709594Y320387D01*
X709761Y320762D01*
X709803Y321179D01*
X709719Y321721D01*
X709594Y322012D01*
X709386Y322304D01*
X709094Y322512D01*
X708803Y322554D01*
X708511Y322471D01*
X708303Y322262D01*
G01X706744Y320054D02*
Y322554D01*
X705744D01*
X705411Y322429D01*
X705161Y322137D01*
X705078Y321804D01*
X705161Y321471D01*
X705369Y321221D01*
X705744Y321096D01*
X706744D01*
G01X702811Y320054D02*
Y322554D01*
X703311Y322054D01*
G01Y320054D02*
X702311D01*
G01X699711D02*
Y322554D01*
X700211Y322054D01*
G01Y320054D02*
X699211D01*
G01X708810Y326784D02*
X709060Y326909D01*
X709352Y326992D01*
X709685D01*
X710060Y326867D01*
X710352Y326659D01*
X710560Y326409D01*
X710727Y325992D01*
X710769Y325617D01*
X710685Y325242D01*
X710560Y324992D01*
X710310Y324742D01*
X710019Y324575D01*
X709727Y324492D01*
X709435D01*
X709144Y324575D01*
X708894Y324700D01*
X708685Y324867D01*
G01X707419Y325534D02*
X707127Y325825D01*
X706877Y325992D01*
X706544Y326075D01*
X706252Y325992D01*
X706044Y325825D01*
X705877Y325575D01*
X705835Y325284D01*
X705877Y325034D01*
X706044Y324784D01*
X706294Y324575D01*
X706585Y324492D01*
X706919Y324575D01*
X707210Y324825D01*
X707377Y325200D01*
X707419Y325617D01*
X707335Y326159D01*
X707210Y326450D01*
X707002Y326742D01*
X706710Y326950D01*
X706419Y326992D01*
X706127Y326909D01*
X705919Y326700D01*
G01X704360Y324492D02*
Y326992D01*
X703360D01*
X703027Y326867D01*
X702777Y326575D01*
X702694Y326242D01*
X702777Y325909D01*
X702985Y325659D01*
X703360Y325534D01*
X704360D01*
G01X701135Y324784D02*
X700844Y324575D01*
X700510Y324492D01*
X700177Y324575D01*
X699885Y324825D01*
X699677Y325200D01*
X699594Y325575D01*
Y326034D01*
X699677Y326409D01*
X699885Y326742D01*
X700135Y326909D01*
X700427Y326992D01*
X700760Y326909D01*
X701010Y326742D01*
X701177Y326492D01*
X701260Y326159D01*
X701177Y325867D01*
X700969Y325575D01*
X700719Y325409D01*
X700427Y325367D01*
X700094Y325450D01*
X699844Y325659D01*
X699594Y326034D01*
G01X710216Y335679D02*
X710466Y335804D01*
X710758Y335887D01*
X711091D01*
X711466Y335762D01*
X711758Y335554D01*
X711966Y335304D01*
X712133Y334887D01*
X712175Y334512D01*
X712091Y334137D01*
X711966Y333887D01*
X711716Y333637D01*
X711425Y333470D01*
X711133Y333387D01*
X710841D01*
X710550Y333470D01*
X710300Y333595D01*
X710091Y333762D01*
G01X708825Y334429D02*
X708533Y334720D01*
X708283Y334887D01*
X707950Y334970D01*
X707658Y334887D01*
X707450Y334720D01*
X707283Y334470D01*
X707241Y334179D01*
X707283Y333929D01*
X707450Y333679D01*
X707700Y333470D01*
X707991Y333387D01*
X708325Y333470D01*
X708616Y333720D01*
X708783Y334095D01*
X708825Y334512D01*
X708741Y335054D01*
X708616Y335345D01*
X708408Y335637D01*
X708116Y335845D01*
X707825Y335887D01*
X707533Y335804D01*
X707325Y335595D01*
G01X705766Y333387D02*
Y335887D01*
X704766D01*
X704433Y335762D01*
X704183Y335470D01*
X704100Y335137D01*
X704183Y334804D01*
X704391Y334554D01*
X704766Y334429D01*
X705766D01*
G01X702625D02*
X702333Y334720D01*
X702083Y334887D01*
X701750Y334970D01*
X701458Y334887D01*
X701250Y334720D01*
X701083Y334470D01*
X701041Y334179D01*
X701083Y333929D01*
X701250Y333679D01*
X701500Y333470D01*
X701791Y333387D01*
X702125Y333470D01*
X702416Y333720D01*
X702583Y334095D01*
X702625Y334512D01*
X702541Y335054D01*
X702416Y335345D01*
X702208Y335637D01*
X701916Y335845D01*
X701625Y335887D01*
X701333Y335804D01*
X701125Y335595D01*
G01X680519Y337140D02*
X680769Y337265D01*
X681061Y337348D01*
X681394D01*
X681769Y337223D01*
X682061Y337015D01*
X682269Y336765D01*
X682436Y336348D01*
X682478Y335973D01*
X682394Y335598D01*
X682269Y335348D01*
X682019Y335098D01*
X681728Y334931D01*
X681436Y334848D01*
X681144D01*
X680853Y334931D01*
X680603Y335056D01*
X680394Y335223D01*
G01X679128Y335890D02*
X678836Y336181D01*
X678586Y336348D01*
X678253Y336431D01*
X677961Y336348D01*
X677753Y336181D01*
X677586Y335931D01*
X677544Y335640D01*
X677586Y335390D01*
X677753Y335140D01*
X678003Y334931D01*
X678294Y334848D01*
X678628Y334931D01*
X678919Y335181D01*
X679086Y335556D01*
X679128Y335973D01*
X679044Y336515D01*
X678919Y336806D01*
X678711Y337098D01*
X678419Y337306D01*
X678128Y337348D01*
X677836Y337265D01*
X677628Y337056D01*
G01X676069Y334848D02*
Y337348D01*
X675069D01*
X674736Y337223D01*
X674486Y336931D01*
X674403Y336598D01*
X674486Y336265D01*
X674694Y336015D01*
X675069Y335890D01*
X676069D01*
G01X671636Y334848D02*
Y337348D01*
X673178Y335556D01*
X671094D01*
G01X728442Y319600D02*
Y322100D01*
X726858D01*
G01X727442Y320892D02*
X728442D01*
G01X724217Y320933D02*
X724050Y321058D01*
X723925Y321267D01*
X723842Y321558D01*
X723925Y321808D01*
X724092Y321975D01*
X724383Y322100D01*
X725508D01*
Y319600D01*
X724133D01*
X723842Y319767D01*
X723675Y320017D01*
X723592Y320308D01*
X723675Y320600D01*
X723925Y320850D01*
X724217Y320933D01*
X725508D01*
G01X722242Y320642D02*
X721950Y320933D01*
X721700Y321100D01*
X721367Y321183D01*
X721075Y321100D01*
X720867Y320933D01*
X720700Y320683D01*
X720658Y320392D01*
X720700Y320142D01*
X720867Y319892D01*
X721117Y319683D01*
X721408Y319600D01*
X721742Y319683D01*
X722033Y319933D01*
X722200Y320308D01*
X722242Y320725D01*
X722158Y321267D01*
X722033Y321558D01*
X721825Y321850D01*
X721533Y322058D01*
X721242Y322100D01*
X720950Y322017D01*
X720742Y321808D01*
G01X719183Y319600D02*
Y322100D01*
X718183D01*
X717850Y321975D01*
X717600Y321683D01*
X717517Y321350D01*
X717600Y321017D01*
X717808Y320767D01*
X718183Y320642D01*
X719183D01*
G01X715250Y319600D02*
Y322100D01*
X715750Y321600D01*
G01Y319600D02*
X714750D01*
G01X687951Y354972D02*
X690451D01*
Y356013D01*
X690326Y356347D01*
X690159Y356555D01*
X689826Y356638D01*
X689493Y356555D01*
X689284Y356305D01*
X689159Y356013D01*
Y354972D01*
G01Y356013D02*
X687951Y356638D01*
G01X688993Y358113D02*
X689284Y358405D01*
X689451Y358655D01*
X689534Y358988D01*
X689451Y359280D01*
X689284Y359488D01*
X689034Y359655D01*
X688743Y359697D01*
X688493Y359655D01*
X688243Y359488D01*
X688034Y359238D01*
X687951Y358947D01*
X688034Y358613D01*
X688284Y358322D01*
X688659Y358155D01*
X689076Y358113D01*
X689618Y358197D01*
X689909Y358322D01*
X690201Y358530D01*
X690409Y358822D01*
X690451Y359113D01*
X690368Y359405D01*
X690159Y359613D01*
G01X687951Y361047D02*
X690451D01*
X687951Y362963D01*
X690451D01*
G01X687951Y365105D02*
X687993Y365397D01*
X688118Y365730D01*
X688326Y365938D01*
X688618Y366022D01*
X688909Y365938D01*
X689159Y365688D01*
X689284Y365313D01*
Y364897D01*
X689368Y364647D01*
X689576Y364438D01*
X689868Y364355D01*
X690159Y364480D01*
X690368Y364772D01*
X690451Y365105D01*
X690368Y365438D01*
X690159Y365730D01*
X689868Y365855D01*
X689576Y365772D01*
X689368Y365563D01*
X689284Y365313D01*
Y364897D01*
X689159Y364522D01*
X688909Y364272D01*
X688618Y364188D01*
X688326Y364272D01*
X688118Y364480D01*
X687993Y364813D01*
X687951Y365105D01*
G01X691451Y354972D02*
X693951D01*
Y356013D01*
X693826Y356347D01*
X693659Y356555D01*
X693326Y356638D01*
X692993Y356555D01*
X692784Y356305D01*
X692659Y356013D01*
Y354972D01*
G01Y356013D02*
X691451Y356638D01*
G01X692493Y358113D02*
X692784Y358405D01*
X692951Y358655D01*
X693034Y358988D01*
X692951Y359280D01*
X692784Y359488D01*
X692534Y359655D01*
X692243Y359697D01*
X691993Y359655D01*
X691743Y359488D01*
X691534Y359238D01*
X691451Y358947D01*
X691534Y358613D01*
X691784Y358322D01*
X692159Y358155D01*
X692576Y358113D01*
X693118Y358197D01*
X693409Y358322D01*
X693701Y358530D01*
X693909Y358822D01*
X693951Y359113D01*
X693868Y359405D01*
X693659Y359613D01*
G01X691451Y361047D02*
X693951D01*
X691451Y362963D01*
X693951D01*
G01X691743Y364397D02*
X691534Y364688D01*
X691451Y365022D01*
X691534Y365355D01*
X691784Y365647D01*
X692159Y365855D01*
X692534Y365938D01*
X692993D01*
X693368Y365855D01*
X693701Y365647D01*
X693868Y365397D01*
X693951Y365105D01*
X693868Y364772D01*
X693701Y364522D01*
X693451Y364355D01*
X693118Y364272D01*
X692826Y364355D01*
X692534Y364563D01*
X692368Y364813D01*
X692326Y365105D01*
X692409Y365438D01*
X692618Y365688D01*
X692993Y365938D01*
G01X718742Y358567D02*
X718867Y358317D01*
X718950Y358025D01*
Y357692D01*
X718825Y357317D01*
X718617Y357025D01*
X718367Y356817D01*
X717950Y356650D01*
X717575Y356608D01*
X717200Y356692D01*
X716950Y356817D01*
X716700Y357067D01*
X716533Y357358D01*
X716450Y357650D01*
Y357942D01*
X716533Y358233D01*
X716658Y358483D01*
X716825Y358692D01*
G01X717492Y359958D02*
X717783Y360250D01*
X717950Y360500D01*
X718033Y360833D01*
X717950Y361125D01*
X717783Y361333D01*
X717533Y361500D01*
X717242Y361542D01*
X716992Y361500D01*
X716742Y361333D01*
X716533Y361083D01*
X716450Y360792D01*
X716533Y360458D01*
X716783Y360167D01*
X717158Y360000D01*
X717575Y359958D01*
X718117Y360042D01*
X718408Y360167D01*
X718700Y360375D01*
X718908Y360667D01*
X718950Y360958D01*
X718867Y361250D01*
X718658Y361458D01*
G01X716450Y362892D02*
X718950D01*
X716450Y364808D01*
X718950D01*
G01X716825Y366033D02*
X716617Y366283D01*
X716492Y366575D01*
X716450Y366950D01*
X716533Y367325D01*
X716700Y367617D01*
X716992Y367825D01*
X717325Y367867D01*
X717658Y367783D01*
X717867Y367575D01*
X718033Y367283D01*
X718075Y366992D01*
X718033Y366700D01*
X717867Y366325D01*
X718950Y366450D01*
Y367575D01*
G01X696900Y346800D02*
Y369375D01*
G01X714900Y346800D02*
Y369372D01*
G01Y346800D02*
X712205D01*
G01X696900D02*
X699598D01*
G01X699600Y382164D02*
X696038D01*
Y369368D01*
X699600D01*
G01X712200Y382164D02*
X715991D01*
Y369368D01*
X712200D01*
G01X711850Y522504D02*
X712100Y522629D01*
X712392Y522712D01*
X712725D01*
X713100Y522587D01*
X713392Y522379D01*
X713600Y522129D01*
X713767Y521712D01*
X713809Y521337D01*
X713725Y520962D01*
X713600Y520712D01*
X713350Y520462D01*
X713059Y520295D01*
X712767Y520212D01*
X712475D01*
X712184Y520295D01*
X711934Y520420D01*
X711725Y520587D01*
G01X710459Y521254D02*
X710167Y521545D01*
X709917Y521712D01*
X709584Y521795D01*
X709292Y521712D01*
X709084Y521545D01*
X708917Y521295D01*
X708875Y521004D01*
X708917Y520754D01*
X709084Y520504D01*
X709334Y520295D01*
X709625Y520212D01*
X709959Y520295D01*
X710250Y520545D01*
X710417Y520920D01*
X710459Y521337D01*
X710375Y521879D01*
X710250Y522170D01*
X710042Y522462D01*
X709750Y522670D01*
X709459Y522712D01*
X709167Y522629D01*
X708959Y522420D01*
G01X707650Y520212D02*
Y522712D01*
X706567Y520629D01*
X705484Y522712D01*
Y520212D01*
G01X704384Y520712D02*
X704134Y520420D01*
X703800Y520254D01*
X703425Y520212D01*
X703092Y520254D01*
X702759Y520462D01*
X702550Y520712D01*
X702509Y520962D01*
X702592Y521254D01*
X702884Y521462D01*
X703175Y521545D01*
X703550D01*
G01X703175D02*
X702925Y521670D01*
X702717Y521879D01*
X702634Y522129D01*
X702717Y522379D01*
X702925Y522587D01*
X703300Y522712D01*
X703675Y522670D01*
X704050Y522504D01*
G01X680864Y498214D02*
Y500714D01*
X679823D01*
X679489Y500589D01*
X679281Y500422D01*
X679198Y500089D01*
X679281Y499756D01*
X679531Y499547D01*
X679823Y499422D01*
X680864D01*
G01X679823D02*
X679198Y498214D01*
G01X677723Y499256D02*
X677431Y499547D01*
X677181Y499714D01*
X676848Y499797D01*
X676556Y499714D01*
X676348Y499547D01*
X676181Y499297D01*
X676139Y499006D01*
X676181Y498756D01*
X676348Y498506D01*
X676598Y498297D01*
X676889Y498214D01*
X677223Y498297D01*
X677514Y498547D01*
X677681Y498922D01*
X677723Y499339D01*
X677639Y499881D01*
X677514Y500172D01*
X677306Y500464D01*
X677014Y500672D01*
X676723Y500714D01*
X676431Y500631D01*
X676223Y500422D01*
G01X674914Y498214D02*
Y500714D01*
X673831Y498631D01*
X672748Y500714D01*
Y498214D01*
G01X670731D02*
X670439Y498256D01*
X670106Y498381D01*
X669898Y498589D01*
X669814Y498881D01*
X669898Y499172D01*
X670148Y499422D01*
X670523Y499547D01*
X670939D01*
X671189Y499631D01*
X671398Y499839D01*
X671481Y500131D01*
X671356Y500422D01*
X671064Y500631D01*
X670731Y500714D01*
X670398Y500631D01*
X670106Y500422D01*
X669981Y500131D01*
X670064Y499839D01*
X670273Y499631D01*
X670523Y499547D01*
X670939D01*
X671314Y499422D01*
X671564Y499172D01*
X671648Y498881D01*
X671564Y498589D01*
X671356Y498381D01*
X671023Y498256D01*
X670731Y498214D01*
G01X682389Y486320D02*
X684889D01*
Y487361D01*
X684764Y487695D01*
X684597Y487903D01*
X684264Y487986D01*
X683931Y487903D01*
X683722Y487653D01*
X683597Y487361D01*
Y486320D01*
G01Y487361D02*
X682389Y487986D01*
G01X683431Y489461D02*
X683722Y489753D01*
X683889Y490003D01*
X683972Y490336D01*
X683889Y490628D01*
X683722Y490836D01*
X683472Y491003D01*
X683181Y491045D01*
X682931Y491003D01*
X682681Y490836D01*
X682472Y490586D01*
X682389Y490295D01*
X682472Y489961D01*
X682722Y489670D01*
X683097Y489503D01*
X683514Y489461D01*
X684056Y489545D01*
X684347Y489670D01*
X684639Y489878D01*
X684847Y490170D01*
X684889Y490461D01*
X684806Y490753D01*
X684597Y490961D01*
G01X682389Y492270D02*
X684889D01*
X682806Y493353D01*
X684889Y494436D01*
X682389D01*
G01Y496953D02*
X684889D01*
X683097Y495411D01*
Y497495D01*
G01X671264Y509401D02*
X673764D01*
Y510442D01*
X673639Y510776D01*
X673472Y510984D01*
X673139Y511067D01*
X672806Y510984D01*
X672597Y510734D01*
X672472Y510442D01*
Y509401D01*
G01Y510442D02*
X671264Y511067D01*
G01X671639Y512417D02*
X671431Y512667D01*
X671306Y512959D01*
X671264Y513334D01*
X671347Y513709D01*
X671514Y514001D01*
X671806Y514209D01*
X672139Y514251D01*
X672472Y514167D01*
X672681Y513959D01*
X672847Y513667D01*
X672889Y513376D01*
X672847Y513084D01*
X672681Y512709D01*
X673764Y512834D01*
Y513959D01*
G01Y515184D02*
X671264Y515767D01*
X673764Y516434D01*
X671264Y517101D01*
X673764Y517684D01*
G01X673347Y518742D02*
X673597Y518992D01*
X673722Y519284D01*
X673764Y519617D01*
X673681Y520034D01*
X673472Y520326D01*
X673222Y520409D01*
X672972Y520367D01*
X672764Y520201D01*
X672347Y519367D01*
X672056Y518992D01*
X671639Y518742D01*
X671264Y518659D01*
Y520409D01*
G01X676642Y525617D02*
X676767Y525367D01*
X676850Y525075D01*
Y524742D01*
X676725Y524367D01*
X676517Y524075D01*
X676267Y523867D01*
X675850Y523700D01*
X675475Y523658D01*
X675100Y523742D01*
X674850Y523867D01*
X674600Y524117D01*
X674433Y524408D01*
X674350Y524700D01*
Y524992D01*
X674433Y525283D01*
X674558Y525533D01*
X674725Y525742D01*
G01X675392Y527008D02*
X675683Y527300D01*
X675850Y527550D01*
X675933Y527883D01*
X675850Y528175D01*
X675683Y528383D01*
X675433Y528550D01*
X675142Y528592D01*
X674892Y528550D01*
X674642Y528383D01*
X674433Y528133D01*
X674350Y527842D01*
X674433Y527508D01*
X674683Y527217D01*
X675058Y527050D01*
X675475Y527008D01*
X676017Y527092D01*
X676308Y527217D01*
X676600Y527425D01*
X676808Y527717D01*
X676850Y528008D01*
X676767Y528300D01*
X676558Y528508D01*
G01X676850Y530067D02*
X674350D01*
Y531733D01*
G01Y534000D02*
X676850D01*
X676350Y533500D01*
G01X674350D02*
Y534500D01*
G01X676433Y536308D02*
X676683Y536558D01*
X676808Y536850D01*
X676850Y537183D01*
X676767Y537600D01*
X676558Y537892D01*
X676308Y537975D01*
X676058Y537933D01*
X675850Y537767D01*
X675433Y536933D01*
X675142Y536558D01*
X674725Y536308D01*
X674350Y536225D01*
Y537975D01*
G01X728883Y518242D02*
X729133Y518367D01*
X729425Y518450D01*
X729758D01*
X730133Y518325D01*
X730425Y518117D01*
X730633Y517867D01*
X730800Y517450D01*
X730842Y517075D01*
X730758Y516700D01*
X730633Y516450D01*
X730383Y516200D01*
X730092Y516033D01*
X729800Y515950D01*
X729508D01*
X729217Y516033D01*
X728967Y516158D01*
X728758Y516325D01*
G01X727492Y518033D02*
X727242Y518283D01*
X726950Y518408D01*
X726617Y518450D01*
X726200Y518367D01*
X725908Y518158D01*
X725825Y517908D01*
X725867Y517658D01*
X726033Y517450D01*
X726867Y517033D01*
X727242Y516742D01*
X727492Y516325D01*
X727575Y515950D01*
X725825D01*
G01X724392Y518033D02*
X724142Y518283D01*
X723850Y518408D01*
X723517Y518450D01*
X723100Y518367D01*
X722808Y518158D01*
X722725Y517908D01*
X722767Y517658D01*
X722933Y517450D01*
X723767Y517033D01*
X724142Y516742D01*
X724392Y516325D01*
X724475Y515950D01*
X722725D01*
G01X721750Y518450D02*
X721167Y515950D01*
X720500Y518450D01*
X719833Y515950D01*
X719250Y518450D01*
G01X718317Y516325D02*
X718067Y516117D01*
X717775Y515992D01*
X717400Y515950D01*
X717025Y516033D01*
X716733Y516200D01*
X716525Y516492D01*
X716483Y516825D01*
X716567Y517158D01*
X716775Y517367D01*
X717067Y517533D01*
X717358Y517575D01*
X717650Y517533D01*
X718025Y517367D01*
X717900Y518450D01*
X716775D01*
G01X735383Y570100D02*
Y572600D01*
X734342D01*
X734008Y572475D01*
X733800Y572308D01*
X733717Y571975D01*
X733800Y571642D01*
X734050Y571433D01*
X734342Y571308D01*
X735383D01*
G01X734342D02*
X733717Y570100D01*
G01X732242Y571142D02*
X731950Y571433D01*
X731700Y571600D01*
X731367Y571683D01*
X731075Y571600D01*
X730867Y571433D01*
X730700Y571183D01*
X730658Y570892D01*
X730700Y570642D01*
X730867Y570392D01*
X731117Y570183D01*
X731408Y570100D01*
X731742Y570183D01*
X732033Y570433D01*
X732200Y570808D01*
X732242Y571225D01*
X732158Y571767D01*
X732033Y572058D01*
X731825Y572350D01*
X731533Y572558D01*
X731242Y572600D01*
X730950Y572517D01*
X730742Y572308D01*
G01X729183Y572600D02*
Y570100D01*
X727517D01*
G01X725958Y570392D02*
X725667Y570183D01*
X725333Y570100D01*
X725000Y570183D01*
X724708Y570433D01*
X724500Y570808D01*
X724417Y571183D01*
Y571642D01*
X724500Y572017D01*
X724708Y572350D01*
X724958Y572517D01*
X725250Y572600D01*
X725583Y572517D01*
X725833Y572350D01*
X726000Y572100D01*
X726083Y571767D01*
X726000Y571475D01*
X725792Y571183D01*
X725542Y571017D01*
X725250Y570975D01*
X724917Y571058D01*
X724667Y571267D01*
X724417Y571642D01*
G01X711000Y564167D02*
X713500D01*
Y565208D01*
X713375Y565542D01*
X713208Y565750D01*
X712875Y565833D01*
X712542Y565750D01*
X712333Y565500D01*
X712208Y565208D01*
Y564167D01*
G01Y565208D02*
X711000Y565833D01*
G01X712042Y567308D02*
X712333Y567600D01*
X712500Y567850D01*
X712583Y568183D01*
X712500Y568475D01*
X712333Y568683D01*
X712083Y568850D01*
X711792Y568892D01*
X711542Y568850D01*
X711292Y568683D01*
X711083Y568433D01*
X711000Y568142D01*
X711083Y567808D01*
X711333Y567517D01*
X711708Y567350D01*
X712125Y567308D01*
X712667Y567392D01*
X712958Y567517D01*
X713250Y567725D01*
X713458Y568017D01*
X713500Y568308D01*
X713417Y568600D01*
X713208Y568808D01*
G01X713500Y570367D02*
X711000D01*
Y572033D01*
G01Y574300D02*
X713500D01*
X713000Y573800D01*
G01X711000D02*
Y574800D01*
G01Y577400D02*
X713500D01*
X713000Y576900D01*
G01X711000D02*
Y577900D01*
G01X718100Y564367D02*
X720600D01*
Y565408D01*
X720475Y565742D01*
X720308Y565950D01*
X719975Y566033D01*
X719642Y565950D01*
X719433Y565700D01*
X719308Y565408D01*
Y564367D01*
G01Y565408D02*
X718100Y566033D01*
G01X719142Y567508D02*
X719433Y567800D01*
X719600Y568050D01*
X719683Y568383D01*
X719600Y568675D01*
X719433Y568883D01*
X719183Y569050D01*
X718892Y569092D01*
X718642Y569050D01*
X718392Y568883D01*
X718183Y568633D01*
X718100Y568342D01*
X718183Y568008D01*
X718433Y567717D01*
X718808Y567550D01*
X719225Y567508D01*
X719767Y567592D01*
X720058Y567717D01*
X720350Y567925D01*
X720558Y568217D01*
X720600Y568508D01*
X720517Y568800D01*
X720308Y569008D01*
G01X720600Y570567D02*
X718100D01*
Y572233D01*
G01Y574500D02*
X720600D01*
X720100Y574000D01*
G01X718100D02*
Y575000D01*
G01X720600Y577600D02*
X720517Y577267D01*
X720308Y577017D01*
X720058Y576850D01*
X719725Y576725D01*
X719350Y576683D01*
X718975Y576725D01*
X718642Y576850D01*
X718392Y577017D01*
X718183Y577267D01*
X718100Y577600D01*
X718183Y577933D01*
X718392Y578183D01*
X718642Y578350D01*
X718975Y578475D01*
X719350Y578517D01*
X719725Y578475D01*
X720058Y578350D01*
X720308Y578183D01*
X720517Y577933D01*
X720600Y577600D01*
G01X679722Y584325D02*
Y586825D01*
X678681D01*
X678347Y586700D01*
X678139Y586533D01*
X678056Y586200D01*
X678139Y585867D01*
X678389Y585658D01*
X678681Y585533D01*
X679722D01*
G01X678681D02*
X678056Y584325D01*
G01X676581Y585367D02*
X676289Y585658D01*
X676039Y585825D01*
X675706Y585908D01*
X675414Y585825D01*
X675206Y585658D01*
X675039Y585408D01*
X674997Y585117D01*
X675039Y584867D01*
X675206Y584617D01*
X675456Y584408D01*
X675747Y584325D01*
X676081Y584408D01*
X676372Y584658D01*
X676539Y585033D01*
X676581Y585450D01*
X676497Y585992D01*
X676372Y586283D01*
X676164Y586575D01*
X675872Y586783D01*
X675581Y586825D01*
X675289Y586742D01*
X675081Y586533D01*
G01X673522Y586825D02*
Y584325D01*
X671856D01*
G01X670381Y585367D02*
X670089Y585658D01*
X669839Y585825D01*
X669506Y585908D01*
X669214Y585825D01*
X669006Y585658D01*
X668839Y585408D01*
X668797Y585117D01*
X668839Y584867D01*
X669006Y584617D01*
X669256Y584408D01*
X669547Y584325D01*
X669881Y584408D01*
X670172Y584658D01*
X670339Y585033D01*
X670381Y585450D01*
X670297Y585992D01*
X670172Y586283D01*
X669964Y586575D01*
X669672Y586783D01*
X669381Y586825D01*
X669089Y586742D01*
X668881Y586533D01*
G01X700583Y577600D02*
Y580100D01*
X699542D01*
X699208Y579975D01*
X699000Y579808D01*
X698917Y579475D01*
X699000Y579142D01*
X699250Y578933D01*
X699542Y578808D01*
X700583D01*
G01X699542D02*
X698917Y577600D01*
G01X697442Y578642D02*
X697150Y578933D01*
X696900Y579100D01*
X696567Y579183D01*
X696275Y579100D01*
X696067Y578933D01*
X695900Y578683D01*
X695858Y578392D01*
X695900Y578142D01*
X696067Y577892D01*
X696317Y577683D01*
X696608Y577600D01*
X696942Y577683D01*
X697233Y577933D01*
X697400Y578308D01*
X697442Y578725D01*
X697358Y579267D01*
X697233Y579558D01*
X697025Y579850D01*
X696733Y580058D01*
X696442Y580100D01*
X696150Y580017D01*
X695942Y579808D01*
G01X694383Y580100D02*
Y577600D01*
X692717D01*
G01X690450D02*
X690158Y577642D01*
X689825Y577767D01*
X689617Y577975D01*
X689533Y578267D01*
X689617Y578558D01*
X689867Y578808D01*
X690242Y578933D01*
X690658D01*
X690908Y579017D01*
X691117Y579225D01*
X691200Y579517D01*
X691075Y579808D01*
X690783Y580017D01*
X690450Y580100D01*
X690117Y580017D01*
X689825Y579808D01*
X689700Y579517D01*
X689783Y579225D01*
X689992Y579017D01*
X690242Y578933D01*
X690658D01*
X691033Y578808D01*
X691283Y578558D01*
X691367Y578267D01*
X691283Y577975D01*
X691075Y577767D01*
X690742Y577642D01*
X690450Y577600D01*
G01X722452Y588232D02*
X722577Y587982D01*
X722660Y587690D01*
Y587357D01*
X722535Y586982D01*
X722327Y586690D01*
X722077Y586482D01*
X721660Y586315D01*
X721285Y586273D01*
X720910Y586357D01*
X720660Y586482D01*
X720410Y586732D01*
X720243Y587023D01*
X720160Y587315D01*
Y587607D01*
X720243Y587898D01*
X720368Y588148D01*
X720535Y588357D01*
G01X721202Y589623D02*
X721493Y589915D01*
X721660Y590165D01*
X721743Y590498D01*
X721660Y590790D01*
X721493Y590998D01*
X721243Y591165D01*
X720952Y591207D01*
X720702Y591165D01*
X720452Y590998D01*
X720243Y590748D01*
X720160Y590457D01*
X720243Y590123D01*
X720493Y589832D01*
X720868Y589665D01*
X721285Y589623D01*
X721827Y589707D01*
X722118Y589832D01*
X722410Y590040D01*
X722618Y590332D01*
X722660Y590623D01*
X722577Y590915D01*
X722368Y591123D01*
G01X722660Y592682D02*
X720160D01*
Y594348D01*
G01X720660Y595698D02*
X720368Y595948D01*
X720202Y596282D01*
X720160Y596657D01*
X720202Y596990D01*
X720410Y597323D01*
X720660Y597532D01*
X720910Y597573D01*
X721202Y597490D01*
X721410Y597198D01*
X721493Y596907D01*
Y596532D01*
G01Y596907D02*
X721618Y597157D01*
X721827Y597365D01*
X722077Y597448D01*
X722327Y597365D01*
X722535Y597157D01*
X722660Y596782D01*
X722618Y596407D01*
X722452Y596032D01*
G01X704552Y586632D02*
X704677Y586382D01*
X704760Y586090D01*
Y585757D01*
X704635Y585382D01*
X704427Y585090D01*
X704177Y584882D01*
X703760Y584715D01*
X703385Y584673D01*
X703010Y584757D01*
X702760Y584882D01*
X702510Y585132D01*
X702343Y585423D01*
X702260Y585715D01*
Y586007D01*
X702343Y586298D01*
X702468Y586548D01*
X702635Y586757D01*
G01X703302Y588023D02*
X703593Y588315D01*
X703760Y588565D01*
X703843Y588898D01*
X703760Y589190D01*
X703593Y589398D01*
X703343Y589565D01*
X703052Y589607D01*
X702802Y589565D01*
X702552Y589398D01*
X702343Y589148D01*
X702260Y588857D01*
X702343Y588523D01*
X702593Y588232D01*
X702968Y588065D01*
X703385Y588023D01*
X703927Y588107D01*
X704218Y588232D01*
X704510Y588440D01*
X704718Y588732D01*
X704760Y589023D01*
X704677Y589315D01*
X704468Y589523D01*
G01X704760Y591082D02*
X702260D01*
Y592748D01*
G01Y595515D02*
X704760D01*
X702968Y593973D01*
Y596057D01*
G01X711932Y531667D02*
X712057Y531417D01*
X712140Y531125D01*
Y530792D01*
X712015Y530417D01*
X711807Y530125D01*
X711557Y529917D01*
X711140Y529750D01*
X710765Y529708D01*
X710390Y529792D01*
X710140Y529917D01*
X709890Y530167D01*
X709723Y530458D01*
X709640Y530750D01*
Y531042D01*
X709723Y531333D01*
X709848Y531583D01*
X710015Y531792D01*
G01X710682Y533058D02*
X710973Y533350D01*
X711140Y533600D01*
X711223Y533933D01*
X711140Y534225D01*
X710973Y534433D01*
X710723Y534600D01*
X710432Y534642D01*
X710182Y534600D01*
X709932Y534433D01*
X709723Y534183D01*
X709640Y533892D01*
X709723Y533558D01*
X709973Y533267D01*
X710348Y533100D01*
X710765Y533058D01*
X711307Y533142D01*
X711598Y533267D01*
X711890Y533475D01*
X712098Y533767D01*
X712140Y534058D01*
X712057Y534350D01*
X711848Y534558D01*
G01X712140Y536117D02*
X709640D01*
Y537783D01*
G01Y540050D02*
X712140D01*
X711640Y539550D01*
G01X709640D02*
Y540550D01*
G01Y543150D02*
X712140D01*
X711640Y542650D01*
G01X709640D02*
Y543650D01*
G01X685333Y574542D02*
X685583Y574667D01*
X685875Y574750D01*
X686208D01*
X686583Y574625D01*
X686875Y574417D01*
X687083Y574167D01*
X687250Y573750D01*
X687292Y573375D01*
X687208Y573000D01*
X687083Y572750D01*
X686833Y572500D01*
X686542Y572333D01*
X686250Y572250D01*
X685958D01*
X685667Y572333D01*
X685417Y572458D01*
X685208Y572625D01*
G01X683942Y573292D02*
X683650Y573583D01*
X683400Y573750D01*
X683067Y573833D01*
X682775Y573750D01*
X682567Y573583D01*
X682400Y573333D01*
X682358Y573042D01*
X682400Y572792D01*
X682567Y572542D01*
X682817Y572333D01*
X683108Y572250D01*
X683442Y572333D01*
X683733Y572583D01*
X683900Y572958D01*
X683942Y573375D01*
X683858Y573917D01*
X683733Y574208D01*
X683525Y574500D01*
X683233Y574708D01*
X682942Y574750D01*
X682650Y574667D01*
X682442Y574458D01*
G01X680883Y574750D02*
Y572250D01*
X679217D01*
G01X676950D02*
X676658Y572292D01*
X676325Y572417D01*
X676117Y572625D01*
X676033Y572917D01*
X676117Y573208D01*
X676367Y573458D01*
X676742Y573583D01*
X677158D01*
X677408Y573667D01*
X677617Y573875D01*
X677700Y574167D01*
X677575Y574458D01*
X677283Y574667D01*
X676950Y574750D01*
X676617Y574667D01*
X676325Y574458D01*
X676200Y574167D01*
X676283Y573875D01*
X676492Y573667D01*
X676742Y573583D01*
X677158D01*
X677533Y573458D01*
X677783Y573208D01*
X677867Y572917D01*
X677783Y572625D01*
X677575Y572417D01*
X677242Y572292D01*
X676950Y572250D01*
G01X696850Y555500D02*
Y553250D01*
X666950D01*
Y554300D01*
G01Y570300D02*
Y571350D01*
X696850D01*
Y569100D01*
G01X789583Y32792D02*
X789833Y32917D01*
X790125Y33000D01*
X790458D01*
X790833Y32875D01*
X791125Y32667D01*
X791333Y32417D01*
X791500Y32000D01*
X791542Y31625D01*
X791458Y31250D01*
X791333Y31000D01*
X791083Y30750D01*
X790792Y30583D01*
X790500Y30500D01*
X790208D01*
X789917Y30583D01*
X789667Y30708D01*
X789458Y30875D01*
G01X788192Y31542D02*
X787900Y31833D01*
X787650Y32000D01*
X787317Y32083D01*
X787025Y32000D01*
X786817Y31833D01*
X786650Y31583D01*
X786608Y31292D01*
X786650Y31042D01*
X786817Y30792D01*
X787067Y30583D01*
X787358Y30500D01*
X787692Y30583D01*
X787983Y30833D01*
X788150Y31208D01*
X788192Y31625D01*
X788108Y32167D01*
X787983Y32458D01*
X787775Y32750D01*
X787483Y32958D01*
X787192Y33000D01*
X786900Y32917D01*
X786692Y32708D01*
G01X785217Y33000D02*
Y31208D01*
X785050Y30833D01*
X784717Y30583D01*
X784300Y30500D01*
X783883Y30583D01*
X783550Y30833D01*
X783383Y31208D01*
Y33000D01*
G01X781200Y30500D02*
Y33000D01*
X781700Y32500D01*
G01Y30500D02*
X780700D01*
G01X778100Y33000D02*
X778433Y32917D01*
X778683Y32708D01*
X778850Y32458D01*
X778975Y32125D01*
X779017Y31750D01*
X778975Y31375D01*
X778850Y31042D01*
X778683Y30792D01*
X778433Y30583D01*
X778100Y30500D01*
X777767Y30583D01*
X777517Y30792D01*
X777350Y31042D01*
X777225Y31375D01*
X777183Y31750D01*
X777225Y32125D01*
X777350Y32458D01*
X777517Y32708D01*
X777767Y32917D01*
X778100Y33000D01*
G01X761191Y-12808D02*
X761441Y-12683D01*
X761733Y-12600D01*
X762066D01*
X762441Y-12725D01*
X762733Y-12933D01*
X762941Y-13183D01*
X763108Y-13600D01*
X763150Y-13975D01*
X763066Y-14350D01*
X762941Y-14600D01*
X762691Y-14850D01*
X762400Y-15017D01*
X762108Y-15100D01*
X761816D01*
X761525Y-15017D01*
X761275Y-14892D01*
X761066Y-14725D01*
G01X759800Y-14058D02*
X759508Y-13767D01*
X759258Y-13600D01*
X758925Y-13517D01*
X758633Y-13600D01*
X758425Y-13767D01*
X758258Y-14017D01*
X758216Y-14308D01*
X758258Y-14558D01*
X758425Y-14808D01*
X758675Y-15017D01*
X758966Y-15100D01*
X759300Y-15017D01*
X759591Y-14767D01*
X759758Y-14392D01*
X759800Y-13975D01*
X759716Y-13433D01*
X759591Y-13142D01*
X759383Y-12850D01*
X759091Y-12642D01*
X758800Y-12600D01*
X758508Y-12683D01*
X758300Y-12892D01*
G01X756825Y-12600D02*
Y-14392D01*
X756658Y-14767D01*
X756325Y-15017D01*
X755908Y-15100D01*
X755491Y-15017D01*
X755158Y-14767D01*
X754991Y-14392D01*
Y-12600D01*
G01X752808Y-15100D02*
Y-12600D01*
X753308Y-13100D01*
G01Y-15100D02*
X752308D01*
G01X749708D02*
X749416Y-15058D01*
X749083Y-14933D01*
X748875Y-14725D01*
X748791Y-14433D01*
X748875Y-14142D01*
X749125Y-13892D01*
X749500Y-13767D01*
X749916D01*
X750166Y-13683D01*
X750375Y-13475D01*
X750458Y-13183D01*
X750333Y-12892D01*
X750041Y-12683D01*
X749708Y-12600D01*
X749375Y-12683D01*
X749083Y-12892D01*
X748958Y-13183D01*
X749041Y-13475D01*
X749250Y-13683D01*
X749500Y-13767D01*
X749916D01*
X750291Y-13892D01*
X750541Y-14142D01*
X750625Y-14433D01*
X750541Y-14725D01*
X750333Y-14933D01*
X750000Y-15058D01*
X749708Y-15100D01*
G01X731048Y19475D02*
X733548D01*
Y20516D01*
X733423Y20850D01*
X733256Y21058D01*
X732923Y21141D01*
X732590Y21058D01*
X732381Y20808D01*
X732256Y20516D01*
Y19475D01*
G01Y20516D02*
X731048Y21141D01*
G01X732090Y22616D02*
X732381Y22908D01*
X732548Y23158D01*
X732631Y23491D01*
X732548Y23783D01*
X732381Y23991D01*
X732131Y24158D01*
X731840Y24200D01*
X731590Y24158D01*
X731340Y23991D01*
X731131Y23741D01*
X731048Y23450D01*
X731131Y23116D01*
X731381Y22825D01*
X731756Y22658D01*
X732173Y22616D01*
X732715Y22700D01*
X733006Y22825D01*
X733298Y23033D01*
X733506Y23325D01*
X733548Y23616D01*
X733465Y23908D01*
X733256Y24116D01*
G01X733548Y25591D02*
X731756D01*
X731381Y25758D01*
X731131Y26091D01*
X731048Y26508D01*
X731131Y26925D01*
X731381Y27258D01*
X731756Y27425D01*
X733548D01*
G01X731048Y30108D02*
X733548D01*
X731756Y28566D01*
Y30650D01*
G01X726782Y19498D02*
X729282D01*
Y20539D01*
X729157Y20873D01*
X728990Y21081D01*
X728657Y21164D01*
X728324Y21081D01*
X728115Y20831D01*
X727990Y20539D01*
Y19498D01*
G01Y20539D02*
X726782Y21164D01*
G01X727824Y22639D02*
X728115Y22931D01*
X728282Y23181D01*
X728365Y23514D01*
X728282Y23806D01*
X728115Y24014D01*
X727865Y24181D01*
X727574Y24223D01*
X727324Y24181D01*
X727074Y24014D01*
X726865Y23764D01*
X726782Y23473D01*
X726865Y23139D01*
X727115Y22848D01*
X727490Y22681D01*
X727907Y22639D01*
X728449Y22723D01*
X728740Y22848D01*
X729032Y23056D01*
X729240Y23348D01*
X729282Y23639D01*
X729199Y23931D01*
X728990Y24139D01*
G01X729282Y25614D02*
X727490D01*
X727115Y25781D01*
X726865Y26114D01*
X726782Y26531D01*
X726865Y26948D01*
X727115Y27281D01*
X727490Y27448D01*
X729282D01*
G01X727157Y28714D02*
X726949Y28964D01*
X726824Y29256D01*
X726782Y29631D01*
X726865Y30006D01*
X727032Y30298D01*
X727324Y30506D01*
X727657Y30548D01*
X727990Y30464D01*
X728199Y30256D01*
X728365Y29964D01*
X728407Y29673D01*
X728365Y29381D01*
X728199Y29006D01*
X729282Y29131D01*
Y30256D01*
G01X737159Y-15719D02*
X737284Y-15969D01*
X737367Y-16261D01*
Y-16594D01*
X737242Y-16969D01*
X737034Y-17261D01*
X736784Y-17469D01*
X736367Y-17636D01*
X735992Y-17678D01*
X735617Y-17594D01*
X735367Y-17469D01*
X735117Y-17219D01*
X734950Y-16928D01*
X734867Y-16636D01*
Y-16344D01*
X734950Y-16053D01*
X735075Y-15803D01*
X735242Y-15594D01*
G01X735909Y-14328D02*
X736200Y-14036D01*
X736367Y-13786D01*
X736450Y-13453D01*
X736367Y-13161D01*
X736200Y-12953D01*
X735950Y-12786D01*
X735659Y-12744D01*
X735409Y-12786D01*
X735159Y-12953D01*
X734950Y-13203D01*
X734867Y-13494D01*
X734950Y-13828D01*
X735200Y-14119D01*
X735575Y-14286D01*
X735992Y-14328D01*
X736534Y-14244D01*
X736825Y-14119D01*
X737117Y-13911D01*
X737325Y-13619D01*
X737367Y-13328D01*
X737284Y-13036D01*
X737075Y-12828D01*
G01X737367Y-11353D02*
X735575D01*
X735200Y-11186D01*
X734950Y-10853D01*
X734867Y-10436D01*
X734950Y-10019D01*
X735200Y-9686D01*
X735575Y-9519D01*
X737367D01*
G01X734867Y-7336D02*
X737367D01*
X736867Y-7836D01*
G01X734867D02*
Y-6836D01*
G01X735242Y-5153D02*
X735034Y-4903D01*
X734909Y-4611D01*
X734867Y-4236D01*
X734950Y-3861D01*
X735117Y-3569D01*
X735409Y-3361D01*
X735742Y-3319D01*
X736075Y-3403D01*
X736284Y-3611D01*
X736450Y-3903D01*
X736492Y-4194D01*
X736450Y-4486D01*
X736284Y-4861D01*
X737367Y-4736D01*
Y-3611D01*
G01X730297Y-14972D02*
X730422Y-15222D01*
X730505Y-15514D01*
Y-15847D01*
X730380Y-16222D01*
X730172Y-16514D01*
X729922Y-16722D01*
X729505Y-16889D01*
X729130Y-16931D01*
X728755Y-16847D01*
X728505Y-16722D01*
X728255Y-16472D01*
X728088Y-16181D01*
X728005Y-15889D01*
Y-15597D01*
X728088Y-15306D01*
X728213Y-15056D01*
X728380Y-14847D01*
G01X729047Y-13581D02*
X729338Y-13289D01*
X729505Y-13039D01*
X729588Y-12706D01*
X729505Y-12414D01*
X729338Y-12206D01*
X729088Y-12039D01*
X728797Y-11997D01*
X728547Y-12039D01*
X728297Y-12206D01*
X728088Y-12456D01*
X728005Y-12747D01*
X728088Y-13081D01*
X728338Y-13372D01*
X728713Y-13539D01*
X729130Y-13581D01*
X729672Y-13497D01*
X729963Y-13372D01*
X730255Y-13164D01*
X730463Y-12872D01*
X730505Y-12581D01*
X730422Y-12289D01*
X730213Y-12081D01*
G01X730505Y-10606D02*
X728713D01*
X728338Y-10439D01*
X728088Y-10106D01*
X728005Y-9689D01*
X728088Y-9272D01*
X728338Y-8939D01*
X728713Y-8772D01*
X730505D01*
G01X728005Y-6589D02*
X730505D01*
X730005Y-7089D01*
G01X728005D02*
Y-6089D01*
G01X729047Y-4281D02*
X729338Y-3989D01*
X729505Y-3739D01*
X729588Y-3406D01*
X729505Y-3114D01*
X729338Y-2906D01*
X729088Y-2739D01*
X728797Y-2697D01*
X728547Y-2739D01*
X728297Y-2906D01*
X728088Y-3156D01*
X728005Y-3447D01*
X728088Y-3781D01*
X728338Y-4072D01*
X728713Y-4239D01*
X729130Y-4281D01*
X729672Y-4197D01*
X729963Y-4072D01*
X730255Y-3864D01*
X730463Y-3572D01*
X730505Y-3281D01*
X730422Y-2989D01*
X730213Y-2781D01*
G01X777883Y-11708D02*
X778133Y-11583D01*
X778425Y-11500D01*
X778758D01*
X779133Y-11625D01*
X779425Y-11833D01*
X779633Y-12083D01*
X779800Y-12500D01*
X779842Y-12875D01*
X779758Y-13250D01*
X779633Y-13500D01*
X779383Y-13750D01*
X779092Y-13917D01*
X778800Y-14000D01*
X778508D01*
X778217Y-13917D01*
X777967Y-13792D01*
X777758Y-13625D01*
G01X776492Y-12958D02*
X776200Y-12667D01*
X775950Y-12500D01*
X775617Y-12417D01*
X775325Y-12500D01*
X775117Y-12667D01*
X774950Y-12917D01*
X774908Y-13208D01*
X774950Y-13458D01*
X775117Y-13708D01*
X775367Y-13917D01*
X775658Y-14000D01*
X775992Y-13917D01*
X776283Y-13667D01*
X776450Y-13292D01*
X776492Y-12875D01*
X776408Y-12333D01*
X776283Y-12042D01*
X776075Y-11750D01*
X775783Y-11542D01*
X775492Y-11500D01*
X775200Y-11583D01*
X774992Y-11792D01*
G01X773517Y-11500D02*
Y-13292D01*
X773350Y-13667D01*
X773017Y-13917D01*
X772600Y-14000D01*
X772183Y-13917D01*
X771850Y-13667D01*
X771683Y-13292D01*
Y-11500D01*
G01X769500Y-14000D02*
Y-11500D01*
X770000Y-12000D01*
G01Y-14000D02*
X769000D01*
G01X766483D02*
X766400Y-13458D01*
X766275Y-13000D01*
X766108Y-12583D01*
X765900Y-12125D01*
X765567Y-11500D01*
X767233D01*
G01X767852Y-4000D02*
Y-900D01*
X768312Y-1520D01*
G01Y-4000D02*
X767392D01*
G01X764292D02*
Y-900D01*
X765710Y-3122D01*
X763794D01*
G01X762495Y-3535D02*
X762265Y-3793D01*
X761997Y-3948D01*
X761652Y-4000D01*
X761307Y-3897D01*
X761039Y-3690D01*
X760847Y-3328D01*
X760809Y-2915D01*
X760885Y-2502D01*
X761077Y-2243D01*
X761345Y-2037D01*
X761614Y-1985D01*
X761882Y-2037D01*
X762227Y-2243D01*
X762112Y-900D01*
X761077D01*
G01X733330Y4216D02*
X733080Y4424D01*
X732913Y4674D01*
X732830Y4966D01*
X732913Y5299D01*
X733080Y5549D01*
X733330Y5799D01*
X733663Y5882D01*
X735330D01*
G01X733872Y7357D02*
X734163Y7649D01*
X734330Y7899D01*
X734413Y8232D01*
X734330Y8524D01*
X734163Y8732D01*
X733913Y8899D01*
X733622Y8941D01*
X733372Y8899D01*
X733122Y8732D01*
X732913Y8482D01*
X732830Y8191D01*
X732913Y7857D01*
X733163Y7566D01*
X733538Y7399D01*
X733955Y7357D01*
X734497Y7441D01*
X734788Y7566D01*
X735080Y7774D01*
X735288Y8066D01*
X735330Y8357D01*
X735247Y8649D01*
X735038Y8857D01*
G01X735330Y10332D02*
X733538D01*
X733163Y10499D01*
X732913Y10832D01*
X732830Y11249D01*
X732913Y11666D01*
X733163Y11999D01*
X733538Y12166D01*
X735330D01*
G01X734913Y13557D02*
X735163Y13807D01*
X735288Y14099D01*
X735330Y14432D01*
X735247Y14849D01*
X735038Y15141D01*
X734788Y15224D01*
X734538Y15182D01*
X734330Y15016D01*
X733913Y14182D01*
X733622Y13807D01*
X733205Y13557D01*
X732830Y13474D01*
Y15224D01*
G01X760710Y25873D02*
X736320D01*
Y283D01*
X760710D01*
G01X787123Y70505D02*
X787373Y70630D01*
X787665Y70713D01*
X787998D01*
X788373Y70588D01*
X788665Y70380D01*
X788873Y70130D01*
X789040Y69713D01*
X789082Y69338D01*
X788998Y68963D01*
X788873Y68713D01*
X788623Y68463D01*
X788332Y68296D01*
X788040Y68213D01*
X787748D01*
X787457Y68296D01*
X787207Y68421D01*
X786998Y68588D01*
G01X785732Y69255D02*
X785440Y69546D01*
X785190Y69713D01*
X784857Y69796D01*
X784565Y69713D01*
X784357Y69546D01*
X784190Y69296D01*
X784148Y69005D01*
X784190Y68755D01*
X784357Y68505D01*
X784607Y68296D01*
X784898Y68213D01*
X785232Y68296D01*
X785523Y68546D01*
X785690Y68921D01*
X785732Y69338D01*
X785648Y69880D01*
X785523Y70171D01*
X785315Y70463D01*
X785023Y70671D01*
X784732Y70713D01*
X784440Y70630D01*
X784232Y70421D01*
G01X781840Y70713D02*
Y68213D01*
G01X782798Y70713D02*
X780882D01*
G01X779532Y70296D02*
X779282Y70546D01*
X778990Y70671D01*
X778657Y70713D01*
X778240Y70630D01*
X777948Y70421D01*
X777865Y70171D01*
X777907Y69921D01*
X778073Y69713D01*
X778907Y69296D01*
X779282Y69005D01*
X779532Y68588D01*
X779615Y68213D01*
X777865D01*
G01X730792Y53567D02*
X730917Y53317D01*
X731000Y53025D01*
Y52692D01*
X730875Y52317D01*
X730667Y52025D01*
X730417Y51817D01*
X730000Y51650D01*
X729625Y51608D01*
X729250Y51692D01*
X729000Y51817D01*
X728750Y52067D01*
X728583Y52358D01*
X728500Y52650D01*
Y52942D01*
X728583Y53233D01*
X728708Y53483D01*
X728875Y53692D01*
G01X729542Y54958D02*
X729833Y55250D01*
X730000Y55500D01*
X730083Y55833D01*
X730000Y56125D01*
X729833Y56333D01*
X729583Y56500D01*
X729292Y56542D01*
X729042Y56500D01*
X728792Y56333D01*
X728583Y56083D01*
X728500Y55792D01*
X728583Y55458D01*
X728833Y55167D01*
X729208Y55000D01*
X729625Y54958D01*
X730167Y55042D01*
X730458Y55167D01*
X730750Y55375D01*
X730958Y55667D01*
X731000Y55958D01*
X730917Y56250D01*
X730708Y56458D01*
G01X731000Y57933D02*
X729208D01*
X728833Y58100D01*
X728583Y58433D01*
X728500Y58850D01*
X728583Y59267D01*
X728833Y59600D01*
X729208Y59767D01*
X731000D01*
G01X728500Y62450D02*
X731000D01*
X729208Y60908D01*
Y62992D01*
G01X770352Y72000D02*
Y75100D01*
X770812Y74480D01*
G01Y72000D02*
X769892D01*
G01X766792D02*
Y75100D01*
X768210Y72878D01*
X766294D01*
G01X764995Y72465D02*
X764765Y72207D01*
X764497Y72052D01*
X764152Y72000D01*
X763807Y72103D01*
X763539Y72310D01*
X763347Y72672D01*
X763309Y73085D01*
X763385Y73498D01*
X763577Y73757D01*
X763845Y73963D01*
X764114Y74015D01*
X764382Y73963D01*
X764727Y73757D01*
X764612Y75100D01*
X763577D01*
G01X729350Y92421D02*
X729100Y92629D01*
X728933Y92879D01*
X728850Y93171D01*
X728933Y93504D01*
X729100Y93754D01*
X729350Y94004D01*
X729683Y94087D01*
X731350D01*
G01X729892Y95562D02*
X730183Y95854D01*
X730350Y96104D01*
X730433Y96437D01*
X730350Y96729D01*
X730183Y96937D01*
X729933Y97104D01*
X729642Y97146D01*
X729392Y97104D01*
X729142Y96937D01*
X728933Y96687D01*
X728850Y96396D01*
X728933Y96062D01*
X729183Y95771D01*
X729558Y95604D01*
X729975Y95562D01*
X730517Y95646D01*
X730808Y95771D01*
X731100Y95979D01*
X731308Y96271D01*
X731350Y96562D01*
X731267Y96854D01*
X731058Y97062D01*
G01X731350Y99454D02*
X728850D01*
G01X731350Y98496D02*
Y100412D01*
G01X728850Y102554D02*
X731350D01*
X730850Y102054D01*
G01X728850D02*
Y103054D01*
G01X760710Y101473D02*
X736320D01*
Y75883D01*
X760710D01*
G01X770352Y34500D02*
Y37600D01*
X770812Y36980D01*
G01Y34500D02*
X769892D01*
G01X766792D02*
Y37600D01*
X768210Y35378D01*
X766294D01*
G01X764995Y34965D02*
X764765Y34707D01*
X764497Y34552D01*
X764152Y34500D01*
X763807Y34603D01*
X763539Y34810D01*
X763347Y35172D01*
X763309Y35585D01*
X763385Y35998D01*
X763577Y36257D01*
X763845Y36463D01*
X764114Y36515D01*
X764382Y36463D01*
X764727Y36257D01*
X764612Y37600D01*
X763577D01*
G01X733333Y45980D02*
X733083Y46188D01*
X732916Y46438D01*
X732833Y46730D01*
X732916Y47063D01*
X733083Y47313D01*
X733333Y47563D01*
X733666Y47646D01*
X735333D01*
G01X733875Y49121D02*
X734166Y49413D01*
X734333Y49663D01*
X734416Y49996D01*
X734333Y50288D01*
X734166Y50496D01*
X733916Y50663D01*
X733625Y50705D01*
X733375Y50663D01*
X733125Y50496D01*
X732916Y50246D01*
X732833Y49955D01*
X732916Y49621D01*
X733166Y49330D01*
X733541Y49163D01*
X733958Y49121D01*
X734500Y49205D01*
X734791Y49330D01*
X735083Y49538D01*
X735291Y49830D01*
X735333Y50121D01*
X735250Y50413D01*
X735041Y50621D01*
G01X735333Y52096D02*
X733541D01*
X733166Y52263D01*
X732916Y52596D01*
X732833Y53013D01*
X732916Y53430D01*
X733166Y53763D01*
X733541Y53930D01*
X735333D01*
G01X732833Y56113D02*
X735333D01*
X734833Y55613D01*
G01X732833D02*
Y56613D01*
G01X760710Y63673D02*
X736320D01*
Y38083D01*
X760710D01*
G01X772740Y209226D02*
Y211726D01*
X771699D01*
X771365Y211601D01*
X771157Y211434D01*
X771074Y211101D01*
X771157Y210768D01*
X771407Y210559D01*
X771699Y210434D01*
X772740D01*
G01X771699D02*
X771074Y209226D01*
G01X769599Y210268D02*
X769307Y210559D01*
X769057Y210726D01*
X768724Y210809D01*
X768432Y210726D01*
X768224Y210559D01*
X768057Y210309D01*
X768015Y210018D01*
X768057Y209768D01*
X768224Y209518D01*
X768474Y209309D01*
X768765Y209226D01*
X769099Y209309D01*
X769390Y209559D01*
X769557Y209934D01*
X769599Y210351D01*
X769515Y210893D01*
X769390Y211184D01*
X769182Y211476D01*
X768890Y211684D01*
X768599Y211726D01*
X768307Y211643D01*
X768099Y211434D01*
G01X766540Y209226D02*
Y211726D01*
X765499D01*
X765165Y211601D01*
X764957Y211434D01*
X764874Y211101D01*
X764957Y210768D01*
X765207Y210559D01*
X765499Y210434D01*
X766540D01*
G01X765499D02*
X764874Y209226D01*
G01X763399Y211309D02*
X763149Y211559D01*
X762857Y211684D01*
X762524Y211726D01*
X762107Y211643D01*
X761815Y211434D01*
X761732Y211184D01*
X761774Y210934D01*
X761940Y210726D01*
X762774Y210309D01*
X763149Y210018D01*
X763399Y209601D01*
X763482Y209226D01*
X761732D01*
G01X772283Y217792D02*
X772533Y217917D01*
X772825Y218000D01*
X773158D01*
X773533Y217875D01*
X773825Y217667D01*
X774033Y217417D01*
X774200Y217000D01*
X774242Y216625D01*
X774158Y216250D01*
X774033Y216000D01*
X773783Y215750D01*
X773492Y215583D01*
X773200Y215500D01*
X772908D01*
X772617Y215583D01*
X772367Y215708D01*
X772158Y215875D01*
G01X770100Y218000D02*
Y215500D01*
G01X771058Y218000D02*
X769142D01*
G01X767792Y217583D02*
X767542Y217833D01*
X767250Y217958D01*
X766917Y218000D01*
X766500Y217917D01*
X766208Y217708D01*
X766125Y217458D01*
X766167Y217208D01*
X766333Y217000D01*
X767167Y216583D01*
X767542Y216292D01*
X767792Y215875D01*
X767875Y215500D01*
X766125D01*
G01X749446Y184475D02*
X749696Y184600D01*
X749988Y184683D01*
X750321D01*
X750696Y184558D01*
X750988Y184350D01*
X751196Y184100D01*
X751363Y183683D01*
X751405Y183308D01*
X751321Y182933D01*
X751196Y182683D01*
X750946Y182433D01*
X750655Y182266D01*
X750363Y182183D01*
X750071D01*
X749780Y182266D01*
X749530Y182391D01*
X749321Y182558D01*
G01X748055Y183225D02*
X747763Y183516D01*
X747513Y183683D01*
X747180Y183766D01*
X746888Y183683D01*
X746680Y183516D01*
X746513Y183266D01*
X746471Y182975D01*
X746513Y182725D01*
X746680Y182475D01*
X746930Y182266D01*
X747221Y182183D01*
X747555Y182266D01*
X747846Y182516D01*
X748013Y182891D01*
X748055Y183308D01*
X747971Y183850D01*
X747846Y184141D01*
X747638Y184433D01*
X747346Y184641D01*
X747055Y184683D01*
X746763Y184600D01*
X746555Y184391D01*
G01X744996Y182183D02*
Y184683D01*
X743955D01*
X743621Y184558D01*
X743413Y184391D01*
X743330Y184058D01*
X743413Y183725D01*
X743663Y183516D01*
X743955Y183391D01*
X744996D01*
G01X743955D02*
X743330Y182183D01*
G01X741063D02*
Y184683D01*
X741563Y184183D01*
G01Y182183D02*
X740563D01*
G01X738755Y183225D02*
X738463Y183516D01*
X738213Y183683D01*
X737880Y183766D01*
X737588Y183683D01*
X737380Y183516D01*
X737213Y183266D01*
X737171Y182975D01*
X737213Y182725D01*
X737380Y182475D01*
X737630Y182266D01*
X737921Y182183D01*
X738255Y182266D01*
X738546Y182516D01*
X738713Y182891D01*
X738755Y183308D01*
X738671Y183850D01*
X738546Y184141D01*
X738338Y184433D01*
X738046Y184641D01*
X737755Y184683D01*
X737463Y184600D01*
X737255Y184391D01*
G01X759000Y186700D02*
Y189398D01*
G01Y204700D02*
Y202005D01*
G01Y204700D02*
X736428D01*
G01X759000Y186700D02*
X736425D01*
G01X781673Y206352D02*
X781923Y206477D01*
X782215Y206560D01*
X782548D01*
X782923Y206435D01*
X783215Y206227D01*
X783423Y205977D01*
X783590Y205560D01*
X783632Y205185D01*
X783548Y204810D01*
X783423Y204560D01*
X783173Y204310D01*
X782882Y204143D01*
X782590Y204060D01*
X782298D01*
X782007Y204143D01*
X781757Y204268D01*
X781548Y204435D01*
G01X778990Y204060D02*
Y206560D01*
X780532Y204768D01*
X778448D01*
G01X775557Y204060D02*
X777223D01*
Y206560D01*
X775557D01*
G01X776223Y205352D02*
X777223D01*
G01X774082Y205102D02*
X773790Y205393D01*
X773540Y205560D01*
X773207Y205643D01*
X772915Y205560D01*
X772707Y205393D01*
X772540Y205143D01*
X772498Y204852D01*
X772540Y204602D01*
X772707Y204352D01*
X772957Y204143D01*
X773248Y204060D01*
X773582Y204143D01*
X773873Y204393D01*
X774040Y204768D01*
X774082Y205185D01*
X773998Y205727D01*
X773873Y206018D01*
X773665Y206310D01*
X773373Y206518D01*
X773082Y206560D01*
X772790Y206477D01*
X772582Y206268D01*
G01X732105Y209045D02*
X732230Y208795D01*
X732313Y208503D01*
Y208170D01*
X732188Y207795D01*
X731980Y207503D01*
X731730Y207295D01*
X731313Y207128D01*
X730938Y207086D01*
X730563Y207170D01*
X730313Y207295D01*
X730063Y207545D01*
X729896Y207836D01*
X729813Y208128D01*
Y208420D01*
X729896Y208711D01*
X730021Y208961D01*
X730188Y209170D01*
G01X729813Y211728D02*
X732313D01*
X730521Y210186D01*
Y212270D01*
G01X729813Y215161D02*
Y213495D01*
X732313D01*
Y215161D01*
G01X731105Y214495D02*
Y213495D01*
G01X729813Y217428D02*
X729855Y217720D01*
X729980Y218053D01*
X730188Y218261D01*
X730480Y218345D01*
X730771Y218261D01*
X731021Y218011D01*
X731146Y217636D01*
Y217220D01*
X731230Y216970D01*
X731438Y216761D01*
X731730Y216678D01*
X732021Y216803D01*
X732230Y217095D01*
X732313Y217428D01*
X732230Y217761D01*
X732021Y218053D01*
X731730Y218178D01*
X731438Y218095D01*
X731230Y217886D01*
X731146Y217636D01*
Y217220D01*
X731021Y216845D01*
X730771Y216595D01*
X730480Y216511D01*
X730188Y216595D01*
X729980Y216803D01*
X729855Y217136D01*
X729813Y217428D01*
G01X754214Y219929D02*
X754339Y219679D01*
X754422Y219387D01*
Y219054D01*
X754297Y218679D01*
X754089Y218387D01*
X753839Y218179D01*
X753422Y218012D01*
X753047Y217970D01*
X752672Y218054D01*
X752422Y218179D01*
X752172Y218429D01*
X752005Y218720D01*
X751922Y219012D01*
Y219304D01*
X752005Y219595D01*
X752130Y219845D01*
X752297Y220054D01*
G01X754005Y221320D02*
X754255Y221570D01*
X754380Y221862D01*
X754422Y222195D01*
X754339Y222612D01*
X754130Y222904D01*
X753880Y222987D01*
X753630Y222945D01*
X753422Y222779D01*
X753005Y221945D01*
X752714Y221570D01*
X752297Y221320D01*
X751922Y221237D01*
Y222987D01*
G01X754005Y224420D02*
X754255Y224670D01*
X754380Y224962D01*
X754422Y225295D01*
X754339Y225712D01*
X754130Y226004D01*
X753880Y226087D01*
X753630Y226045D01*
X753422Y225879D01*
X753005Y225045D01*
X752714Y224670D01*
X752297Y224420D01*
X751922Y224337D01*
Y226087D01*
G01X754422Y227062D02*
X751922Y227645D01*
X754422Y228312D01*
X751922Y228979D01*
X754422Y229562D01*
G01X751922Y231412D02*
X754422D01*
X753922Y230912D01*
G01X751922D02*
Y231912D01*
G01Y234429D02*
X752464Y234512D01*
X752922Y234637D01*
X753339Y234804D01*
X753797Y235012D01*
X754422Y235345D01*
Y233679D01*
G01X771383Y264092D02*
X771633Y264217D01*
X771925Y264300D01*
X772258D01*
X772633Y264175D01*
X772925Y263967D01*
X773133Y263717D01*
X773300Y263300D01*
X773342Y262925D01*
X773258Y262550D01*
X773133Y262300D01*
X772883Y262050D01*
X772592Y261883D01*
X772300Y261800D01*
X772008D01*
X771717Y261883D01*
X771467Y262008D01*
X771258Y262175D01*
G01X769992Y262842D02*
X769700Y263133D01*
X769450Y263300D01*
X769117Y263383D01*
X768825Y263300D01*
X768617Y263133D01*
X768450Y262883D01*
X768408Y262592D01*
X768450Y262342D01*
X768617Y262092D01*
X768867Y261883D01*
X769158Y261800D01*
X769492Y261883D01*
X769783Y262133D01*
X769950Y262508D01*
X769992Y262925D01*
X769908Y263467D01*
X769783Y263758D01*
X769575Y264050D01*
X769283Y264258D01*
X768992Y264300D01*
X768700Y264217D01*
X768492Y264008D01*
G01X766933Y261800D02*
Y264300D01*
X765933D01*
X765600Y264175D01*
X765350Y263883D01*
X765267Y263550D01*
X765350Y263217D01*
X765558Y262967D01*
X765933Y262842D01*
X766933D01*
G01X763792Y263883D02*
X763542Y264133D01*
X763250Y264258D01*
X762917Y264300D01*
X762500Y264217D01*
X762208Y264008D01*
X762125Y263758D01*
X762167Y263508D01*
X762333Y263300D01*
X763167Y262883D01*
X763542Y262592D01*
X763792Y262175D01*
X763875Y261800D01*
X762125D01*
G01X759400D02*
Y264300D01*
X760942Y262508D01*
X758858D01*
G01X770883Y260792D02*
X771133Y260917D01*
X771425Y261000D01*
X771758D01*
X772133Y260875D01*
X772425Y260667D01*
X772633Y260417D01*
X772800Y260000D01*
X772842Y259625D01*
X772758Y259250D01*
X772633Y259000D01*
X772383Y258750D01*
X772092Y258583D01*
X771800Y258500D01*
X771508D01*
X771217Y258583D01*
X770967Y258708D01*
X770758Y258875D01*
G01X769492Y259542D02*
X769200Y259833D01*
X768950Y260000D01*
X768617Y260083D01*
X768325Y260000D01*
X768117Y259833D01*
X767950Y259583D01*
X767908Y259292D01*
X767950Y259042D01*
X768117Y258792D01*
X768367Y258583D01*
X768658Y258500D01*
X768992Y258583D01*
X769283Y258833D01*
X769450Y259208D01*
X769492Y259625D01*
X769408Y260167D01*
X769283Y260458D01*
X769075Y260750D01*
X768783Y260958D01*
X768492Y261000D01*
X768200Y260917D01*
X767992Y260708D01*
G01X766433Y258500D02*
Y261000D01*
X765392D01*
X765058Y260875D01*
X764850Y260708D01*
X764767Y260375D01*
X764850Y260042D01*
X765100Y259833D01*
X765392Y259708D01*
X766433D01*
G01X765392D02*
X764767Y258500D01*
G01X762000D02*
Y261000D01*
X763542Y259208D01*
X761458D01*
G01X771483Y233392D02*
X771733Y233517D01*
X772025Y233600D01*
X772358D01*
X772733Y233475D01*
X773025Y233267D01*
X773233Y233017D01*
X773400Y232600D01*
X773442Y232225D01*
X773358Y231850D01*
X773233Y231600D01*
X772983Y231350D01*
X772692Y231183D01*
X772400Y231100D01*
X772108D01*
X771817Y231183D01*
X771567Y231308D01*
X771358Y231475D01*
G01X770092Y232142D02*
X769800Y232433D01*
X769550Y232600D01*
X769217Y232683D01*
X768925Y232600D01*
X768717Y232433D01*
X768550Y232183D01*
X768508Y231892D01*
X768550Y231642D01*
X768717Y231392D01*
X768967Y231183D01*
X769258Y231100D01*
X769592Y231183D01*
X769883Y231433D01*
X770050Y231808D01*
X770092Y232225D01*
X770008Y232767D01*
X769883Y233058D01*
X769675Y233350D01*
X769383Y233558D01*
X769092Y233600D01*
X768800Y233517D01*
X768592Y233308D01*
G01X767033Y231100D02*
Y233600D01*
X765992D01*
X765658Y233475D01*
X765450Y233308D01*
X765367Y232975D01*
X765450Y232642D01*
X765700Y232433D01*
X765992Y232308D01*
X767033D01*
G01X765992D02*
X765367Y231100D01*
G01X763892Y232142D02*
X763600Y232433D01*
X763350Y232600D01*
X763017Y232683D01*
X762725Y232600D01*
X762517Y232433D01*
X762350Y232183D01*
X762308Y231892D01*
X762350Y231642D01*
X762517Y231392D01*
X762767Y231183D01*
X763058Y231100D01*
X763392Y231183D01*
X763683Y231433D01*
X763850Y231808D01*
X763892Y232225D01*
X763808Y232767D01*
X763683Y233058D01*
X763475Y233350D01*
X763183Y233558D01*
X762892Y233600D01*
X762600Y233517D01*
X762392Y233308D01*
G01X771483Y229392D02*
X771733Y229517D01*
X772025Y229600D01*
X772358D01*
X772733Y229475D01*
X773025Y229267D01*
X773233Y229017D01*
X773400Y228600D01*
X773442Y228225D01*
X773358Y227850D01*
X773233Y227600D01*
X772983Y227350D01*
X772692Y227183D01*
X772400Y227100D01*
X772108D01*
X771817Y227183D01*
X771567Y227308D01*
X771358Y227475D01*
G01X770092Y228142D02*
X769800Y228433D01*
X769550Y228600D01*
X769217Y228683D01*
X768925Y228600D01*
X768717Y228433D01*
X768550Y228183D01*
X768508Y227892D01*
X768550Y227642D01*
X768717Y227392D01*
X768967Y227183D01*
X769258Y227100D01*
X769592Y227183D01*
X769883Y227433D01*
X770050Y227808D01*
X770092Y228225D01*
X770008Y228767D01*
X769883Y229058D01*
X769675Y229350D01*
X769383Y229558D01*
X769092Y229600D01*
X768800Y229517D01*
X768592Y229308D01*
G01X767033Y227100D02*
Y229600D01*
X765992D01*
X765658Y229475D01*
X765450Y229308D01*
X765367Y228975D01*
X765450Y228642D01*
X765700Y228433D01*
X765992Y228308D01*
X767033D01*
G01X765992D02*
X765367Y227100D01*
G01X763100D02*
Y229600D01*
X763600Y229100D01*
G01Y227100D02*
X762600D01*
G01X760000D02*
Y229600D01*
X760500Y229100D01*
G01Y227100D02*
X759500D01*
G01X770383Y225592D02*
X770633Y225717D01*
X770925Y225800D01*
X771258D01*
X771633Y225675D01*
X771925Y225467D01*
X772133Y225217D01*
X772300Y224800D01*
X772342Y224425D01*
X772258Y224050D01*
X772133Y223800D01*
X771883Y223550D01*
X771592Y223383D01*
X771300Y223300D01*
X771008D01*
X770717Y223383D01*
X770467Y223508D01*
X770258Y223675D01*
G01X768992Y224342D02*
X768700Y224633D01*
X768450Y224800D01*
X768117Y224883D01*
X767825Y224800D01*
X767617Y224633D01*
X767450Y224383D01*
X767408Y224092D01*
X767450Y223842D01*
X767617Y223592D01*
X767867Y223383D01*
X768158Y223300D01*
X768492Y223383D01*
X768783Y223633D01*
X768950Y224008D01*
X768992Y224425D01*
X768908Y224967D01*
X768783Y225258D01*
X768575Y225550D01*
X768283Y225758D01*
X767992Y225800D01*
X767700Y225717D01*
X767492Y225508D01*
G01X765933Y223300D02*
Y225800D01*
X764892D01*
X764558Y225675D01*
X764350Y225508D01*
X764267Y225175D01*
X764350Y224842D01*
X764600Y224633D01*
X764892Y224508D01*
X765933D01*
G01X764892D02*
X764267Y223300D01*
G01X762000D02*
Y225800D01*
X762500Y225300D01*
G01Y223300D02*
X761500D01*
G01X759817Y223800D02*
X759567Y223508D01*
X759233Y223342D01*
X758858Y223300D01*
X758525Y223342D01*
X758192Y223550D01*
X757983Y223800D01*
X757942Y224050D01*
X758025Y224342D01*
X758317Y224550D01*
X758608Y224633D01*
X758983D01*
G01X758608D02*
X758358Y224758D01*
X758150Y224967D01*
X758067Y225217D01*
X758150Y225467D01*
X758358Y225675D01*
X758733Y225800D01*
X759108Y225758D01*
X759483Y225592D01*
G01X765947Y267852D02*
X766197Y267977D01*
X766489Y268060D01*
X766822D01*
X767197Y267935D01*
X767489Y267727D01*
X767697Y267477D01*
X767864Y267060D01*
X767906Y266685D01*
X767822Y266310D01*
X767697Y266060D01*
X767447Y265810D01*
X767156Y265643D01*
X766864Y265560D01*
X766572D01*
X766281Y265643D01*
X766031Y265768D01*
X765822Y265935D01*
G01X764556Y266602D02*
X764264Y266893D01*
X764014Y267060D01*
X763681Y267143D01*
X763389Y267060D01*
X763181Y266893D01*
X763014Y266643D01*
X762972Y266352D01*
X763014Y266102D01*
X763181Y265852D01*
X763431Y265643D01*
X763722Y265560D01*
X764056Y265643D01*
X764347Y265893D01*
X764514Y266268D01*
X764556Y266685D01*
X764472Y267227D01*
X764347Y267518D01*
X764139Y267810D01*
X763847Y268018D01*
X763556Y268060D01*
X763264Y267977D01*
X763056Y267768D01*
G01X761497Y265560D02*
Y268060D01*
X760497D01*
X760164Y267935D01*
X759914Y267643D01*
X759831Y267310D01*
X759914Y266977D01*
X760122Y266727D01*
X760497Y266602D01*
X761497D01*
G01X758356Y267643D02*
X758106Y267893D01*
X757814Y268018D01*
X757481Y268060D01*
X757064Y267977D01*
X756772Y267768D01*
X756689Y267518D01*
X756731Y267268D01*
X756897Y267060D01*
X757731Y266643D01*
X758106Y266352D01*
X758356Y265935D01*
X758439Y265560D01*
X756689D01*
G01X755256Y267643D02*
X755006Y267893D01*
X754714Y268018D01*
X754381Y268060D01*
X753964Y267977D01*
X753672Y267768D01*
X753589Y267518D01*
X753631Y267268D01*
X753797Y267060D01*
X754631Y266643D01*
X755006Y266352D01*
X755256Y265935D01*
X755339Y265560D01*
X753589D01*
G01X763615Y246689D02*
Y249189D01*
X762574D01*
X762240Y249064D01*
X762032Y248897D01*
X761949Y248564D01*
X762032Y248231D01*
X762282Y248022D01*
X762574Y247897D01*
X763615D01*
G01X762574D02*
X761949Y246689D01*
G01X760474Y247731D02*
X760182Y248022D01*
X759932Y248189D01*
X759599Y248272D01*
X759307Y248189D01*
X759099Y248022D01*
X758932Y247772D01*
X758890Y247481D01*
X758932Y247231D01*
X759099Y246981D01*
X759349Y246772D01*
X759640Y246689D01*
X759974Y246772D01*
X760265Y247022D01*
X760432Y247397D01*
X760474Y247814D01*
X760390Y248356D01*
X760265Y248647D01*
X760057Y248939D01*
X759765Y249147D01*
X759474Y249189D01*
X759182Y249106D01*
X758974Y248897D01*
G01X757415Y246689D02*
Y249189D01*
X756374D01*
X756040Y249064D01*
X755832Y248897D01*
X755749Y248564D01*
X755832Y248231D01*
X756082Y248022D01*
X756374Y247897D01*
X757415D01*
G01X756374D02*
X755749Y246689D01*
G01X754274Y247731D02*
X753982Y248022D01*
X753732Y248189D01*
X753399Y248272D01*
X753107Y248189D01*
X752899Y248022D01*
X752732Y247772D01*
X752690Y247481D01*
X752732Y247231D01*
X752899Y246981D01*
X753149Y246772D01*
X753440Y246689D01*
X753774Y246772D01*
X754065Y247022D01*
X754232Y247397D01*
X754274Y247814D01*
X754190Y248356D01*
X754065Y248647D01*
X753857Y248939D01*
X753565Y249147D01*
X753274Y249189D01*
X752982Y249106D01*
X752774Y248897D01*
G01X762677Y277983D02*
Y280483D01*
X761636D01*
X761302Y280358D01*
X761094Y280191D01*
X761011Y279858D01*
X761094Y279525D01*
X761344Y279316D01*
X761636Y279191D01*
X762677D01*
G01X761636D02*
X761011Y277983D01*
G01X759536Y279025D02*
X759244Y279316D01*
X758994Y279483D01*
X758661Y279566D01*
X758369Y279483D01*
X758161Y279316D01*
X757994Y279066D01*
X757952Y278775D01*
X757994Y278525D01*
X758161Y278275D01*
X758411Y278066D01*
X758702Y277983D01*
X759036Y278066D01*
X759327Y278316D01*
X759494Y278691D01*
X759536Y279108D01*
X759452Y279650D01*
X759327Y279941D01*
X759119Y280233D01*
X758827Y280441D01*
X758536Y280483D01*
X758244Y280400D01*
X758036Y280191D01*
G01X756477Y277983D02*
Y280483D01*
X755477D01*
X755144Y280358D01*
X754894Y280066D01*
X754811Y279733D01*
X754894Y279400D01*
X755102Y279150D01*
X755477Y279025D01*
X756477D01*
G01X752544Y277983D02*
Y280483D01*
X753044Y279983D01*
G01Y277983D02*
X752044D01*
G01X750152Y278275D02*
X749861Y278066D01*
X749527Y277983D01*
X749194Y278066D01*
X748902Y278316D01*
X748694Y278691D01*
X748611Y279066D01*
Y279525D01*
X748694Y279900D01*
X748902Y280233D01*
X749152Y280400D01*
X749444Y280483D01*
X749777Y280400D01*
X750027Y280233D01*
X750194Y279983D01*
X750277Y279650D01*
X750194Y279358D01*
X749986Y279066D01*
X749736Y278900D01*
X749444Y278858D01*
X749111Y278941D01*
X748861Y279150D01*
X748611Y279525D01*
G01X726911Y267110D02*
X729411D01*
Y268151D01*
X729286Y268485D01*
X729119Y268693D01*
X728786Y268776D01*
X728453Y268693D01*
X728244Y268443D01*
X728119Y268151D01*
Y267110D01*
G01Y268151D02*
X726911Y268776D01*
G01X727953Y270251D02*
X728244Y270543D01*
X728411Y270793D01*
X728494Y271126D01*
X728411Y271418D01*
X728244Y271626D01*
X727994Y271793D01*
X727703Y271835D01*
X727453Y271793D01*
X727203Y271626D01*
X726994Y271376D01*
X726911Y271085D01*
X726994Y270751D01*
X727244Y270460D01*
X727619Y270293D01*
X728036Y270251D01*
X728578Y270335D01*
X728869Y270460D01*
X729161Y270668D01*
X729369Y270960D01*
X729411Y271251D01*
X729328Y271543D01*
X729119Y271751D01*
G01X726911Y273310D02*
X729411D01*
Y274310D01*
X729286Y274643D01*
X728994Y274893D01*
X728661Y274976D01*
X728328Y274893D01*
X728078Y274685D01*
X727953Y274310D01*
Y273310D01*
G01X728994Y276451D02*
X729244Y276701D01*
X729369Y276993D01*
X729411Y277326D01*
X729328Y277743D01*
X729119Y278035D01*
X728869Y278118D01*
X728619Y278076D01*
X728411Y277910D01*
X727994Y277076D01*
X727703Y276701D01*
X727286Y276451D01*
X726911Y276368D01*
Y278118D01*
G01Y280260D02*
X727453Y280343D01*
X727911Y280468D01*
X728328Y280635D01*
X728786Y280843D01*
X729411Y281176D01*
Y279510D01*
G01X761783Y253092D02*
X762033Y253217D01*
X762325Y253300D01*
X762658D01*
X763033Y253175D01*
X763325Y252967D01*
X763533Y252717D01*
X763700Y252300D01*
X763742Y251925D01*
X763658Y251550D01*
X763533Y251300D01*
X763283Y251050D01*
X762992Y250883D01*
X762700Y250800D01*
X762408D01*
X762117Y250883D01*
X761867Y251008D01*
X761658Y251175D01*
G01X759600Y253300D02*
Y250800D01*
G01X760558Y253300D02*
X758642D01*
G01X756000Y250800D02*
Y253300D01*
X757542Y251508D01*
X755458D01*
G01X765777Y241094D02*
X766027Y241219D01*
X766319Y241302D01*
X766652D01*
X767027Y241177D01*
X767319Y240969D01*
X767527Y240719D01*
X767694Y240302D01*
X767736Y239927D01*
X767652Y239552D01*
X767527Y239302D01*
X767277Y239052D01*
X766986Y238885D01*
X766694Y238802D01*
X766402D01*
X766111Y238885D01*
X765861Y239010D01*
X765652Y239177D01*
G01X763094Y238802D02*
Y241302D01*
X764636Y239510D01*
X762552D01*
G01X759661Y238802D02*
X761327D01*
Y241302D01*
X759661D01*
G01X760327Y240094D02*
X761327D01*
G01X758186Y240885D02*
X757936Y241135D01*
X757644Y241260D01*
X757311Y241302D01*
X756894Y241219D01*
X756602Y241010D01*
X756519Y240760D01*
X756561Y240510D01*
X756727Y240302D01*
X757561Y239885D01*
X757936Y239594D01*
X758186Y239177D01*
X758269Y238802D01*
X756519D01*
G01X755211Y239177D02*
X754961Y238969D01*
X754669Y238844D01*
X754294Y238802D01*
X753919Y238885D01*
X753627Y239052D01*
X753419Y239344D01*
X753377Y239677D01*
X753461Y240010D01*
X753669Y240219D01*
X753961Y240385D01*
X754252Y240427D01*
X754544Y240385D01*
X754919Y240219D01*
X754794Y241302D01*
X753669D01*
G01X768732Y273628D02*
X768982Y273753D01*
X769274Y273836D01*
X769607D01*
X769982Y273711D01*
X770274Y273503D01*
X770482Y273253D01*
X770649Y272836D01*
X770691Y272461D01*
X770607Y272086D01*
X770482Y271836D01*
X770232Y271586D01*
X769941Y271419D01*
X769649Y271336D01*
X769357D01*
X769066Y271419D01*
X768816Y271544D01*
X768607Y271711D01*
G01X766049Y271336D02*
Y273836D01*
X767591Y272044D01*
X765507D01*
G01X764366Y271336D02*
Y273836D01*
X763532D01*
X763199Y273711D01*
X762949Y273544D01*
X762741Y273294D01*
X762574Y273003D01*
X762532Y272586D01*
X762574Y272169D01*
X762741Y271878D01*
X762949Y271628D01*
X763199Y271461D01*
X763532Y271336D01*
X764366D01*
G01X760349D02*
Y273836D01*
X760849Y273336D01*
G01Y271336D02*
X759849D01*
G01X756749D02*
Y273836D01*
X758291Y272044D01*
X756207D01*
G01X735312Y243807D02*
X735437Y243557D01*
X735520Y243265D01*
Y242932D01*
X735395Y242557D01*
X735187Y242265D01*
X734937Y242057D01*
X734520Y241890D01*
X734145Y241848D01*
X733770Y241932D01*
X733520Y242057D01*
X733270Y242307D01*
X733103Y242598D01*
X733020Y242890D01*
Y243182D01*
X733103Y243473D01*
X733228Y243723D01*
X733395Y243932D01*
G01X735103Y245198D02*
X735353Y245448D01*
X735478Y245740D01*
X735520Y246073D01*
X735437Y246490D01*
X735228Y246782D01*
X734978Y246865D01*
X734728Y246823D01*
X734520Y246657D01*
X734103Y245823D01*
X733812Y245448D01*
X733395Y245198D01*
X733020Y245115D01*
Y246865D01*
G01X735103Y248298D02*
X735353Y248548D01*
X735478Y248840D01*
X735520Y249173D01*
X735437Y249590D01*
X735228Y249882D01*
X734978Y249965D01*
X734728Y249923D01*
X734520Y249757D01*
X734103Y248923D01*
X733812Y248548D01*
X733395Y248298D01*
X733020Y248215D01*
Y249965D01*
G01X735520Y250940D02*
X733020Y251523D01*
X735520Y252190D01*
X733020Y252857D01*
X735520Y253440D01*
G01X733020Y255290D02*
X735520D01*
X735020Y254790D01*
G01X733020D02*
Y255790D01*
G01X733395Y257473D02*
X733187Y257723D01*
X733062Y258015D01*
X733020Y258390D01*
X733103Y258765D01*
X733270Y259057D01*
X733562Y259265D01*
X733895Y259307D01*
X734228Y259223D01*
X734437Y259015D01*
X734603Y258723D01*
X734645Y258432D01*
X734603Y258140D01*
X734437Y257765D01*
X735520Y257890D01*
Y259015D01*
G01X745107Y247426D02*
X745232Y247176D01*
X745315Y246884D01*
Y246551D01*
X745190Y246176D01*
X744982Y245884D01*
X744732Y245676D01*
X744315Y245509D01*
X743940Y245467D01*
X743565Y245551D01*
X743315Y245676D01*
X743065Y245926D01*
X742898Y246217D01*
X742815Y246509D01*
Y246801D01*
X742898Y247092D01*
X743023Y247342D01*
X743190Y247551D01*
G01X744898Y248817D02*
X745148Y249067D01*
X745273Y249359D01*
X745315Y249692D01*
X745232Y250109D01*
X745023Y250401D01*
X744773Y250484D01*
X744523Y250442D01*
X744315Y250276D01*
X743898Y249442D01*
X743607Y249067D01*
X743190Y248817D01*
X742815Y248734D01*
Y250484D01*
G01X744898Y251917D02*
X745148Y252167D01*
X745273Y252459D01*
X745315Y252792D01*
X745232Y253209D01*
X745023Y253501D01*
X744773Y253584D01*
X744523Y253542D01*
X744315Y253376D01*
X743898Y252542D01*
X743607Y252167D01*
X743190Y251917D01*
X742815Y251834D01*
Y253584D01*
G01X745315Y254559D02*
X742815Y255142D01*
X745315Y255809D01*
X742815Y256476D01*
X745315Y257059D01*
G01X744898Y258117D02*
X745148Y258367D01*
X745273Y258659D01*
X745315Y258992D01*
X745232Y259409D01*
X745023Y259701D01*
X744773Y259784D01*
X744523Y259742D01*
X744315Y259576D01*
X743898Y258742D01*
X743607Y258367D01*
X743190Y258117D01*
X742815Y258034D01*
Y259784D01*
G01Y262009D02*
X745315D01*
X744815Y261509D01*
G01X742815D02*
Y262509D01*
G01X763814Y299370D02*
X764064Y299495D01*
X764356Y299578D01*
X764689D01*
X765064Y299453D01*
X765356Y299245D01*
X765564Y298995D01*
X765731Y298578D01*
X765773Y298203D01*
X765689Y297828D01*
X765564Y297578D01*
X765314Y297328D01*
X765023Y297161D01*
X764731Y297078D01*
X764439D01*
X764148Y297161D01*
X763898Y297286D01*
X763689Y297453D01*
G01X762423Y298120D02*
X762131Y298411D01*
X761881Y298578D01*
X761548Y298661D01*
X761256Y298578D01*
X761048Y298411D01*
X760881Y298161D01*
X760839Y297870D01*
X760881Y297620D01*
X761048Y297370D01*
X761298Y297161D01*
X761589Y297078D01*
X761923Y297161D01*
X762214Y297411D01*
X762381Y297786D01*
X762423Y298203D01*
X762339Y298745D01*
X762214Y299036D01*
X762006Y299328D01*
X761714Y299536D01*
X761423Y299578D01*
X761131Y299495D01*
X760923Y299286D01*
G01X759364Y297078D02*
Y299578D01*
X758364D01*
X758031Y299453D01*
X757781Y299161D01*
X757698Y298828D01*
X757781Y298495D01*
X757989Y298245D01*
X758364Y298120D01*
X759364D01*
G01X755431Y297078D02*
Y299578D01*
X755931Y299078D01*
G01Y297078D02*
X754931D01*
G01X752414D02*
X752331Y297620D01*
X752206Y298078D01*
X752039Y298495D01*
X751831Y298953D01*
X751498Y299578D01*
X753164D01*
G01X767946Y291708D02*
X768196Y291833D01*
X768488Y291916D01*
X768821D01*
X769196Y291791D01*
X769488Y291583D01*
X769696Y291333D01*
X769863Y290916D01*
X769905Y290541D01*
X769821Y290166D01*
X769696Y289916D01*
X769446Y289666D01*
X769155Y289499D01*
X768863Y289416D01*
X768571D01*
X768280Y289499D01*
X768030Y289624D01*
X767821Y289791D01*
G01X766555Y290458D02*
X766263Y290749D01*
X766013Y290916D01*
X765680Y290999D01*
X765388Y290916D01*
X765180Y290749D01*
X765013Y290499D01*
X764971Y290208D01*
X765013Y289958D01*
X765180Y289708D01*
X765430Y289499D01*
X765721Y289416D01*
X766055Y289499D01*
X766346Y289749D01*
X766513Y290124D01*
X766555Y290541D01*
X766471Y291083D01*
X766346Y291374D01*
X766138Y291666D01*
X765846Y291874D01*
X765555Y291916D01*
X765263Y291833D01*
X765055Y291624D01*
G01X763496Y289416D02*
Y291916D01*
X762496D01*
X762163Y291791D01*
X761913Y291499D01*
X761830Y291166D01*
X761913Y290833D01*
X762121Y290583D01*
X762496Y290458D01*
X763496D01*
G01X760355Y291499D02*
X760105Y291749D01*
X759813Y291874D01*
X759480Y291916D01*
X759063Y291833D01*
X758771Y291624D01*
X758688Y291374D01*
X758730Y291124D01*
X758896Y290916D01*
X759730Y290499D01*
X760105Y290208D01*
X760355Y289791D01*
X760438Y289416D01*
X758688D01*
G01X756463Y291916D02*
X756796Y291833D01*
X757046Y291624D01*
X757213Y291374D01*
X757338Y291041D01*
X757380Y290666D01*
X757338Y290291D01*
X757213Y289958D01*
X757046Y289708D01*
X756796Y289499D01*
X756463Y289416D01*
X756130Y289499D01*
X755880Y289708D01*
X755713Y289958D01*
X755588Y290291D01*
X755546Y290666D01*
X755588Y291041D01*
X755713Y291374D01*
X755880Y291624D01*
X756130Y291833D01*
X756463Y291916D01*
G01X767946Y295708D02*
X768196Y295833D01*
X768488Y295916D01*
X768821D01*
X769196Y295791D01*
X769488Y295583D01*
X769696Y295333D01*
X769863Y294916D01*
X769905Y294541D01*
X769821Y294166D01*
X769696Y293916D01*
X769446Y293666D01*
X769155Y293499D01*
X768863Y293416D01*
X768571D01*
X768280Y293499D01*
X768030Y293624D01*
X767821Y293791D01*
G01X766555Y294458D02*
X766263Y294749D01*
X766013Y294916D01*
X765680Y294999D01*
X765388Y294916D01*
X765180Y294749D01*
X765013Y294499D01*
X764971Y294208D01*
X765013Y293958D01*
X765180Y293708D01*
X765430Y293499D01*
X765721Y293416D01*
X766055Y293499D01*
X766346Y293749D01*
X766513Y294124D01*
X766555Y294541D01*
X766471Y295083D01*
X766346Y295374D01*
X766138Y295666D01*
X765846Y295874D01*
X765555Y295916D01*
X765263Y295833D01*
X765055Y295624D01*
G01X763496Y293416D02*
Y295916D01*
X762496D01*
X762163Y295791D01*
X761913Y295499D01*
X761830Y295166D01*
X761913Y294833D01*
X762121Y294583D01*
X762496Y294458D01*
X763496D01*
G01X759563Y293416D02*
Y295916D01*
X760063Y295416D01*
G01Y293416D02*
X759063D01*
G01X757171Y293708D02*
X756880Y293499D01*
X756546Y293416D01*
X756213Y293499D01*
X755921Y293749D01*
X755713Y294124D01*
X755630Y294499D01*
Y294958D01*
X755713Y295333D01*
X755921Y295666D01*
X756171Y295833D01*
X756463Y295916D01*
X756796Y295833D01*
X757046Y295666D01*
X757213Y295416D01*
X757296Y295083D01*
X757213Y294791D01*
X757005Y294499D01*
X756755Y294333D01*
X756463Y294291D01*
X756130Y294374D01*
X755880Y294583D01*
X755630Y294958D01*
G01X767083Y325212D02*
X767333Y325337D01*
X767625Y325420D01*
X767958D01*
X768333Y325295D01*
X768625Y325087D01*
X768833Y324837D01*
X769000Y324420D01*
X769042Y324045D01*
X768958Y323670D01*
X768833Y323420D01*
X768583Y323170D01*
X768292Y323003D01*
X768000Y322920D01*
X767708D01*
X767417Y323003D01*
X767167Y323128D01*
X766958Y323295D01*
G01X765692Y323962D02*
X765400Y324253D01*
X765150Y324420D01*
X764817Y324503D01*
X764525Y324420D01*
X764317Y324253D01*
X764150Y324003D01*
X764108Y323712D01*
X764150Y323462D01*
X764317Y323212D01*
X764567Y323003D01*
X764858Y322920D01*
X765192Y323003D01*
X765483Y323253D01*
X765650Y323628D01*
X765692Y324045D01*
X765608Y324587D01*
X765483Y324878D01*
X765275Y325170D01*
X764983Y325378D01*
X764692Y325420D01*
X764400Y325337D01*
X764192Y325128D01*
G01X762633Y322920D02*
Y325420D01*
X761633D01*
X761300Y325295D01*
X761050Y325003D01*
X760967Y324670D01*
X761050Y324337D01*
X761258Y324087D01*
X761633Y323962D01*
X762633D01*
G01X758700Y322920D02*
Y325420D01*
X759200Y324920D01*
G01Y322920D02*
X758200D01*
G01X756517Y323295D02*
X756267Y323087D01*
X755975Y322962D01*
X755600Y322920D01*
X755225Y323003D01*
X754933Y323170D01*
X754725Y323462D01*
X754683Y323795D01*
X754767Y324128D01*
X754975Y324337D01*
X755267Y324503D01*
X755558Y324545D01*
X755850Y324503D01*
X756225Y324337D01*
X756100Y325420D01*
X754975D01*
G01X771940Y328957D02*
X772190Y329082D01*
X772482Y329165D01*
X772815D01*
X773190Y329040D01*
X773482Y328832D01*
X773690Y328582D01*
X773857Y328165D01*
X773899Y327790D01*
X773815Y327415D01*
X773690Y327165D01*
X773440Y326915D01*
X773149Y326748D01*
X772857Y326665D01*
X772565D01*
X772274Y326748D01*
X772024Y326873D01*
X771815Y327040D01*
G01X770549Y327707D02*
X770257Y327998D01*
X770007Y328165D01*
X769674Y328248D01*
X769382Y328165D01*
X769174Y327998D01*
X769007Y327748D01*
X768965Y327457D01*
X769007Y327207D01*
X769174Y326957D01*
X769424Y326748D01*
X769715Y326665D01*
X770049Y326748D01*
X770340Y326998D01*
X770507Y327373D01*
X770549Y327790D01*
X770465Y328332D01*
X770340Y328623D01*
X770132Y328915D01*
X769840Y329123D01*
X769549Y329165D01*
X769257Y329082D01*
X769049Y328873D01*
G01X767490Y326665D02*
Y329165D01*
X766490D01*
X766157Y329040D01*
X765907Y328748D01*
X765824Y328415D01*
X765907Y328082D01*
X766115Y327832D01*
X766490Y327707D01*
X767490D01*
G01X763557Y326665D02*
Y329165D01*
X764057Y328665D01*
G01Y326665D02*
X763057D01*
G01X761374Y327165D02*
X761124Y326873D01*
X760790Y326707D01*
X760415Y326665D01*
X760082Y326707D01*
X759749Y326915D01*
X759540Y327165D01*
X759499Y327415D01*
X759582Y327707D01*
X759874Y327915D01*
X760165Y327998D01*
X760540D01*
G01X760165D02*
X759915Y328123D01*
X759707Y328332D01*
X759624Y328582D01*
X759707Y328832D01*
X759915Y329040D01*
X760290Y329165D01*
X760665Y329123D01*
X761040Y328957D01*
G01X767083Y333212D02*
X767333Y333337D01*
X767625Y333420D01*
X767958D01*
X768333Y333295D01*
X768625Y333087D01*
X768833Y332837D01*
X769000Y332420D01*
X769042Y332045D01*
X768958Y331670D01*
X768833Y331420D01*
X768583Y331170D01*
X768292Y331003D01*
X768000Y330920D01*
X767708D01*
X767417Y331003D01*
X767167Y331128D01*
X766958Y331295D01*
G01X765692Y331962D02*
X765400Y332253D01*
X765150Y332420D01*
X764817Y332503D01*
X764525Y332420D01*
X764317Y332253D01*
X764150Y332003D01*
X764108Y331712D01*
X764150Y331462D01*
X764317Y331212D01*
X764567Y331003D01*
X764858Y330920D01*
X765192Y331003D01*
X765483Y331253D01*
X765650Y331628D01*
X765692Y332045D01*
X765608Y332587D01*
X765483Y332878D01*
X765275Y333170D01*
X764983Y333378D01*
X764692Y333420D01*
X764400Y333337D01*
X764192Y333128D01*
G01X762633Y330920D02*
Y333420D01*
X761633D01*
X761300Y333295D01*
X761050Y333003D01*
X760967Y332670D01*
X761050Y332337D01*
X761258Y332087D01*
X761633Y331962D01*
X762633D01*
G01X758783Y330920D02*
X758700Y331462D01*
X758575Y331920D01*
X758408Y332337D01*
X758200Y332795D01*
X757867Y333420D01*
X759533D01*
G01X763365Y340589D02*
Y343089D01*
X762324D01*
X761990Y342964D01*
X761782Y342797D01*
X761699Y342464D01*
X761782Y342131D01*
X762032Y341922D01*
X762324Y341797D01*
X763365D01*
G01X762324D02*
X761699Y340589D01*
G01X760224Y341631D02*
X759932Y341922D01*
X759682Y342089D01*
X759349Y342172D01*
X759057Y342089D01*
X758849Y341922D01*
X758682Y341672D01*
X758640Y341381D01*
X758682Y341131D01*
X758849Y340881D01*
X759099Y340672D01*
X759390Y340589D01*
X759724Y340672D01*
X760015Y340922D01*
X760182Y341297D01*
X760224Y341714D01*
X760140Y342256D01*
X760015Y342547D01*
X759807Y342839D01*
X759515Y343047D01*
X759224Y343089D01*
X758932Y343006D01*
X758724Y342797D01*
G01X757165Y340589D02*
Y343089D01*
X756165D01*
X755832Y342964D01*
X755582Y342672D01*
X755499Y342339D01*
X755582Y342006D01*
X755790Y341756D01*
X756165Y341631D01*
X757165D01*
G01X752732Y340589D02*
Y343089D01*
X754274Y341297D01*
X752190D01*
G01X750215Y340589D02*
X750132Y341131D01*
X750007Y341589D01*
X749840Y342006D01*
X749632Y342464D01*
X749299Y343089D01*
X750965D01*
G01X762992Y308568D02*
Y311068D01*
X761951D01*
X761617Y310943D01*
X761409Y310776D01*
X761326Y310443D01*
X761409Y310110D01*
X761659Y309901D01*
X761951Y309776D01*
X762992D01*
G01X761951D02*
X761326Y308568D01*
G01X759851Y309610D02*
X759559Y309901D01*
X759309Y310068D01*
X758976Y310151D01*
X758684Y310068D01*
X758476Y309901D01*
X758309Y309651D01*
X758267Y309360D01*
X758309Y309110D01*
X758476Y308860D01*
X758726Y308651D01*
X759017Y308568D01*
X759351Y308651D01*
X759642Y308901D01*
X759809Y309276D01*
X759851Y309693D01*
X759767Y310235D01*
X759642Y310526D01*
X759434Y310818D01*
X759142Y311026D01*
X758851Y311068D01*
X758559Y310985D01*
X758351Y310776D01*
G01X756792Y308568D02*
Y311068D01*
X755792D01*
X755459Y310943D01*
X755209Y310651D01*
X755126Y310318D01*
X755209Y309985D01*
X755417Y309735D01*
X755792Y309610D01*
X756792D01*
G01X752859Y308568D02*
Y311068D01*
X753359Y310568D01*
G01Y308568D02*
X752359D01*
G01X749759Y311068D02*
X750092Y310985D01*
X750342Y310776D01*
X750509Y310526D01*
X750634Y310193D01*
X750676Y309818D01*
X750634Y309443D01*
X750509Y309110D01*
X750342Y308860D01*
X750092Y308651D01*
X749759Y308568D01*
X749426Y308651D01*
X749176Y308860D01*
X749009Y309110D01*
X748884Y309443D01*
X748842Y309818D01*
X748884Y310193D01*
X749009Y310526D01*
X749176Y310776D01*
X749426Y310985D01*
X749759Y311068D01*
G01X730250Y312667D02*
X732750D01*
Y313708D01*
X732625Y314042D01*
X732458Y314250D01*
X732125Y314333D01*
X731792Y314250D01*
X731583Y314000D01*
X731458Y313708D01*
Y312667D01*
G01Y313708D02*
X730250Y314333D01*
G01X731292Y315808D02*
X731583Y316100D01*
X731750Y316350D01*
X731833Y316683D01*
X731750Y316975D01*
X731583Y317183D01*
X731333Y317350D01*
X731042Y317392D01*
X730792Y317350D01*
X730542Y317183D01*
X730333Y316933D01*
X730250Y316642D01*
X730333Y316308D01*
X730583Y316017D01*
X730958Y315850D01*
X731375Y315808D01*
X731917Y315892D01*
X732208Y316017D01*
X732500Y316225D01*
X732708Y316517D01*
X732750Y316808D01*
X732667Y317100D01*
X732458Y317308D01*
G01X730250Y318867D02*
X732750D01*
Y319867D01*
X732625Y320200D01*
X732333Y320450D01*
X732000Y320533D01*
X731667Y320450D01*
X731417Y320242D01*
X731292Y319867D01*
Y318867D01*
G01X730250Y323300D02*
X732750D01*
X730958Y321758D01*
Y323842D01*
G01X730250Y325900D02*
X730292Y326192D01*
X730417Y326525D01*
X730625Y326733D01*
X730917Y326817D01*
X731208Y326733D01*
X731458Y326483D01*
X731583Y326108D01*
Y325692D01*
X731667Y325442D01*
X731875Y325233D01*
X732167Y325150D01*
X732458Y325275D01*
X732667Y325567D01*
X732750Y325900D01*
X732667Y326233D01*
X732458Y326525D01*
X732167Y326650D01*
X731875Y326567D01*
X731667Y326358D01*
X731583Y326108D01*
Y325692D01*
X731458Y325317D01*
X731208Y325067D01*
X730917Y324983D01*
X730625Y325067D01*
X730417Y325275D01*
X730292Y325608D01*
X730250Y325900D01*
G01X761247Y284853D02*
X761497Y284978D01*
X761789Y285061D01*
X762122D01*
X762497Y284936D01*
X762789Y284728D01*
X762997Y284478D01*
X763164Y284061D01*
X763206Y283686D01*
X763122Y283311D01*
X762997Y283061D01*
X762747Y282811D01*
X762456Y282644D01*
X762164Y282561D01*
X761872D01*
X761581Y282644D01*
X761331Y282769D01*
X761122Y282936D01*
G01X759064Y285061D02*
Y282561D01*
G01X760022Y285061D02*
X758106D01*
G01X756881Y283061D02*
X756631Y282769D01*
X756297Y282603D01*
X755922Y282561D01*
X755589Y282603D01*
X755256Y282811D01*
X755047Y283061D01*
X755006Y283311D01*
X755089Y283603D01*
X755381Y283811D01*
X755672Y283894D01*
X756047D01*
G01X755672D02*
X755422Y284019D01*
X755214Y284228D01*
X755131Y284478D01*
X755214Y284728D01*
X755422Y284936D01*
X755797Y285061D01*
X756172Y285019D01*
X756547Y284853D01*
G01X752947Y282561D02*
X752864Y283103D01*
X752739Y283561D01*
X752572Y283978D01*
X752364Y284436D01*
X752031Y285061D01*
X753697D01*
G01X762070Y320091D02*
X762320Y320216D01*
X762612Y320299D01*
X762945D01*
X763320Y320174D01*
X763612Y319966D01*
X763820Y319716D01*
X763987Y319299D01*
X764029Y318924D01*
X763945Y318549D01*
X763820Y318299D01*
X763570Y318049D01*
X763279Y317882D01*
X762987Y317799D01*
X762695D01*
X762404Y317882D01*
X762154Y318007D01*
X761945Y318174D01*
G01X759887Y320299D02*
Y317799D01*
G01X760845Y320299D02*
X758929D01*
G01X756287Y317799D02*
Y320299D01*
X757829Y318507D01*
X755745D01*
G01X754479Y319882D02*
X754229Y320132D01*
X753937Y320257D01*
X753604Y320299D01*
X753187Y320216D01*
X752895Y320007D01*
X752812Y319757D01*
X752854Y319507D01*
X753020Y319299D01*
X753854Y318882D01*
X754229Y318591D01*
X754479Y318174D01*
X754562Y317799D01*
X752812D01*
G01X767633Y306659D02*
X767883Y306784D01*
X768175Y306867D01*
X768508D01*
X768883Y306742D01*
X769175Y306534D01*
X769383Y306284D01*
X769550Y305867D01*
X769592Y305492D01*
X769508Y305117D01*
X769383Y304867D01*
X769133Y304617D01*
X768842Y304450D01*
X768550Y304367D01*
X768258D01*
X767967Y304450D01*
X767717Y304575D01*
X767508Y304742D01*
G01X764950Y304367D02*
Y306867D01*
X766492Y305075D01*
X764408D01*
G01X763267Y304367D02*
Y306867D01*
X762433D01*
X762100Y306742D01*
X761850Y306575D01*
X761642Y306325D01*
X761475Y306034D01*
X761433Y305617D01*
X761475Y305200D01*
X761642Y304909D01*
X761850Y304659D01*
X762100Y304492D01*
X762433Y304367D01*
X763267D01*
G01X760042Y305409D02*
X759750Y305700D01*
X759500Y305867D01*
X759167Y305950D01*
X758875Y305867D01*
X758667Y305700D01*
X758500Y305450D01*
X758458Y305159D01*
X758500Y304909D01*
X758667Y304659D01*
X758917Y304450D01*
X759208Y304367D01*
X759542Y304450D01*
X759833Y304700D01*
X760000Y305075D01*
X760042Y305492D01*
X759958Y306034D01*
X759833Y306325D01*
X759625Y306617D01*
X759333Y306825D01*
X759042Y306867D01*
X758750Y306784D01*
X758542Y306575D01*
G01X767083Y337959D02*
X767333Y338084D01*
X767625Y338167D01*
X767958D01*
X768333Y338042D01*
X768625Y337834D01*
X768833Y337584D01*
X769000Y337167D01*
X769042Y336792D01*
X768958Y336417D01*
X768833Y336167D01*
X768583Y335917D01*
X768292Y335750D01*
X768000Y335667D01*
X767708D01*
X767417Y335750D01*
X767167Y335875D01*
X766958Y336042D01*
G01X764400Y335667D02*
Y338167D01*
X765942Y336375D01*
X763858D01*
G01X760883Y337959D02*
X761133Y338084D01*
X761425Y338167D01*
X761758D01*
X762133Y338042D01*
X762425Y337834D01*
X762633Y337584D01*
X762800Y337167D01*
X762842Y336792D01*
X762758Y336417D01*
X762633Y336167D01*
X762383Y335917D01*
X762092Y335750D01*
X761800Y335667D01*
X761508D01*
X761217Y335750D01*
X760967Y335875D01*
X760758Y336042D01*
G01X758700Y335667D02*
Y338167D01*
X759200Y337667D01*
G01Y335667D02*
X758200D01*
G01X755100D02*
Y338167D01*
X756642Y336375D01*
X754558D01*
G01X786268Y402167D02*
X786518Y402292D01*
X786810Y402375D01*
X787143D01*
X787518Y402250D01*
X787810Y402042D01*
X788018Y401792D01*
X788185Y401375D01*
X788227Y401000D01*
X788143Y400625D01*
X788018Y400375D01*
X787768Y400125D01*
X787477Y399958D01*
X787185Y399875D01*
X786893D01*
X786602Y399958D01*
X786352Y400083D01*
X786143Y400250D01*
G01X784877Y400917D02*
X784585Y401208D01*
X784335Y401375D01*
X784002Y401458D01*
X783710Y401375D01*
X783502Y401208D01*
X783335Y400958D01*
X783293Y400667D01*
X783335Y400417D01*
X783502Y400167D01*
X783752Y399958D01*
X784043Y399875D01*
X784377Y399958D01*
X784668Y400208D01*
X784835Y400583D01*
X784877Y401000D01*
X784793Y401542D01*
X784668Y401833D01*
X784460Y402125D01*
X784168Y402333D01*
X783877Y402375D01*
X783585Y402292D01*
X783377Y402083D01*
G01X781943Y399875D02*
Y402375D01*
X780027Y399875D01*
Y402375D01*
G01X778677Y400917D02*
X778385Y401208D01*
X778135Y401375D01*
X777802Y401458D01*
X777510Y401375D01*
X777302Y401208D01*
X777135Y400958D01*
X777093Y400667D01*
X777135Y400417D01*
X777302Y400167D01*
X777552Y399958D01*
X777843Y399875D01*
X778177Y399958D01*
X778468Y400208D01*
X778635Y400583D01*
X778677Y401000D01*
X778593Y401542D01*
X778468Y401833D01*
X778260Y402125D01*
X777968Y402333D01*
X777677Y402375D01*
X777385Y402292D01*
X777177Y402083D01*
G01X763006Y357000D02*
X763256Y357125D01*
X763548Y357208D01*
X763881D01*
X764256Y357083D01*
X764548Y356875D01*
X764756Y356625D01*
X764923Y356208D01*
X764965Y355833D01*
X764881Y355458D01*
X764756Y355208D01*
X764506Y354958D01*
X764215Y354791D01*
X763923Y354708D01*
X763631D01*
X763340Y354791D01*
X763090Y354916D01*
X762881Y355083D01*
G01X761615Y355750D02*
X761323Y356041D01*
X761073Y356208D01*
X760740Y356291D01*
X760448Y356208D01*
X760240Y356041D01*
X760073Y355791D01*
X760031Y355500D01*
X760073Y355250D01*
X760240Y355000D01*
X760490Y354791D01*
X760781Y354708D01*
X761115Y354791D01*
X761406Y355041D01*
X761573Y355416D01*
X761615Y355833D01*
X761531Y356375D01*
X761406Y356666D01*
X761198Y356958D01*
X760906Y357166D01*
X760615Y357208D01*
X760323Y357125D01*
X760115Y356916D01*
G01X758681Y354708D02*
Y357208D01*
X756765Y354708D01*
Y357208D01*
G01X754623Y354708D02*
Y357208D01*
X755123Y356708D01*
G01Y354708D02*
X754123D01*
G01X751523Y357208D02*
X751856Y357125D01*
X752106Y356916D01*
X752273Y356666D01*
X752398Y356333D01*
X752440Y355958D01*
X752398Y355583D01*
X752273Y355250D01*
X752106Y355000D01*
X751856Y354791D01*
X751523Y354708D01*
X751190Y354791D01*
X750940Y355000D01*
X750773Y355250D01*
X750648Y355583D01*
X750606Y355958D01*
X750648Y356333D01*
X750773Y356666D01*
X750940Y356916D01*
X751190Y357125D01*
X751523Y357208D01*
G01X771540Y361001D02*
X771790Y361126D01*
X772082Y361209D01*
X772415D01*
X772790Y361084D01*
X773082Y360876D01*
X773290Y360626D01*
X773457Y360209D01*
X773499Y359834D01*
X773415Y359459D01*
X773290Y359209D01*
X773040Y358959D01*
X772749Y358792D01*
X772457Y358709D01*
X772165D01*
X771874Y358792D01*
X771624Y358917D01*
X771415Y359084D01*
G01X770149Y359751D02*
X769857Y360042D01*
X769607Y360209D01*
X769274Y360292D01*
X768982Y360209D01*
X768774Y360042D01*
X768607Y359792D01*
X768565Y359501D01*
X768607Y359251D01*
X768774Y359001D01*
X769024Y358792D01*
X769315Y358709D01*
X769649Y358792D01*
X769940Y359042D01*
X770107Y359417D01*
X770149Y359834D01*
X770065Y360376D01*
X769940Y360667D01*
X769732Y360959D01*
X769440Y361167D01*
X769149Y361209D01*
X768857Y361126D01*
X768649Y360917D01*
G01X767215Y358709D02*
Y361209D01*
X765299Y358709D01*
Y361209D01*
G01X763157Y358709D02*
X762865Y358751D01*
X762532Y358876D01*
X762324Y359084D01*
X762240Y359376D01*
X762324Y359667D01*
X762574Y359917D01*
X762949Y360042D01*
X763365D01*
X763615Y360126D01*
X763824Y360334D01*
X763907Y360626D01*
X763782Y360917D01*
X763490Y361126D01*
X763157Y361209D01*
X762824Y361126D01*
X762532Y360917D01*
X762407Y360626D01*
X762490Y360334D01*
X762699Y360126D01*
X762949Y360042D01*
X763365D01*
X763740Y359917D01*
X763990Y359667D01*
X764074Y359376D01*
X763990Y359084D01*
X763782Y358876D01*
X763449Y358751D01*
X763157Y358709D01*
G01X763006Y353000D02*
X763256Y353125D01*
X763548Y353208D01*
X763881D01*
X764256Y353083D01*
X764548Y352875D01*
X764756Y352625D01*
X764923Y352208D01*
X764965Y351833D01*
X764881Y351458D01*
X764756Y351208D01*
X764506Y350958D01*
X764215Y350791D01*
X763923Y350708D01*
X763631D01*
X763340Y350791D01*
X763090Y350916D01*
X762881Y351083D01*
G01X761615Y351750D02*
X761323Y352041D01*
X761073Y352208D01*
X760740Y352291D01*
X760448Y352208D01*
X760240Y352041D01*
X760073Y351791D01*
X760031Y351500D01*
X760073Y351250D01*
X760240Y351000D01*
X760490Y350791D01*
X760781Y350708D01*
X761115Y350791D01*
X761406Y351041D01*
X761573Y351416D01*
X761615Y351833D01*
X761531Y352375D01*
X761406Y352666D01*
X761198Y352958D01*
X760906Y353166D01*
X760615Y353208D01*
X760323Y353125D01*
X760115Y352916D01*
G01X758681Y350708D02*
Y353208D01*
X756765Y350708D01*
Y353208D01*
G01X754623Y350708D02*
Y353208D01*
X755123Y352708D01*
G01Y350708D02*
X754123D01*
G01X751523D02*
Y353208D01*
X752023Y352708D01*
G01Y350708D02*
X751023D01*
G01X786268Y406167D02*
X786518Y406292D01*
X786810Y406375D01*
X787143D01*
X787518Y406250D01*
X787810Y406042D01*
X788018Y405792D01*
X788185Y405375D01*
X788227Y405000D01*
X788143Y404625D01*
X788018Y404375D01*
X787768Y404125D01*
X787477Y403958D01*
X787185Y403875D01*
X786893D01*
X786602Y403958D01*
X786352Y404083D01*
X786143Y404250D01*
G01X784877Y404917D02*
X784585Y405208D01*
X784335Y405375D01*
X784002Y405458D01*
X783710Y405375D01*
X783502Y405208D01*
X783335Y404958D01*
X783293Y404667D01*
X783335Y404417D01*
X783502Y404167D01*
X783752Y403958D01*
X784043Y403875D01*
X784377Y403958D01*
X784668Y404208D01*
X784835Y404583D01*
X784877Y405000D01*
X784793Y405542D01*
X784668Y405833D01*
X784460Y406125D01*
X784168Y406333D01*
X783877Y406375D01*
X783585Y406292D01*
X783377Y406083D01*
G01X781943Y403875D02*
Y406375D01*
X780027Y403875D01*
Y406375D01*
G01X778802Y404375D02*
X778552Y404083D01*
X778218Y403917D01*
X777843Y403875D01*
X777510Y403917D01*
X777177Y404125D01*
X776968Y404375D01*
X776927Y404625D01*
X777010Y404917D01*
X777302Y405125D01*
X777593Y405208D01*
X777968D01*
G01X777593D02*
X777343Y405333D01*
X777135Y405542D01*
X777052Y405792D01*
X777135Y406042D01*
X777343Y406250D01*
X777718Y406375D01*
X778093Y406333D01*
X778468Y406167D01*
G01X769440Y369641D02*
Y372141D01*
X768399D01*
X768065Y372016D01*
X767857Y371849D01*
X767774Y371516D01*
X767857Y371183D01*
X768107Y370974D01*
X768399Y370849D01*
X769440D01*
G01X768399D02*
X767774Y369641D01*
G01X766299Y370683D02*
X766007Y370974D01*
X765757Y371141D01*
X765424Y371224D01*
X765132Y371141D01*
X764924Y370974D01*
X764757Y370724D01*
X764715Y370433D01*
X764757Y370183D01*
X764924Y369933D01*
X765174Y369724D01*
X765465Y369641D01*
X765799Y369724D01*
X766090Y369974D01*
X766257Y370349D01*
X766299Y370766D01*
X766215Y371308D01*
X766090Y371599D01*
X765882Y371891D01*
X765590Y372099D01*
X765299Y372141D01*
X765007Y372058D01*
X764799Y371849D01*
G01X763365Y369641D02*
Y372141D01*
X761449Y369641D01*
Y372141D01*
G01X760224Y370141D02*
X759974Y369849D01*
X759640Y369683D01*
X759265Y369641D01*
X758932Y369683D01*
X758599Y369891D01*
X758390Y370141D01*
X758349Y370391D01*
X758432Y370683D01*
X758724Y370891D01*
X759015Y370974D01*
X759390D01*
G01X759015D02*
X758765Y371099D01*
X758557Y371308D01*
X758474Y371558D01*
X758557Y371808D01*
X758765Y372016D01*
X759140Y372141D01*
X759515Y372099D01*
X759890Y371933D01*
G01X757798Y390363D02*
X760298D01*
Y391404D01*
X760173Y391738D01*
X760006Y391946D01*
X759673Y392029D01*
X759340Y391946D01*
X759131Y391696D01*
X759006Y391404D01*
Y390363D01*
G01Y391404D02*
X757798Y392029D01*
G01X758840Y393504D02*
X759131Y393796D01*
X759298Y394046D01*
X759381Y394379D01*
X759298Y394671D01*
X759131Y394879D01*
X758881Y395046D01*
X758590Y395088D01*
X758340Y395046D01*
X758090Y394879D01*
X757881Y394629D01*
X757798Y394338D01*
X757881Y394004D01*
X758131Y393713D01*
X758506Y393546D01*
X758923Y393504D01*
X759465Y393588D01*
X759756Y393713D01*
X760048Y393921D01*
X760256Y394213D01*
X760298Y394504D01*
X760215Y394796D01*
X760006Y395004D01*
G01X757798Y396438D02*
X760298D01*
X757798Y398354D01*
X760298D01*
G01X757798Y400496D02*
X760298D01*
X759798Y399996D01*
G01X757798D02*
Y400996D01*
G01X758173Y402679D02*
X757965Y402929D01*
X757840Y403221D01*
X757798Y403596D01*
X757881Y403971D01*
X758048Y404263D01*
X758340Y404471D01*
X758673Y404513D01*
X759006Y404429D01*
X759215Y404221D01*
X759381Y403929D01*
X759423Y403638D01*
X759381Y403346D01*
X759215Y402971D01*
X760298Y403096D01*
Y404221D01*
G01X753798Y390363D02*
X756298D01*
Y391404D01*
X756173Y391738D01*
X756006Y391946D01*
X755673Y392029D01*
X755340Y391946D01*
X755131Y391696D01*
X755006Y391404D01*
Y390363D01*
G01Y391404D02*
X753798Y392029D01*
G01X754840Y393504D02*
X755131Y393796D01*
X755298Y394046D01*
X755381Y394379D01*
X755298Y394671D01*
X755131Y394879D01*
X754881Y395046D01*
X754590Y395088D01*
X754340Y395046D01*
X754090Y394879D01*
X753881Y394629D01*
X753798Y394338D01*
X753881Y394004D01*
X754131Y393713D01*
X754506Y393546D01*
X754923Y393504D01*
X755465Y393588D01*
X755756Y393713D01*
X756048Y393921D01*
X756256Y394213D01*
X756298Y394504D01*
X756215Y394796D01*
X756006Y395004D01*
G01X753798Y396438D02*
X756298D01*
X753798Y398354D01*
X756298D01*
G01X753798Y400496D02*
X756298D01*
X755798Y399996D01*
G01X753798D02*
Y400996D01*
G01X754298Y402679D02*
X754006Y402929D01*
X753840Y403263D01*
X753798Y403638D01*
X753840Y403971D01*
X754048Y404304D01*
X754298Y404513D01*
X754548Y404554D01*
X754840Y404471D01*
X755048Y404179D01*
X755131Y403888D01*
Y403513D01*
G01Y403888D02*
X755256Y404138D01*
X755465Y404346D01*
X755715Y404429D01*
X755965Y404346D01*
X756173Y404138D01*
X756298Y403763D01*
X756256Y403388D01*
X756090Y403013D01*
G01X749798Y390363D02*
X752298D01*
Y391404D01*
X752173Y391738D01*
X752006Y391946D01*
X751673Y392029D01*
X751340Y391946D01*
X751131Y391696D01*
X751006Y391404D01*
Y390363D01*
G01Y391404D02*
X749798Y392029D01*
G01X750840Y393504D02*
X751131Y393796D01*
X751298Y394046D01*
X751381Y394379D01*
X751298Y394671D01*
X751131Y394879D01*
X750881Y395046D01*
X750590Y395088D01*
X750340Y395046D01*
X750090Y394879D01*
X749881Y394629D01*
X749798Y394338D01*
X749881Y394004D01*
X750131Y393713D01*
X750506Y393546D01*
X750923Y393504D01*
X751465Y393588D01*
X751756Y393713D01*
X752048Y393921D01*
X752256Y394213D01*
X752298Y394504D01*
X752215Y394796D01*
X752006Y395004D01*
G01X749798Y396438D02*
X752298D01*
X749798Y398354D01*
X752298D01*
G01X749798Y400496D02*
X752298D01*
X751798Y399996D01*
G01X749798D02*
Y400996D01*
G01Y404096D02*
X752298D01*
X750506Y402554D01*
Y404638D01*
G01X760427Y378223D02*
X760677Y378348D01*
X760969Y378431D01*
X761302D01*
X761677Y378306D01*
X761969Y378098D01*
X762177Y377848D01*
X762344Y377431D01*
X762386Y377056D01*
X762302Y376681D01*
X762177Y376431D01*
X761927Y376181D01*
X761636Y376014D01*
X761344Y375931D01*
X761052D01*
X760761Y376014D01*
X760511Y376139D01*
X760302Y376306D01*
G01X758244Y378431D02*
Y375931D01*
G01X759202Y378431D02*
X757286D01*
G01X756061Y376306D02*
X755811Y376098D01*
X755519Y375973D01*
X755144Y375931D01*
X754769Y376014D01*
X754477Y376181D01*
X754269Y376473D01*
X754227Y376806D01*
X754311Y377139D01*
X754519Y377348D01*
X754811Y377514D01*
X755102Y377556D01*
X755394Y377514D01*
X755769Y377348D01*
X755644Y378431D01*
X754519D01*
G01X752044Y375931D02*
X751752Y375973D01*
X751419Y376098D01*
X751211Y376306D01*
X751127Y376598D01*
X751211Y376889D01*
X751461Y377139D01*
X751836Y377264D01*
X752252D01*
X752502Y377348D01*
X752711Y377556D01*
X752794Y377848D01*
X752669Y378139D01*
X752377Y378348D01*
X752044Y378431D01*
X751711Y378348D01*
X751419Y378139D01*
X751294Y377848D01*
X751377Y377556D01*
X751586Y377348D01*
X751836Y377264D01*
X752252D01*
X752627Y377139D01*
X752877Y376889D01*
X752961Y376598D01*
X752877Y376306D01*
X752669Y376098D01*
X752336Y375973D01*
X752044Y375931D01*
G01X761633Y349192D02*
X761883Y349317D01*
X762175Y349400D01*
X762508D01*
X762883Y349275D01*
X763175Y349067D01*
X763383Y348817D01*
X763550Y348400D01*
X763592Y348025D01*
X763508Y347650D01*
X763383Y347400D01*
X763133Y347150D01*
X762842Y346983D01*
X762550Y346900D01*
X762258D01*
X761967Y346983D01*
X761717Y347108D01*
X761508Y347275D01*
G01X759450Y349400D02*
Y346900D01*
G01X760408Y349400D02*
X758492D01*
G01X757267Y347400D02*
X757017Y347108D01*
X756683Y346942D01*
X756308Y346900D01*
X755975Y346942D01*
X755642Y347150D01*
X755433Y347400D01*
X755392Y347650D01*
X755475Y347942D01*
X755767Y348150D01*
X756058Y348233D01*
X756433D01*
G01X756058D02*
X755808Y348358D01*
X755600Y348567D01*
X755517Y348817D01*
X755600Y349067D01*
X755808Y349275D01*
X756183Y349400D01*
X756558Y349358D01*
X756933Y349192D01*
G01X752750Y346900D02*
Y349400D01*
X754292Y347608D01*
X752208D01*
G01X795703Y369832D02*
X795953Y369957D01*
X796245Y370040D01*
X796578D01*
X796953Y369915D01*
X797245Y369707D01*
X797453Y369457D01*
X797620Y369040D01*
X797662Y368665D01*
X797578Y368290D01*
X797453Y368040D01*
X797203Y367790D01*
X796912Y367623D01*
X796620Y367540D01*
X796328D01*
X796037Y367623D01*
X795787Y367748D01*
X795578Y367915D01*
G01X793020Y367540D02*
Y370040D01*
X794562Y368248D01*
X792478D01*
G01X789503Y369832D02*
X789753Y369957D01*
X790045Y370040D01*
X790378D01*
X790753Y369915D01*
X791045Y369707D01*
X791253Y369457D01*
X791420Y369040D01*
X791462Y368665D01*
X791378Y368290D01*
X791253Y368040D01*
X791003Y367790D01*
X790712Y367623D01*
X790420Y367540D01*
X790128D01*
X789837Y367623D01*
X789587Y367748D01*
X789378Y367915D01*
G01X786820Y367540D02*
Y370040D01*
X788362Y368248D01*
X786278D01*
G01X792500Y420000D02*
Y428641D01*
X785186D01*
Y500544D01*
X861111D01*
Y483043D01*
X886360D01*
Y439500D01*
X966999D01*
G01X786268Y410167D02*
X786518Y410292D01*
X786810Y410375D01*
X787143D01*
X787518Y410250D01*
X787810Y410042D01*
X788018Y409792D01*
X788185Y409375D01*
X788227Y409000D01*
X788143Y408625D01*
X788018Y408375D01*
X787768Y408125D01*
X787477Y407958D01*
X787185Y407875D01*
X786893D01*
X786602Y407958D01*
X786352Y408083D01*
X786143Y408250D01*
G01X784877Y408917D02*
X784585Y409208D01*
X784335Y409375D01*
X784002Y409458D01*
X783710Y409375D01*
X783502Y409208D01*
X783335Y408958D01*
X783293Y408667D01*
X783335Y408417D01*
X783502Y408167D01*
X783752Y407958D01*
X784043Y407875D01*
X784377Y407958D01*
X784668Y408208D01*
X784835Y408583D01*
X784877Y409000D01*
X784793Y409542D01*
X784668Y409833D01*
X784460Y410125D01*
X784168Y410333D01*
X783877Y410375D01*
X783585Y410292D01*
X783377Y410083D01*
G01X781943Y407875D02*
Y410375D01*
X780027Y407875D01*
Y410375D01*
G01X778677Y409958D02*
X778427Y410208D01*
X778135Y410333D01*
X777802Y410375D01*
X777385Y410292D01*
X777093Y410083D01*
X777010Y409833D01*
X777052Y409583D01*
X777218Y409375D01*
X778052Y408958D01*
X778427Y408667D01*
X778677Y408250D01*
X778760Y407875D01*
X777010D01*
G01X800947Y430181D02*
Y432681D01*
X799906D01*
X799572Y432556D01*
X799364Y432389D01*
X799281Y432056D01*
X799364Y431723D01*
X799614Y431514D01*
X799906Y431389D01*
X800947D01*
G01X799906D02*
X799281Y430181D01*
G01X797014D02*
Y432681D01*
X797514Y432181D01*
G01Y430181D02*
X796514D01*
G01X794831Y432681D02*
Y430889D01*
X794664Y430514D01*
X794331Y430264D01*
X793914Y430181D01*
X793497Y430264D01*
X793164Y430514D01*
X792997Y430889D01*
Y432681D01*
G01X790314Y430181D02*
Y432681D01*
X791856Y430889D01*
X789772D01*
G01X787214Y430181D02*
Y432681D01*
X788756Y430889D01*
X786672D01*
G01X732132Y492118D02*
X734632D01*
Y493159D01*
X734507Y493493D01*
X734340Y493701D01*
X734007Y493784D01*
X733674Y493701D01*
X733465Y493451D01*
X733340Y493159D01*
Y492118D01*
G01Y493159D02*
X732132Y493784D01*
G01Y496051D02*
X734632D01*
X734132Y495551D01*
G01X732132D02*
Y496551D01*
G01X734215Y498359D02*
X734465Y498609D01*
X734590Y498901D01*
X734632Y499234D01*
X734549Y499651D01*
X734340Y499943D01*
X734090Y500026D01*
X733840Y499984D01*
X733632Y499818D01*
X733215Y498984D01*
X732924Y498609D01*
X732507Y498359D01*
X732132Y498276D01*
Y500026D01*
G01X734632Y501001D02*
X732132Y501584D01*
X734632Y502251D01*
X732132Y502918D01*
X734632Y503501D01*
G01X732424Y504643D02*
X732215Y504934D01*
X732132Y505268D01*
X732215Y505601D01*
X732465Y505893D01*
X732840Y506101D01*
X733215Y506184D01*
X733674D01*
X734049Y506101D01*
X734382Y505893D01*
X734549Y505643D01*
X734632Y505351D01*
X734549Y505018D01*
X734382Y504768D01*
X734132Y504601D01*
X733799Y504518D01*
X733507Y504601D01*
X733215Y504809D01*
X733049Y505059D01*
X733007Y505351D01*
X733090Y505684D01*
X733299Y505934D01*
X733674Y506184D01*
G01X769852Y497501D02*
Y500601D01*
X770312Y499981D01*
G01Y497501D02*
X769392D01*
G01X766292D02*
Y500601D01*
X767710Y498379D01*
X765794D01*
G01X764495Y497966D02*
X764265Y497708D01*
X763997Y497553D01*
X763652Y497501D01*
X763307Y497604D01*
X763039Y497811D01*
X762847Y498173D01*
X762809Y498586D01*
X762885Y498999D01*
X763077Y499258D01*
X763345Y499464D01*
X763614Y499516D01*
X763882Y499464D01*
X764227Y499258D01*
X764112Y500601D01*
X763077D01*
G01X733350Y512217D02*
X733100Y512425D01*
X732933Y512675D01*
X732850Y512967D01*
X732933Y513300D01*
X733100Y513550D01*
X733350Y513800D01*
X733683Y513883D01*
X735350D01*
G01X733892Y515358D02*
X734183Y515650D01*
X734350Y515900D01*
X734433Y516233D01*
X734350Y516525D01*
X734183Y516733D01*
X733933Y516900D01*
X733642Y516942D01*
X733392Y516900D01*
X733142Y516733D01*
X732933Y516483D01*
X732850Y516192D01*
X732933Y515858D01*
X733183Y515567D01*
X733558Y515400D01*
X733975Y515358D01*
X734517Y515442D01*
X734808Y515567D01*
X735100Y515775D01*
X735308Y516067D01*
X735350Y516358D01*
X735267Y516650D01*
X735058Y516858D01*
G01X732850Y518167D02*
X735350D01*
X733267Y519250D01*
X735350Y520333D01*
X732850D01*
G01Y522350D02*
X735350D01*
X734850Y521850D01*
G01X732850D02*
Y522850D01*
G01X760710Y526874D02*
X736320D01*
Y501284D01*
X760710D01*
G01X728392Y537117D02*
X728517Y536867D01*
X728600Y536575D01*
Y536242D01*
X728475Y535867D01*
X728267Y535575D01*
X728017Y535367D01*
X727600Y535200D01*
X727225Y535158D01*
X726850Y535242D01*
X726600Y535367D01*
X726350Y535617D01*
X726183Y535908D01*
X726100Y536200D01*
Y536492D01*
X726183Y536783D01*
X726308Y537033D01*
X726475Y537242D01*
G01X727142Y538508D02*
X727433Y538800D01*
X727600Y539050D01*
X727683Y539383D01*
X727600Y539675D01*
X727433Y539883D01*
X727183Y540050D01*
X726892Y540092D01*
X726642Y540050D01*
X726392Y539883D01*
X726183Y539633D01*
X726100Y539342D01*
X726183Y539008D01*
X726433Y538717D01*
X726808Y538550D01*
X727225Y538508D01*
X727767Y538592D01*
X728058Y538717D01*
X728350Y538925D01*
X728558Y539217D01*
X728600Y539508D01*
X728517Y539800D01*
X728308Y540008D01*
G01X728600Y541567D02*
X726100D01*
Y543233D01*
G01Y545500D02*
X728600D01*
X728100Y545000D01*
G01X726100D02*
Y546000D01*
G01X728600Y548600D02*
X728517Y548267D01*
X728308Y548017D01*
X728058Y547850D01*
X727725Y547725D01*
X727350Y547683D01*
X726975Y547725D01*
X726642Y547850D01*
X726392Y548017D01*
X726183Y548267D01*
X726100Y548600D01*
X726183Y548933D01*
X726392Y549183D01*
X726642Y549350D01*
X726975Y549475D01*
X727350Y549517D01*
X727725Y549475D01*
X728058Y549350D01*
X728308Y549183D01*
X728517Y548933D01*
X728600Y548600D01*
G01X788614Y566094D02*
Y568594D01*
X787573D01*
X787239Y568469D01*
X787031Y568302D01*
X786948Y567969D01*
X787031Y567636D01*
X787281Y567427D01*
X787573Y567302D01*
X788614D01*
G01X787573D02*
X786948Y566094D01*
G01X785473Y567136D02*
X785181Y567427D01*
X784931Y567594D01*
X784598Y567677D01*
X784306Y567594D01*
X784098Y567427D01*
X783931Y567177D01*
X783889Y566886D01*
X783931Y566636D01*
X784098Y566386D01*
X784348Y566177D01*
X784639Y566094D01*
X784973Y566177D01*
X785264Y566427D01*
X785431Y566802D01*
X785473Y567219D01*
X785389Y567761D01*
X785264Y568052D01*
X785056Y568344D01*
X784764Y568552D01*
X784473Y568594D01*
X784181Y568511D01*
X783973Y568302D01*
G01X782414Y568594D02*
Y566094D01*
X780748D01*
G01X778481D02*
Y568594D01*
X778981Y568094D01*
G01Y566094D02*
X777981D01*
G01X774881D02*
Y568594D01*
X776423Y566802D01*
X774339D01*
G01X779116Y575639D02*
X779366Y575764D01*
X779658Y575847D01*
X779991D01*
X780366Y575722D01*
X780658Y575514D01*
X780866Y575264D01*
X781033Y574847D01*
X781075Y574472D01*
X780991Y574097D01*
X780866Y573847D01*
X780616Y573597D01*
X780325Y573430D01*
X780033Y573347D01*
X779741D01*
X779450Y573430D01*
X779200Y573555D01*
X778991Y573722D01*
G01X777725Y574389D02*
X777433Y574680D01*
X777183Y574847D01*
X776850Y574930D01*
X776558Y574847D01*
X776350Y574680D01*
X776183Y574430D01*
X776141Y574139D01*
X776183Y573889D01*
X776350Y573639D01*
X776600Y573430D01*
X776891Y573347D01*
X777225Y573430D01*
X777516Y573680D01*
X777683Y574055D01*
X777725Y574472D01*
X777641Y575014D01*
X777516Y575305D01*
X777308Y575597D01*
X777016Y575805D01*
X776725Y575847D01*
X776433Y575764D01*
X776225Y575555D01*
G01X774666Y575847D02*
Y573347D01*
X773000D01*
G01X770816D02*
X770733Y573889D01*
X770608Y574347D01*
X770441Y574764D01*
X770233Y575222D01*
X769900Y575847D01*
X771566D01*
G01X793733Y538224D02*
X793983Y538349D01*
X794275Y538432D01*
X794608D01*
X794983Y538307D01*
X795275Y538099D01*
X795483Y537849D01*
X795650Y537432D01*
X795692Y537057D01*
X795608Y536682D01*
X795483Y536432D01*
X795233Y536182D01*
X794942Y536015D01*
X794650Y535932D01*
X794358D01*
X794067Y536015D01*
X793817Y536140D01*
X793608Y536307D01*
G01X792342Y536974D02*
X792050Y537265D01*
X791800Y537432D01*
X791467Y537515D01*
X791175Y537432D01*
X790967Y537265D01*
X790800Y537015D01*
X790758Y536724D01*
X790800Y536474D01*
X790967Y536224D01*
X791217Y536015D01*
X791508Y535932D01*
X791842Y536015D01*
X792133Y536265D01*
X792300Y536640D01*
X792342Y537057D01*
X792258Y537599D01*
X792133Y537890D01*
X791925Y538182D01*
X791633Y538390D01*
X791342Y538432D01*
X791050Y538349D01*
X790842Y538140D01*
G01X789533Y535932D02*
Y538432D01*
X788450Y536349D01*
X787367Y538432D01*
Y535932D01*
G01X786142Y538015D02*
X785892Y538265D01*
X785600Y538390D01*
X785267Y538432D01*
X784850Y538349D01*
X784558Y538140D01*
X784475Y537890D01*
X784517Y537640D01*
X784683Y537432D01*
X785517Y537015D01*
X785892Y536724D01*
X786142Y536307D01*
X786225Y535932D01*
X784475D01*
G01X732950Y584117D02*
X732700Y584325D01*
X732533Y584575D01*
X732450Y584867D01*
X732533Y585200D01*
X732700Y585450D01*
X732950Y585700D01*
X733283Y585783D01*
X734950D01*
G01X733492Y587258D02*
X733783Y587550D01*
X733950Y587800D01*
X734033Y588133D01*
X733950Y588425D01*
X733783Y588633D01*
X733533Y588800D01*
X733242Y588842D01*
X732992Y588800D01*
X732742Y588633D01*
X732533Y588383D01*
X732450Y588092D01*
X732533Y587758D01*
X732783Y587467D01*
X733158Y587300D01*
X733575Y587258D01*
X734117Y587342D01*
X734408Y587467D01*
X734700Y587675D01*
X734908Y587967D01*
X734950Y588258D01*
X734867Y588550D01*
X734658Y588758D01*
G01X734950Y590317D02*
X732450D01*
Y591983D01*
G01Y594250D02*
X734950D01*
X734450Y593750D01*
G01X732450D02*
Y594750D01*
G01X760710Y602474D02*
X736320D01*
Y576884D01*
X760710D01*
G01X775852Y535501D02*
Y538601D01*
X776312Y537981D01*
G01Y535501D02*
X775392D01*
G01X772292D02*
Y538601D01*
X773710Y536379D01*
X771794D01*
G01X770495Y535966D02*
X770265Y535708D01*
X769997Y535553D01*
X769652Y535501D01*
X769307Y535604D01*
X769039Y535811D01*
X768847Y536173D01*
X768809Y536586D01*
X768885Y536999D01*
X769077Y537258D01*
X769345Y537464D01*
X769614Y537516D01*
X769882Y537464D01*
X770227Y537258D01*
X770112Y538601D01*
X769077D01*
G01X733294Y557307D02*
X733044Y557515D01*
X732877Y557765D01*
X732794Y558057D01*
X732877Y558390D01*
X733044Y558640D01*
X733294Y558890D01*
X733627Y558973D01*
X735294D01*
G01X733836Y560448D02*
X734127Y560740D01*
X734294Y560990D01*
X734377Y561323D01*
X734294Y561615D01*
X734127Y561823D01*
X733877Y561990D01*
X733586Y562032D01*
X733336Y561990D01*
X733086Y561823D01*
X732877Y561573D01*
X732794Y561282D01*
X732877Y560948D01*
X733127Y560657D01*
X733502Y560490D01*
X733919Y560448D01*
X734461Y560532D01*
X734752Y560657D01*
X735044Y560865D01*
X735252Y561157D01*
X735294Y561448D01*
X735211Y561740D01*
X735002Y561948D01*
G01X735294Y563507D02*
X732794D01*
Y565173D01*
G01X734877Y566648D02*
X735127Y566898D01*
X735252Y567190D01*
X735294Y567523D01*
X735211Y567940D01*
X735002Y568232D01*
X734752Y568315D01*
X734502Y568273D01*
X734294Y568107D01*
X733877Y567273D01*
X733586Y566898D01*
X733169Y566648D01*
X732794Y566565D01*
Y568315D01*
G01X760710Y564674D02*
X736320D01*
Y539084D01*
X760710D01*
G01X773483Y616500D02*
Y619000D01*
X772442D01*
X772108Y618875D01*
X771900Y618708D01*
X771817Y618375D01*
X771900Y618042D01*
X772150Y617833D01*
X772442Y617708D01*
X773483D01*
G01X772442D02*
X771817Y616500D01*
G01X770342Y617542D02*
X770050Y617833D01*
X769800Y618000D01*
X769467Y618083D01*
X769175Y618000D01*
X768967Y617833D01*
X768800Y617583D01*
X768758Y617292D01*
X768800Y617042D01*
X768967Y616792D01*
X769217Y616583D01*
X769508Y616500D01*
X769842Y616583D01*
X770133Y616833D01*
X770300Y617208D01*
X770342Y617625D01*
X770258Y618167D01*
X770133Y618458D01*
X769925Y618750D01*
X769633Y618958D01*
X769342Y619000D01*
X769050Y618917D01*
X768842Y618708D01*
G01X767283Y619000D02*
Y616500D01*
X765617D01*
G01X764267Y617000D02*
X764017Y616708D01*
X763683Y616542D01*
X763308Y616500D01*
X762975Y616542D01*
X762642Y616750D01*
X762433Y617000D01*
X762392Y617250D01*
X762475Y617542D01*
X762767Y617750D01*
X763058Y617833D01*
X763433D01*
G01X763058D02*
X762808Y617958D01*
X762600Y618167D01*
X762517Y618417D01*
X762600Y618667D01*
X762808Y618875D01*
X763183Y619000D01*
X763558Y618958D01*
X763933Y618792D01*
G01X786683Y616500D02*
Y619000D01*
X785642D01*
X785308Y618875D01*
X785100Y618708D01*
X785017Y618375D01*
X785100Y618042D01*
X785350Y617833D01*
X785642Y617708D01*
X786683D01*
G01X785642D02*
X785017Y616500D01*
G01X783542Y617542D02*
X783250Y617833D01*
X783000Y618000D01*
X782667Y618083D01*
X782375Y618000D01*
X782167Y617833D01*
X782000Y617583D01*
X781958Y617292D01*
X782000Y617042D01*
X782167Y616792D01*
X782417Y616583D01*
X782708Y616500D01*
X783042Y616583D01*
X783333Y616833D01*
X783500Y617208D01*
X783542Y617625D01*
X783458Y618167D01*
X783333Y618458D01*
X783125Y618750D01*
X782833Y618958D01*
X782542Y619000D01*
X782250Y618917D01*
X782042Y618708D01*
G01X780483Y619000D02*
Y616500D01*
X778817D01*
G01X777342Y618583D02*
X777092Y618833D01*
X776800Y618958D01*
X776467Y619000D01*
X776050Y618917D01*
X775758Y618708D01*
X775675Y618458D01*
X775717Y618208D01*
X775883Y618000D01*
X776717Y617583D01*
X777092Y617292D01*
X777342Y616875D01*
X777425Y616500D01*
X775675D01*
G01X729150Y597317D02*
X731650D01*
Y598358D01*
X731525Y598692D01*
X731358Y598900D01*
X731025Y598983D01*
X730692Y598900D01*
X730483Y598650D01*
X730358Y598358D01*
Y597317D01*
G01Y598358D02*
X729150Y598983D01*
G01X730192Y600458D02*
X730483Y600750D01*
X730650Y601000D01*
X730733Y601333D01*
X730650Y601625D01*
X730483Y601833D01*
X730233Y602000D01*
X729942Y602042D01*
X729692Y602000D01*
X729442Y601833D01*
X729233Y601583D01*
X729150Y601292D01*
X729233Y600958D01*
X729483Y600667D01*
X729858Y600500D01*
X730275Y600458D01*
X730817Y600542D01*
X731108Y600667D01*
X731400Y600875D01*
X731608Y601167D01*
X731650Y601458D01*
X731567Y601750D01*
X731358Y601958D01*
G01X731650Y603517D02*
X729150D01*
Y605183D01*
G01Y607950D02*
X731650D01*
X729858Y606408D01*
Y608492D01*
G01X758533Y618792D02*
X758783Y618917D01*
X759075Y619000D01*
X759408D01*
X759783Y618875D01*
X760075Y618667D01*
X760283Y618417D01*
X760450Y618000D01*
X760492Y617625D01*
X760408Y617250D01*
X760283Y617000D01*
X760033Y616750D01*
X759742Y616583D01*
X759450Y616500D01*
X759158D01*
X758867Y616583D01*
X758617Y616708D01*
X758408Y616875D01*
G01X757142Y617542D02*
X756850Y617833D01*
X756600Y618000D01*
X756267Y618083D01*
X755975Y618000D01*
X755767Y617833D01*
X755600Y617583D01*
X755558Y617292D01*
X755600Y617042D01*
X755767Y616792D01*
X756017Y616583D01*
X756308Y616500D01*
X756642Y616583D01*
X756933Y616833D01*
X757100Y617208D01*
X757142Y617625D01*
X757058Y618167D01*
X756933Y618458D01*
X756725Y618750D01*
X756433Y618958D01*
X756142Y619000D01*
X755850Y618917D01*
X755642Y618708D01*
G01X754083Y619000D02*
Y616500D01*
X752417D01*
G01X750942Y618583D02*
X750692Y618833D01*
X750400Y618958D01*
X750067Y619000D01*
X749650Y618917D01*
X749358Y618708D01*
X749275Y618458D01*
X749317Y618208D01*
X749483Y618000D01*
X750317Y617583D01*
X750692Y617292D01*
X750942Y616875D01*
X751025Y616500D01*
X749275D01*
G01X757600Y603967D02*
Y607067D01*
X758060Y606447D01*
G01Y603967D02*
X757140D01*
G01X754040D02*
Y607067D01*
X755458Y604845D01*
X753542D01*
G01X752243Y604432D02*
X752013Y604174D01*
X751745Y604019D01*
X751400Y603967D01*
X751055Y604070D01*
X750787Y604277D01*
X750595Y604639D01*
X750557Y605052D01*
X750633Y605465D01*
X750825Y605724D01*
X751093Y605930D01*
X751362Y605982D01*
X751630Y605930D01*
X751975Y605724D01*
X751860Y607067D01*
X750825D01*
G01X795313Y658474D02*
Y661474D01*
X794313D01*
X793913Y661324D01*
X793613Y661124D01*
X793363Y660824D01*
X793163Y660474D01*
X793113Y659974D01*
X793163Y659474D01*
X793363Y659124D01*
X793613Y658824D01*
X793913Y658624D01*
X794313Y658474D01*
X795313D01*
G01X791363Y659824D02*
X789763D01*
X789913Y660174D01*
X790163Y660374D01*
X790513Y660474D01*
X790863Y660424D01*
X791163Y660274D01*
X791363Y659924D01*
X791463Y659624D01*
Y659324D01*
X791363Y659024D01*
X791113Y658724D01*
X790813Y658524D01*
X790463Y658474D01*
X790113Y658574D01*
X789763Y658874D01*
G01X787013Y658474D02*
Y661474D01*
G01X783413D02*
Y658474D01*
G01X784113Y660474D02*
X782713D01*
G01X778913Y658474D02*
Y660474D01*
G01Y660124D02*
X779113Y660324D01*
X779413Y660424D01*
X779763Y660474D01*
X780113Y660374D01*
X780413Y660174D01*
X780613Y659874D01*
X780713Y659474D01*
X780613Y659074D01*
X780413Y658774D01*
X780113Y658574D01*
X779763Y658474D01*
X779413Y658524D01*
X779113Y658674D01*
X778913Y658874D01*
G01X777713Y657474D02*
X774713D01*
G01X773613Y661474D02*
Y658474D01*
X771613D01*
G01X769013D02*
Y661474D01*
X769613Y660874D01*
G01Y658474D02*
X768413D01*
G01X764813D02*
Y661474D01*
X766663Y659324D01*
X764163D01*
G01X763313Y657474D02*
X760313D01*
G01X758213Y658474D02*
Y661474D01*
X758813Y660874D01*
G01Y658474D02*
X757613D01*
G01X754613Y661474D02*
X755013Y661374D01*
X755313Y661124D01*
X755513Y660824D01*
X755663Y660424D01*
X755713Y659974D01*
X755663Y659524D01*
X755513Y659124D01*
X755313Y658824D01*
X755013Y658574D01*
X754613Y658474D01*
X754213Y658574D01*
X753913Y658824D01*
X753713Y659124D01*
X753563Y659524D01*
X753513Y659974D01*
X753563Y660424D01*
X753713Y660824D01*
X753913Y661124D01*
X754213Y661374D01*
X754613Y661474D01*
G01X751013Y660474D02*
Y658474D01*
G01Y661274D02*
X751113Y661324D01*
Y661424D01*
X751013Y661474D01*
X750913Y661424D01*
Y661324D01*
X751013Y661274D01*
G01X748263Y658474D02*
Y660474D01*
G01Y659974D02*
X748063Y660224D01*
X747763Y660424D01*
X747363Y660474D01*
X747013Y660424D01*
X746713Y660224D01*
X746563Y659874D01*
Y658474D01*
G01X743013Y660224D02*
X743363Y660424D01*
X743663Y660474D01*
X744063Y660374D01*
X744363Y660174D01*
X744563Y659824D01*
X744613Y659474D01*
X744563Y659124D01*
X744363Y658824D01*
X744063Y658574D01*
X743663Y658474D01*
X743313Y658574D01*
X743013Y658774D01*
G01X741063Y658474D02*
Y661474D01*
G01Y660024D02*
X740813Y660274D01*
X740563Y660424D01*
X740163Y660474D01*
X739863Y660424D01*
X739513Y660224D01*
X739363Y659924D01*
Y658474D01*
G01X802460Y33085D02*
X802710Y33210D01*
X803002Y33293D01*
X803335D01*
X803710Y33168D01*
X804002Y32960D01*
X804210Y32710D01*
X804377Y32293D01*
X804419Y31918D01*
X804335Y31543D01*
X804210Y31293D01*
X803960Y31043D01*
X803669Y30876D01*
X803377Y30793D01*
X803085D01*
X802794Y30876D01*
X802544Y31001D01*
X802335Y31168D01*
G01X801069Y31835D02*
X800777Y32126D01*
X800527Y32293D01*
X800194Y32376D01*
X799902Y32293D01*
X799694Y32126D01*
X799527Y31876D01*
X799485Y31585D01*
X799527Y31335D01*
X799694Y31085D01*
X799944Y30876D01*
X800235Y30793D01*
X800569Y30876D01*
X800860Y31126D01*
X801027Y31501D01*
X801069Y31918D01*
X800985Y32460D01*
X800860Y32751D01*
X800652Y33043D01*
X800360Y33251D01*
X800069Y33293D01*
X799777Y33210D01*
X799569Y33001D01*
G01X798094Y33293D02*
Y31501D01*
X797927Y31126D01*
X797594Y30876D01*
X797177Y30793D01*
X796760Y30876D01*
X796427Y31126D01*
X796260Y31501D01*
Y33293D01*
G01X794785Y31085D02*
X794494Y30876D01*
X794160Y30793D01*
X793827Y30876D01*
X793535Y31126D01*
X793327Y31501D01*
X793244Y31876D01*
Y32335D01*
X793327Y32710D01*
X793535Y33043D01*
X793785Y33210D01*
X794077Y33293D01*
X794410Y33210D01*
X794660Y33043D01*
X794827Y32793D01*
X794910Y32460D01*
X794827Y32168D01*
X794619Y31876D01*
X794369Y31710D01*
X794077Y31668D01*
X793744Y31751D01*
X793494Y31960D01*
X793244Y32335D01*
G01X801133Y70324D02*
X801383Y70449D01*
X801675Y70532D01*
X802008D01*
X802383Y70407D01*
X802675Y70199D01*
X802883Y69949D01*
X803050Y69532D01*
X803092Y69157D01*
X803008Y68782D01*
X802883Y68532D01*
X802633Y68282D01*
X802342Y68115D01*
X802050Y68032D01*
X801758D01*
X801467Y68115D01*
X801217Y68240D01*
X801008Y68407D01*
G01X799742Y69074D02*
X799450Y69365D01*
X799200Y69532D01*
X798867Y69615D01*
X798575Y69532D01*
X798367Y69365D01*
X798200Y69115D01*
X798158Y68824D01*
X798200Y68574D01*
X798367Y68324D01*
X798617Y68115D01*
X798908Y68032D01*
X799242Y68115D01*
X799533Y68365D01*
X799700Y68740D01*
X799742Y69157D01*
X799658Y69699D01*
X799533Y69990D01*
X799325Y70282D01*
X799033Y70490D01*
X798742Y70532D01*
X798450Y70449D01*
X798242Y70240D01*
G01X795850Y70532D02*
Y68032D01*
G01X796808Y70532D02*
X794892D01*
G01X792750Y68032D02*
Y70532D01*
X793250Y70032D01*
G01Y68032D02*
X792250D01*
G01X889480Y122000D02*
X870500D01*
Y137850D01*
X870499Y137851D01*
X841515D01*
Y209280D01*
X900618D01*
Y150890D01*
G01X851368Y181520D02*
X851493Y181270D01*
X851576Y180978D01*
Y180645D01*
X851451Y180270D01*
X851243Y179978D01*
X850993Y179770D01*
X850576Y179603D01*
X850201Y179561D01*
X849826Y179645D01*
X849576Y179770D01*
X849326Y180020D01*
X849159Y180311D01*
X849076Y180603D01*
Y180895D01*
X849159Y181186D01*
X849284Y181436D01*
X849451Y181645D01*
G01X851159Y182911D02*
X851409Y183161D01*
X851534Y183453D01*
X851576Y183786D01*
X851493Y184203D01*
X851284Y184495D01*
X851034Y184578D01*
X850784Y184536D01*
X850576Y184370D01*
X850159Y183536D01*
X849868Y183161D01*
X849451Y182911D01*
X849076Y182828D01*
Y184578D01*
G01X849451Y185886D02*
X849243Y186136D01*
X849118Y186428D01*
X849076Y186803D01*
X849159Y187178D01*
X849326Y187470D01*
X849618Y187678D01*
X849951Y187720D01*
X850284Y187636D01*
X850493Y187428D01*
X850659Y187136D01*
X850701Y186845D01*
X850659Y186553D01*
X850493Y186178D01*
X851576Y186303D01*
Y187428D01*
G01Y188653D02*
X849076Y189236D01*
X851576Y189903D01*
X849076Y190570D01*
X851576Y191153D01*
G01X851159Y192211D02*
X851409Y192461D01*
X851534Y192753D01*
X851576Y193086D01*
X851493Y193503D01*
X851284Y193795D01*
X851034Y193878D01*
X850784Y193836D01*
X850576Y193670D01*
X850159Y192836D01*
X849868Y192461D01*
X849451Y192211D01*
X849076Y192128D01*
Y193878D01*
G01X849451Y195186D02*
X849243Y195436D01*
X849118Y195728D01*
X849076Y196103D01*
X849159Y196478D01*
X849326Y196770D01*
X849618Y196978D01*
X849951Y197020D01*
X850284Y196936D01*
X850493Y196728D01*
X850659Y196436D01*
X850701Y196145D01*
X850659Y195853D01*
X850493Y195478D01*
X851576Y195603D01*
Y196728D01*
G01X801108Y215500D02*
X823680D01*
G01X801108D02*
Y218195D01*
G01X836472Y218200D02*
Y214409D01*
X823676D01*
Y218200D01*
G01X858657Y203296D02*
Y205796D01*
X857073D01*
G01X857657Y204588D02*
X858657D01*
G01X854432Y204629D02*
X854265Y204754D01*
X854140Y204963D01*
X854057Y205254D01*
X854140Y205504D01*
X854307Y205671D01*
X854598Y205796D01*
X855723D01*
Y203296D01*
X854348D01*
X854057Y203463D01*
X853890Y203713D01*
X853807Y204004D01*
X853890Y204296D01*
X854140Y204546D01*
X854432Y204629D01*
X855723D01*
G01X852457Y205379D02*
X852207Y205629D01*
X851915Y205754D01*
X851582Y205796D01*
X851165Y205713D01*
X850873Y205504D01*
X850790Y205254D01*
X850832Y205004D01*
X850998Y204796D01*
X851832Y204379D01*
X852207Y204088D01*
X852457Y203671D01*
X852540Y203296D01*
X850790D01*
G01X848565Y205796D02*
Y203296D01*
G01X849523Y205796D02*
X847607D01*
G01X844965Y203296D02*
Y205796D01*
X846507Y204004D01*
X844423D01*
G01X858783Y272592D02*
X859033Y272717D01*
X859325Y272800D01*
X859658D01*
X860033Y272675D01*
X860325Y272467D01*
X860533Y272217D01*
X860700Y271800D01*
X860742Y271425D01*
X860658Y271050D01*
X860533Y270800D01*
X860283Y270550D01*
X859992Y270383D01*
X859700Y270300D01*
X859408D01*
X859117Y270383D01*
X858867Y270508D01*
X858658Y270675D01*
G01X857392Y271342D02*
X857100Y271633D01*
X856850Y271800D01*
X856517Y271883D01*
X856225Y271800D01*
X856017Y271633D01*
X855850Y271383D01*
X855808Y271092D01*
X855850Y270842D01*
X856017Y270592D01*
X856267Y270383D01*
X856558Y270300D01*
X856892Y270383D01*
X857183Y270633D01*
X857350Y271008D01*
X857392Y271425D01*
X857308Y271967D01*
X857183Y272258D01*
X856975Y272550D01*
X856683Y272758D01*
X856392Y272800D01*
X856100Y272717D01*
X855892Y272508D01*
G01X854333Y270300D02*
Y272800D01*
X853333D01*
X853000Y272675D01*
X852750Y272383D01*
X852667Y272050D01*
X852750Y271717D01*
X852958Y271467D01*
X853333Y271342D01*
X854333D01*
G01X851192Y272383D02*
X850942Y272633D01*
X850650Y272758D01*
X850317Y272800D01*
X849900Y272717D01*
X849608Y272508D01*
X849525Y272258D01*
X849567Y272008D01*
X849733Y271800D01*
X850567Y271383D01*
X850942Y271092D01*
X851192Y270675D01*
X851275Y270300D01*
X849525D01*
G01X847300D02*
Y272800D01*
X847800Y272300D01*
G01Y270300D02*
X846800D01*
G01X847741Y258292D02*
X847991Y258417D01*
X848283Y258500D01*
X848616D01*
X848991Y258375D01*
X849283Y258167D01*
X849491Y257917D01*
X849658Y257500D01*
X849700Y257125D01*
X849616Y256750D01*
X849491Y256500D01*
X849241Y256250D01*
X848950Y256083D01*
X848658Y256000D01*
X848366D01*
X848075Y256083D01*
X847825Y256208D01*
X847616Y256375D01*
G01X846350Y257042D02*
X846058Y257333D01*
X845808Y257500D01*
X845475Y257583D01*
X845183Y257500D01*
X844975Y257333D01*
X844808Y257083D01*
X844766Y256792D01*
X844808Y256542D01*
X844975Y256292D01*
X845225Y256083D01*
X845516Y256000D01*
X845850Y256083D01*
X846141Y256333D01*
X846308Y256708D01*
X846350Y257125D01*
X846266Y257667D01*
X846141Y257958D01*
X845933Y258250D01*
X845641Y258458D01*
X845350Y258500D01*
X845058Y258417D01*
X844850Y258208D01*
G01X843291Y256000D02*
Y258500D01*
X842250D01*
X841916Y258375D01*
X841708Y258208D01*
X841625Y257875D01*
X841708Y257542D01*
X841958Y257333D01*
X842250Y257208D01*
X843291D01*
G01X842250D02*
X841625Y256000D01*
G01X840275Y256500D02*
X840025Y256208D01*
X839691Y256042D01*
X839316Y256000D01*
X838983Y256042D01*
X838650Y256250D01*
X838441Y256500D01*
X838400Y256750D01*
X838483Y257042D01*
X838775Y257250D01*
X839066Y257333D01*
X839441D01*
G01X839066D02*
X838816Y257458D01*
X838608Y257667D01*
X838525Y257917D01*
X838608Y258167D01*
X838816Y258375D01*
X839191Y258500D01*
X839566Y258458D01*
X839941Y258292D01*
G01X836472Y240200D02*
Y236409D01*
X823676D01*
Y240200D01*
G01X836472Y252800D02*
Y256362D01*
X823676D01*
Y252800D01*
G01X801108Y255500D02*
Y252802D01*
G01Y237500D02*
Y240195D01*
G01Y237500D02*
X823680D01*
G01X801108Y255500D02*
X823683D01*
G01X848441Y227492D02*
X848691Y227617D01*
X848983Y227700D01*
X849316D01*
X849691Y227575D01*
X849983Y227367D01*
X850191Y227117D01*
X850358Y226700D01*
X850400Y226325D01*
X850316Y225950D01*
X850191Y225700D01*
X849941Y225450D01*
X849650Y225283D01*
X849358Y225200D01*
X849066D01*
X848775Y225283D01*
X848525Y225408D01*
X848316Y225575D01*
G01X847050Y226242D02*
X846758Y226533D01*
X846508Y226700D01*
X846175Y226783D01*
X845883Y226700D01*
X845675Y226533D01*
X845508Y226283D01*
X845466Y225992D01*
X845508Y225742D01*
X845675Y225492D01*
X845925Y225283D01*
X846216Y225200D01*
X846550Y225283D01*
X846841Y225533D01*
X847008Y225908D01*
X847050Y226325D01*
X846966Y226867D01*
X846841Y227158D01*
X846633Y227450D01*
X846341Y227658D01*
X846050Y227700D01*
X845758Y227617D01*
X845550Y227408D01*
G01X843991Y225200D02*
Y227700D01*
X842950D01*
X842616Y227575D01*
X842408Y227408D01*
X842325Y227075D01*
X842408Y226742D01*
X842658Y226533D01*
X842950Y226408D01*
X843991D01*
G01X842950D02*
X842325Y225200D01*
G01X840766Y225492D02*
X840475Y225283D01*
X840141Y225200D01*
X839808Y225283D01*
X839516Y225533D01*
X839308Y225908D01*
X839225Y226283D01*
Y226742D01*
X839308Y227117D01*
X839516Y227450D01*
X839766Y227617D01*
X840058Y227700D01*
X840391Y227617D01*
X840641Y227450D01*
X840808Y227200D01*
X840891Y226867D01*
X840808Y226575D01*
X840600Y226283D01*
X840350Y226117D01*
X840058Y226075D01*
X839725Y226158D01*
X839475Y226367D01*
X839225Y226742D01*
G01X801108Y233500D02*
X823683D01*
G01X801108D02*
Y230802D01*
G01X836472Y230800D02*
Y234362D01*
X823676D01*
Y230800D01*
G01X801108Y279500D02*
X823680D01*
G01X801108D02*
Y282195D01*
G01X836472Y282200D02*
Y278409D01*
X823676D01*
Y282200D01*
G01X850591Y262792D02*
X850841Y262917D01*
X851133Y263000D01*
X851466D01*
X851841Y262875D01*
X852133Y262667D01*
X852341Y262417D01*
X852508Y262000D01*
X852550Y261625D01*
X852466Y261250D01*
X852341Y261000D01*
X852091Y260750D01*
X851800Y260583D01*
X851508Y260500D01*
X851216D01*
X850925Y260583D01*
X850675Y260708D01*
X850466Y260875D01*
G01X849200Y261542D02*
X848908Y261833D01*
X848658Y262000D01*
X848325Y262083D01*
X848033Y262000D01*
X847825Y261833D01*
X847658Y261583D01*
X847616Y261292D01*
X847658Y261042D01*
X847825Y260792D01*
X848075Y260583D01*
X848366Y260500D01*
X848700Y260583D01*
X848991Y260833D01*
X849158Y261208D01*
X849200Y261625D01*
X849116Y262167D01*
X848991Y262458D01*
X848783Y262750D01*
X848491Y262958D01*
X848200Y263000D01*
X847908Y262917D01*
X847700Y262708D01*
G01X846141Y260500D02*
Y263000D01*
X845141D01*
X844808Y262875D01*
X844558Y262583D01*
X844475Y262250D01*
X844558Y261917D01*
X844766Y261667D01*
X845141Y261542D01*
X846141D01*
G01X843000Y262583D02*
X842750Y262833D01*
X842458Y262958D01*
X842125Y263000D01*
X841708Y262917D01*
X841416Y262708D01*
X841333Y262458D01*
X841375Y262208D01*
X841541Y262000D01*
X842375Y261583D01*
X842750Y261292D01*
X843000Y260875D01*
X843083Y260500D01*
X841333D01*
G01X840025Y261000D02*
X839775Y260708D01*
X839441Y260542D01*
X839066Y260500D01*
X838733Y260542D01*
X838400Y260750D01*
X838191Y261000D01*
X838150Y261250D01*
X838233Y261542D01*
X838525Y261750D01*
X838816Y261833D01*
X839191D01*
G01X838816D02*
X838566Y261958D01*
X838358Y262167D01*
X838275Y262417D01*
X838358Y262667D01*
X838566Y262875D01*
X838941Y263000D01*
X839316Y262958D01*
X839691Y262792D01*
G01X801108Y276500D02*
X823683D01*
G01X801108Y258500D02*
X823680D01*
G01X801108D02*
Y261195D01*
G01Y276500D02*
Y273802D01*
G01X836472Y273800D02*
Y277362D01*
X823676D01*
Y273800D01*
G01X836472Y261200D02*
Y257409D01*
X823676D01*
Y261200D01*
G01X859598Y304292D02*
X859848Y304417D01*
X860140Y304500D01*
X860473D01*
X860848Y304375D01*
X861140Y304167D01*
X861348Y303917D01*
X861515Y303500D01*
X861557Y303125D01*
X861473Y302750D01*
X861348Y302500D01*
X861098Y302250D01*
X860807Y302083D01*
X860515Y302000D01*
X860223D01*
X859932Y302083D01*
X859682Y302208D01*
X859473Y302375D01*
G01X858207Y303042D02*
X857915Y303333D01*
X857665Y303500D01*
X857332Y303583D01*
X857040Y303500D01*
X856832Y303333D01*
X856665Y303083D01*
X856623Y302792D01*
X856665Y302542D01*
X856832Y302292D01*
X857082Y302083D01*
X857373Y302000D01*
X857707Y302083D01*
X857998Y302333D01*
X858165Y302708D01*
X858207Y303125D01*
X858123Y303667D01*
X857998Y303958D01*
X857790Y304250D01*
X857498Y304458D01*
X857207Y304500D01*
X856915Y304417D01*
X856707Y304208D01*
G01X855148Y302000D02*
Y304500D01*
X854148D01*
X853815Y304375D01*
X853565Y304083D01*
X853482Y303750D01*
X853565Y303417D01*
X853773Y303167D01*
X854148Y303042D01*
X855148D01*
G01X851215Y302000D02*
Y304500D01*
X851715Y304000D01*
G01Y302000D02*
X850715D01*
G01X848907Y303042D02*
X848615Y303333D01*
X848365Y303500D01*
X848032Y303583D01*
X847740Y303500D01*
X847532Y303333D01*
X847365Y303083D01*
X847323Y302792D01*
X847365Y302542D01*
X847532Y302292D01*
X847782Y302083D01*
X848073Y302000D01*
X848407Y302083D01*
X848698Y302333D01*
X848865Y302708D01*
X848907Y303125D01*
X848823Y303667D01*
X848698Y303958D01*
X848490Y304250D01*
X848198Y304458D01*
X847907Y304500D01*
X847615Y304417D01*
X847407Y304208D01*
G01X850191Y319992D02*
X850441Y320117D01*
X850733Y320200D01*
X851066D01*
X851441Y320075D01*
X851733Y319867D01*
X851941Y319617D01*
X852108Y319200D01*
X852150Y318825D01*
X852066Y318450D01*
X851941Y318200D01*
X851691Y317950D01*
X851400Y317783D01*
X851108Y317700D01*
X850816D01*
X850525Y317783D01*
X850275Y317908D01*
X850066Y318075D01*
G01X848800Y318742D02*
X848508Y319033D01*
X848258Y319200D01*
X847925Y319283D01*
X847633Y319200D01*
X847425Y319033D01*
X847258Y318783D01*
X847216Y318492D01*
X847258Y318242D01*
X847425Y317992D01*
X847675Y317783D01*
X847966Y317700D01*
X848300Y317783D01*
X848591Y318033D01*
X848758Y318408D01*
X848800Y318825D01*
X848716Y319367D01*
X848591Y319658D01*
X848383Y319950D01*
X848091Y320158D01*
X847800Y320200D01*
X847508Y320117D01*
X847300Y319908D01*
G01X845741Y317700D02*
Y320200D01*
X844741D01*
X844408Y320075D01*
X844158Y319783D01*
X844075Y319450D01*
X844158Y319117D01*
X844366Y318867D01*
X844741Y318742D01*
X845741D01*
G01X841808Y317700D02*
Y320200D01*
X842308Y319700D01*
G01Y317700D02*
X841308D01*
G01X838208D02*
Y320200D01*
X839750Y318408D01*
X837666D01*
G01X836472Y304200D02*
Y300409D01*
X823676D01*
Y304200D01*
G01X836472Y316800D02*
Y320362D01*
X823676D01*
Y316800D01*
G01X801108Y319500D02*
Y316802D01*
G01Y301500D02*
Y304195D01*
G01Y301500D02*
X823680D01*
G01X801108Y319500D02*
X823683D01*
G01X849991Y291492D02*
X850241Y291617D01*
X850533Y291700D01*
X850866D01*
X851241Y291575D01*
X851533Y291367D01*
X851741Y291117D01*
X851908Y290700D01*
X851950Y290325D01*
X851866Y289950D01*
X851741Y289700D01*
X851491Y289450D01*
X851200Y289283D01*
X850908Y289200D01*
X850616D01*
X850325Y289283D01*
X850075Y289408D01*
X849866Y289575D01*
G01X848600Y290242D02*
X848308Y290533D01*
X848058Y290700D01*
X847725Y290783D01*
X847433Y290700D01*
X847225Y290533D01*
X847058Y290283D01*
X847016Y289992D01*
X847058Y289742D01*
X847225Y289492D01*
X847475Y289283D01*
X847766Y289200D01*
X848100Y289283D01*
X848391Y289533D01*
X848558Y289908D01*
X848600Y290325D01*
X848516Y290867D01*
X848391Y291158D01*
X848183Y291450D01*
X847891Y291658D01*
X847600Y291700D01*
X847308Y291617D01*
X847100Y291408D01*
G01X845541Y289200D02*
Y291700D01*
X844541D01*
X844208Y291575D01*
X843958Y291283D01*
X843875Y290950D01*
X843958Y290617D01*
X844166Y290367D01*
X844541Y290242D01*
X845541D01*
G01X841608Y289200D02*
Y291700D01*
X842108Y291200D01*
G01Y289200D02*
X841108D01*
G01X838508D02*
X838216Y289242D01*
X837883Y289367D01*
X837675Y289575D01*
X837591Y289867D01*
X837675Y290158D01*
X837925Y290408D01*
X838300Y290533D01*
X838716D01*
X838966Y290617D01*
X839175Y290825D01*
X839258Y291117D01*
X839133Y291408D01*
X838841Y291617D01*
X838508Y291700D01*
X838175Y291617D01*
X837883Y291408D01*
X837758Y291117D01*
X837841Y290825D01*
X838050Y290617D01*
X838300Y290533D01*
X838716D01*
X839091Y290408D01*
X839341Y290158D01*
X839425Y289867D01*
X839341Y289575D01*
X839133Y289367D01*
X838800Y289242D01*
X838508Y289200D01*
G01X801108Y297500D02*
X823683D01*
G01X801108D02*
Y294802D01*
G01X836472Y294800D02*
Y298362D01*
X823676D01*
Y294800D01*
G01X847741Y324792D02*
X847991Y324917D01*
X848283Y325000D01*
X848616D01*
X848991Y324875D01*
X849283Y324667D01*
X849491Y324417D01*
X849658Y324000D01*
X849700Y323625D01*
X849616Y323250D01*
X849491Y323000D01*
X849241Y322750D01*
X848950Y322583D01*
X848658Y322500D01*
X848366D01*
X848075Y322583D01*
X847825Y322708D01*
X847616Y322875D01*
G01X846350Y323542D02*
X846058Y323833D01*
X845808Y324000D01*
X845475Y324083D01*
X845183Y324000D01*
X844975Y323833D01*
X844808Y323583D01*
X844766Y323292D01*
X844808Y323042D01*
X844975Y322792D01*
X845225Y322583D01*
X845516Y322500D01*
X845850Y322583D01*
X846141Y322833D01*
X846308Y323208D01*
X846350Y323625D01*
X846266Y324167D01*
X846141Y324458D01*
X845933Y324750D01*
X845641Y324958D01*
X845350Y325000D01*
X845058Y324917D01*
X844850Y324708D01*
G01X843291Y322500D02*
Y325000D01*
X842291D01*
X841958Y324875D01*
X841708Y324583D01*
X841625Y324250D01*
X841708Y323917D01*
X841916Y323667D01*
X842291Y323542D01*
X843291D01*
G01X839358Y322500D02*
X839066Y322542D01*
X838733Y322667D01*
X838525Y322875D01*
X838441Y323167D01*
X838525Y323458D01*
X838775Y323708D01*
X839150Y323833D01*
X839566D01*
X839816Y323917D01*
X840025Y324125D01*
X840108Y324417D01*
X839983Y324708D01*
X839691Y324917D01*
X839358Y325000D01*
X839025Y324917D01*
X838733Y324708D01*
X838608Y324417D01*
X838691Y324125D01*
X838900Y323917D01*
X839150Y323833D01*
X839566D01*
X839941Y323708D01*
X840191Y323458D01*
X840275Y323167D01*
X840191Y322875D01*
X839983Y322667D01*
X839650Y322542D01*
X839358Y322500D01*
G01X801108Y339500D02*
X823683D01*
G01X801108Y321500D02*
X823680D01*
G01X801108D02*
Y324195D01*
G01Y339500D02*
Y336802D01*
G01X836472Y336800D02*
Y340362D01*
X823676D01*
Y336800D01*
G01X836472Y324200D02*
Y320409D01*
X823676D01*
Y324200D01*
G01X858183Y383400D02*
Y385900D01*
X857142D01*
X856808Y385775D01*
X856600Y385608D01*
X856517Y385275D01*
X856600Y384942D01*
X856850Y384733D01*
X857142Y384608D01*
X858183D01*
G01X857142D02*
X856517Y383400D01*
G01X855042Y384442D02*
X854750Y384733D01*
X854500Y384900D01*
X854167Y384983D01*
X853875Y384900D01*
X853667Y384733D01*
X853500Y384483D01*
X853458Y384192D01*
X853500Y383942D01*
X853667Y383692D01*
X853917Y383483D01*
X854208Y383400D01*
X854542Y383483D01*
X854833Y383733D01*
X855000Y384108D01*
X855042Y384525D01*
X854958Y385067D01*
X854833Y385358D01*
X854625Y385650D01*
X854333Y385858D01*
X854042Y385900D01*
X853750Y385817D01*
X853542Y385608D01*
G01X852108Y383400D02*
Y385900D01*
X850192Y383400D01*
Y385900D01*
G01X847550Y383400D02*
Y385900D01*
X849092Y384108D01*
X847008D01*
G01X857054Y371469D02*
X857304Y371594D01*
X857596Y371677D01*
X857929D01*
X858304Y371552D01*
X858596Y371344D01*
X858804Y371094D01*
X858971Y370677D01*
X859013Y370302D01*
X858929Y369927D01*
X858804Y369677D01*
X858554Y369427D01*
X858263Y369260D01*
X857971Y369177D01*
X857679D01*
X857388Y369260D01*
X857138Y369385D01*
X856929Y369552D01*
G01X855663Y370219D02*
X855371Y370510D01*
X855121Y370677D01*
X854788Y370760D01*
X854496Y370677D01*
X854288Y370510D01*
X854121Y370260D01*
X854079Y369969D01*
X854121Y369719D01*
X854288Y369469D01*
X854538Y369260D01*
X854829Y369177D01*
X855163Y369260D01*
X855454Y369510D01*
X855621Y369885D01*
X855663Y370302D01*
X855579Y370844D01*
X855454Y371135D01*
X855246Y371427D01*
X854954Y371635D01*
X854663Y371677D01*
X854371Y371594D01*
X854163Y371385D01*
G01X852729Y369177D02*
Y371677D01*
X850813Y369177D01*
Y371677D01*
G01X848754Y369177D02*
X848671Y369719D01*
X848546Y370177D01*
X848379Y370594D01*
X848171Y371052D01*
X847838Y371677D01*
X849504D01*
G01X852115Y392055D02*
X852365Y392180D01*
X852657Y392263D01*
X852990D01*
X853365Y392138D01*
X853657Y391930D01*
X853865Y391680D01*
X854032Y391263D01*
X854074Y390888D01*
X853990Y390513D01*
X853865Y390263D01*
X853615Y390013D01*
X853324Y389846D01*
X853032Y389763D01*
X852740D01*
X852449Y389846D01*
X852199Y389971D01*
X851990Y390138D01*
G01X850724Y390805D02*
X850432Y391096D01*
X850182Y391263D01*
X849849Y391346D01*
X849557Y391263D01*
X849349Y391096D01*
X849182Y390846D01*
X849140Y390555D01*
X849182Y390305D01*
X849349Y390055D01*
X849599Y389846D01*
X849890Y389763D01*
X850224Y389846D01*
X850515Y390096D01*
X850682Y390471D01*
X850724Y390888D01*
X850640Y391430D01*
X850515Y391721D01*
X850307Y392013D01*
X850015Y392221D01*
X849724Y392263D01*
X849432Y392180D01*
X849224Y391971D01*
G01X847790Y389763D02*
Y392263D01*
X845874Y389763D01*
Y392263D01*
G01X843232Y389763D02*
Y392263D01*
X844774Y390471D01*
X842690D01*
G01X800182Y385363D02*
X822757D01*
G01X800182Y367363D02*
X822754D01*
G01X800182D02*
Y370058D01*
G01Y385363D02*
Y382665D01*
G01X835546Y382663D02*
Y386225D01*
X822750D01*
Y382663D01*
G01X835546Y370063D02*
Y366272D01*
X822750D01*
Y370063D01*
G01X845515Y404255D02*
X845765Y404380D01*
X846057Y404463D01*
X846390D01*
X846765Y404338D01*
X847057Y404130D01*
X847265Y403880D01*
X847432Y403463D01*
X847474Y403088D01*
X847390Y402713D01*
X847265Y402463D01*
X847015Y402213D01*
X846724Y402046D01*
X846432Y401963D01*
X846140D01*
X845849Y402046D01*
X845599Y402171D01*
X845390Y402338D01*
G01X844124Y403005D02*
X843832Y403296D01*
X843582Y403463D01*
X843249Y403546D01*
X842957Y403463D01*
X842749Y403296D01*
X842582Y403046D01*
X842540Y402755D01*
X842582Y402505D01*
X842749Y402255D01*
X842999Y402046D01*
X843290Y401963D01*
X843624Y402046D01*
X843915Y402296D01*
X844082Y402671D01*
X844124Y403088D01*
X844040Y403630D01*
X843915Y403921D01*
X843707Y404213D01*
X843415Y404421D01*
X843124Y404463D01*
X842832Y404380D01*
X842624Y404171D01*
G01X841190Y401963D02*
Y404463D01*
X839274Y401963D01*
Y404463D01*
G01X837132Y401963D02*
Y404463D01*
X837632Y403963D01*
G01Y401963D02*
X836632D01*
G01X800182Y387363D02*
X822754D01*
G01X800182D02*
Y390058D01*
G01Y405363D02*
Y402665D01*
G01X835546Y402663D02*
Y406225D01*
X822750D01*
Y402663D01*
G01X835546Y390063D02*
Y386272D01*
X822750D01*
Y390063D01*
G01X848441Y355792D02*
X848691Y355917D01*
X848983Y356000D01*
X849316D01*
X849691Y355875D01*
X849983Y355667D01*
X850191Y355417D01*
X850358Y355000D01*
X850400Y354625D01*
X850316Y354250D01*
X850191Y354000D01*
X849941Y353750D01*
X849650Y353583D01*
X849358Y353500D01*
X849066D01*
X848775Y353583D01*
X848525Y353708D01*
X848316Y353875D01*
G01X847050Y354542D02*
X846758Y354833D01*
X846508Y355000D01*
X846175Y355083D01*
X845883Y355000D01*
X845675Y354833D01*
X845508Y354583D01*
X845466Y354292D01*
X845508Y354042D01*
X845675Y353792D01*
X845925Y353583D01*
X846216Y353500D01*
X846550Y353583D01*
X846841Y353833D01*
X847008Y354208D01*
X847050Y354625D01*
X846966Y355167D01*
X846841Y355458D01*
X846633Y355750D01*
X846341Y355958D01*
X846050Y356000D01*
X845758Y355917D01*
X845550Y355708D01*
G01X844116Y353500D02*
Y356000D01*
X842200Y353500D01*
Y356000D01*
G01X840766Y353792D02*
X840475Y353583D01*
X840141Y353500D01*
X839808Y353583D01*
X839516Y353833D01*
X839308Y354208D01*
X839225Y354583D01*
Y355042D01*
X839308Y355417D01*
X839516Y355750D01*
X839766Y355917D01*
X840058Y356000D01*
X840391Y355917D01*
X840641Y355750D01*
X840808Y355500D01*
X840891Y355167D01*
X840808Y354875D01*
X840600Y354583D01*
X840350Y354417D01*
X840058Y354375D01*
X839725Y354458D01*
X839475Y354667D01*
X839225Y355042D01*
G01X836472Y346500D02*
Y342709D01*
X823676D01*
Y346500D01*
G01X836472Y359100D02*
Y362662D01*
X823676D01*
Y359100D01*
G01X801108Y361800D02*
Y359102D01*
G01Y343800D02*
Y346495D01*
G01Y343800D02*
X823680D01*
G01X801108Y361800D02*
X823683D01*
G01X793425Y441597D02*
X792892Y441947D01*
X792492Y442531D01*
X792225Y443347D01*
X792492Y444047D01*
X793025Y444514D01*
X793959Y444864D01*
X797559D01*
Y437864D01*
X793159D01*
X792225Y438331D01*
X791692Y439031D01*
X791425Y439847D01*
X791692Y440664D01*
X792492Y441364D01*
X793425Y441597D01*
X797559D01*
G01X923380Y489000D02*
X950370D01*
Y484530D01*
X969620D01*
Y456710D01*
X966999D01*
Y420000D01*
X792500D01*
G01X826703Y411002D02*
Y413502D01*
X825662D01*
X825328Y413377D01*
X825120Y413210D01*
X825037Y412877D01*
X825120Y412544D01*
X825370Y412335D01*
X825662Y412210D01*
X826703D01*
G01X825662D02*
X825037Y411002D01*
G01X823562Y412044D02*
X823270Y412335D01*
X823020Y412502D01*
X822687Y412585D01*
X822395Y412502D01*
X822187Y412335D01*
X822020Y412085D01*
X821978Y411794D01*
X822020Y411544D01*
X822187Y411294D01*
X822437Y411085D01*
X822728Y411002D01*
X823062Y411085D01*
X823353Y411335D01*
X823520Y411710D01*
X823562Y412127D01*
X823478Y412669D01*
X823353Y412960D01*
X823145Y413252D01*
X822853Y413460D01*
X822562Y413502D01*
X822270Y413419D01*
X822062Y413210D01*
G01X820628Y411002D02*
Y413502D01*
X818712Y411002D01*
Y413502D01*
G01X816570Y411002D02*
Y413502D01*
X817070Y413002D01*
G01Y411002D02*
X816070D01*
G01X813470D02*
Y413502D01*
X813970Y413002D01*
G01Y411002D02*
X812970D01*
G01X826643Y414556D02*
Y417056D01*
X825602D01*
X825268Y416931D01*
X825060Y416764D01*
X824977Y416431D01*
X825060Y416098D01*
X825310Y415889D01*
X825602Y415764D01*
X826643D01*
G01X825602D02*
X824977Y414556D01*
G01X823502Y415598D02*
X823210Y415889D01*
X822960Y416056D01*
X822627Y416139D01*
X822335Y416056D01*
X822127Y415889D01*
X821960Y415639D01*
X821918Y415348D01*
X821960Y415098D01*
X822127Y414848D01*
X822377Y414639D01*
X822668Y414556D01*
X823002Y414639D01*
X823293Y414889D01*
X823460Y415264D01*
X823502Y415681D01*
X823418Y416223D01*
X823293Y416514D01*
X823085Y416806D01*
X822793Y417014D01*
X822502Y417056D01*
X822210Y416973D01*
X822002Y416764D01*
G01X820568Y414556D02*
Y417056D01*
X818652Y414556D01*
Y417056D01*
G01X816510Y414556D02*
Y417056D01*
X817010Y416556D01*
G01Y414556D02*
X816010D01*
G01X813410Y417056D02*
X813743Y416973D01*
X813993Y416764D01*
X814160Y416514D01*
X814285Y416181D01*
X814327Y415806D01*
X814285Y415431D01*
X814160Y415098D01*
X813993Y414848D01*
X813743Y414639D01*
X813410Y414556D01*
X813077Y414639D01*
X812827Y414848D01*
X812660Y415098D01*
X812535Y415431D01*
X812493Y415806D01*
X812535Y416181D01*
X812660Y416514D01*
X812827Y416764D01*
X813077Y416973D01*
X813410Y417056D01*
G01X827007Y407371D02*
Y409871D01*
X825966D01*
X825632Y409746D01*
X825424Y409579D01*
X825341Y409246D01*
X825424Y408913D01*
X825674Y408704D01*
X825966Y408579D01*
X827007D01*
G01X825966D02*
X825341Y407371D01*
G01X823866Y408413D02*
X823574Y408704D01*
X823324Y408871D01*
X822991Y408954D01*
X822699Y408871D01*
X822491Y408704D01*
X822324Y408454D01*
X822282Y408163D01*
X822324Y407913D01*
X822491Y407663D01*
X822741Y407454D01*
X823032Y407371D01*
X823366Y407454D01*
X823657Y407704D01*
X823824Y408079D01*
X823866Y408496D01*
X823782Y409038D01*
X823657Y409329D01*
X823449Y409621D01*
X823157Y409829D01*
X822866Y409871D01*
X822574Y409788D01*
X822366Y409579D01*
G01X820932Y407371D02*
Y409871D01*
X819016Y407371D01*
Y409871D01*
G01X816874Y407371D02*
Y409871D01*
X817374Y409371D01*
G01Y407371D02*
X816374D01*
G01X814566Y409454D02*
X814316Y409704D01*
X814024Y409829D01*
X813691Y409871D01*
X813274Y409788D01*
X812982Y409579D01*
X812899Y409329D01*
X812941Y409079D01*
X813107Y408871D01*
X813941Y408454D01*
X814316Y408163D01*
X814566Y407746D01*
X814649Y407371D01*
X812899D01*
G01X809685Y456440D02*
Y458940D01*
X808644D01*
X808310Y458815D01*
X808102Y458648D01*
X808019Y458315D01*
X808102Y457982D01*
X808352Y457773D01*
X808644Y457648D01*
X809685D01*
G01X808644D02*
X808019Y456440D01*
G01X806544Y458523D02*
X806294Y458773D01*
X806002Y458898D01*
X805669Y458940D01*
X805252Y458857D01*
X804960Y458648D01*
X804877Y458398D01*
X804919Y458148D01*
X805085Y457940D01*
X805919Y457523D01*
X806294Y457232D01*
X806544Y456815D01*
X806627Y456440D01*
X804877D01*
G01X803569Y456815D02*
X803319Y456607D01*
X803027Y456482D01*
X802652Y456440D01*
X802277Y456523D01*
X801985Y456690D01*
X801777Y456982D01*
X801735Y457315D01*
X801819Y457648D01*
X802027Y457857D01*
X802319Y458023D01*
X802610Y458065D01*
X802902Y458023D01*
X803277Y457857D01*
X803152Y458940D01*
X802027D01*
G01X800802D02*
X800219Y456440D01*
X799552Y458940D01*
X798885Y456440D01*
X798302Y458940D01*
G01X796452Y456440D02*
Y458940D01*
X796952Y458440D01*
G01Y456440D02*
X795952D01*
G01X793352Y458940D02*
X793685Y458857D01*
X793935Y458648D01*
X794102Y458398D01*
X794227Y458065D01*
X794269Y457690D01*
X794227Y457315D01*
X794102Y456982D01*
X793935Y456732D01*
X793685Y456523D01*
X793352Y456440D01*
X793019Y456523D01*
X792769Y456732D01*
X792602Y456982D01*
X792477Y457315D01*
X792435Y457690D01*
X792477Y458065D01*
X792602Y458398D01*
X792769Y458648D01*
X793019Y458857D01*
X793352Y458940D01*
G01X791044Y457482D02*
X790752Y457773D01*
X790502Y457940D01*
X790169Y458023D01*
X789877Y457940D01*
X789669Y457773D01*
X789502Y457523D01*
X789460Y457232D01*
X789502Y456982D01*
X789669Y456732D01*
X789919Y456523D01*
X790210Y456440D01*
X790544Y456523D01*
X790835Y456773D01*
X791002Y457148D01*
X791044Y457565D01*
X790960Y458107D01*
X790835Y458398D01*
X790627Y458690D01*
X790335Y458898D01*
X790044Y458940D01*
X789752Y458857D01*
X789544Y458648D01*
G01X812142Y463960D02*
X814642D01*
Y465001D01*
X814517Y465335D01*
X814350Y465543D01*
X814017Y465626D01*
X813684Y465543D01*
X813475Y465293D01*
X813350Y465001D01*
Y463960D01*
G01Y465001D02*
X812142Y465626D01*
G01X814225Y467101D02*
X814475Y467351D01*
X814600Y467643D01*
X814642Y467976D01*
X814559Y468393D01*
X814350Y468685D01*
X814100Y468768D01*
X813850Y468726D01*
X813642Y468560D01*
X813225Y467726D01*
X812934Y467351D01*
X812517Y467101D01*
X812142Y467018D01*
Y468768D01*
G01X812517Y470076D02*
X812309Y470326D01*
X812184Y470618D01*
X812142Y470993D01*
X812225Y471368D01*
X812392Y471660D01*
X812684Y471868D01*
X813017Y471910D01*
X813350Y471826D01*
X813559Y471618D01*
X813725Y471326D01*
X813767Y471035D01*
X813725Y470743D01*
X813559Y470368D01*
X814642Y470493D01*
Y471618D01*
G01Y472843D02*
X812142Y473426D01*
X814642Y474093D01*
X812142Y474760D01*
X814642Y475343D01*
G01X812142Y477193D02*
X812184Y477485D01*
X812309Y477818D01*
X812517Y478026D01*
X812809Y478110D01*
X813100Y478026D01*
X813350Y477776D01*
X813475Y477401D01*
Y476985D01*
X813559Y476735D01*
X813767Y476526D01*
X814059Y476443D01*
X814350Y476568D01*
X814559Y476860D01*
X814642Y477193D01*
X814559Y477526D01*
X814350Y477818D01*
X814059Y477943D01*
X813767Y477860D01*
X813559Y477651D01*
X813475Y477401D01*
Y476985D01*
X813350Y476610D01*
X813100Y476360D01*
X812809Y476276D01*
X812517Y476360D01*
X812309Y476568D01*
X812184Y476901D01*
X812142Y477193D01*
G01X813184Y479501D02*
X813475Y479793D01*
X813642Y480043D01*
X813725Y480376D01*
X813642Y480668D01*
X813475Y480876D01*
X813225Y481043D01*
X812934Y481085D01*
X812684Y481043D01*
X812434Y480876D01*
X812225Y480626D01*
X812142Y480335D01*
X812225Y480001D01*
X812475Y479710D01*
X812850Y479543D01*
X813267Y479501D01*
X813809Y479585D01*
X814100Y479710D01*
X814392Y479918D01*
X814600Y480210D01*
X814642Y480501D01*
X814559Y480793D01*
X814350Y481001D01*
G01X804154Y421622D02*
X806654D01*
Y422663D01*
X806529Y422997D01*
X806362Y423205D01*
X806029Y423288D01*
X805696Y423205D01*
X805487Y422955D01*
X805362Y422663D01*
Y421622D01*
G01Y422663D02*
X804154Y423288D01*
G01Y425555D02*
X806654D01*
X806154Y425055D01*
G01X804154D02*
Y426055D01*
G01X806654Y427738D02*
X804862D01*
X804487Y427905D01*
X804237Y428238D01*
X804154Y428655D01*
X804237Y429072D01*
X804487Y429405D01*
X804862Y429572D01*
X806654D01*
G01X804654Y430838D02*
X804362Y431088D01*
X804196Y431422D01*
X804154Y431797D01*
X804196Y432130D01*
X804404Y432463D01*
X804654Y432672D01*
X804904Y432713D01*
X805196Y432630D01*
X805404Y432338D01*
X805487Y432047D01*
Y431672D01*
G01Y432047D02*
X805612Y432297D01*
X805821Y432505D01*
X806071Y432588D01*
X806321Y432505D01*
X806529Y432297D01*
X806654Y431922D01*
X806612Y431547D01*
X806446Y431172D01*
G01X806237Y434063D02*
X806487Y434313D01*
X806612Y434605D01*
X806654Y434938D01*
X806571Y435355D01*
X806362Y435647D01*
X806112Y435730D01*
X805862Y435688D01*
X805654Y435522D01*
X805237Y434688D01*
X804946Y434313D01*
X804529Y434063D01*
X804154Y433980D01*
Y435730D01*
G01X817654Y436071D02*
X820154D01*
Y437112D01*
X820029Y437446D01*
X819862Y437654D01*
X819529Y437737D01*
X819196Y437654D01*
X818987Y437404D01*
X818862Y437112D01*
Y436071D01*
G01Y437112D02*
X817654Y437737D01*
G01Y440004D02*
X820154D01*
X819654Y439504D01*
G01X817654D02*
Y440504D01*
G01X820154Y442187D02*
X818362D01*
X817987Y442354D01*
X817737Y442687D01*
X817654Y443104D01*
X817737Y443521D01*
X817987Y443854D01*
X818362Y444021D01*
X820154D01*
G01X818154Y445287D02*
X817862Y445537D01*
X817696Y445871D01*
X817654Y446246D01*
X817696Y446579D01*
X817904Y446912D01*
X818154Y447121D01*
X818404Y447162D01*
X818696Y447079D01*
X818904Y446787D01*
X818987Y446496D01*
Y446121D01*
G01Y446496D02*
X819112Y446746D01*
X819321Y446954D01*
X819571Y447037D01*
X819821Y446954D01*
X820029Y446746D01*
X820154Y446371D01*
X820112Y445996D01*
X819946Y445621D01*
G01X817946Y448596D02*
X817737Y448887D01*
X817654Y449221D01*
X817737Y449554D01*
X817987Y449846D01*
X818362Y450054D01*
X818737Y450137D01*
X819196D01*
X819571Y450054D01*
X819904Y449846D01*
X820071Y449596D01*
X820154Y449304D01*
X820071Y448971D01*
X819904Y448721D01*
X819654Y448554D01*
X819321Y448471D01*
X819029Y448554D01*
X818737Y448762D01*
X818571Y449012D01*
X818529Y449304D01*
X818612Y449637D01*
X818821Y449887D01*
X819196Y450137D01*
G01X825654Y436071D02*
X828154D01*
Y437112D01*
X828029Y437446D01*
X827862Y437654D01*
X827529Y437737D01*
X827196Y437654D01*
X826987Y437404D01*
X826862Y437112D01*
Y436071D01*
G01Y437112D02*
X825654Y437737D01*
G01Y440004D02*
X828154D01*
X827654Y439504D01*
G01X825654D02*
Y440504D01*
G01X828154Y442187D02*
X826362D01*
X825987Y442354D01*
X825737Y442687D01*
X825654Y443104D01*
X825737Y443521D01*
X825987Y443854D01*
X826362Y444021D01*
X828154D01*
G01X826154Y445287D02*
X825862Y445537D01*
X825696Y445871D01*
X825654Y446246D01*
X825696Y446579D01*
X825904Y446912D01*
X826154Y447121D01*
X826404Y447162D01*
X826696Y447079D01*
X826904Y446787D01*
X826987Y446496D01*
Y446121D01*
G01Y446496D02*
X827112Y446746D01*
X827321Y446954D01*
X827571Y447037D01*
X827821Y446954D01*
X828029Y446746D01*
X828154Y446371D01*
X828112Y445996D01*
X827946Y445621D01*
G01X825654Y449304D02*
X825696Y449596D01*
X825821Y449929D01*
X826029Y450137D01*
X826321Y450221D01*
X826612Y450137D01*
X826862Y449887D01*
X826987Y449512D01*
Y449096D01*
X827071Y448846D01*
X827279Y448637D01*
X827571Y448554D01*
X827862Y448679D01*
X828071Y448971D01*
X828154Y449304D01*
X828071Y449637D01*
X827862Y449929D01*
X827571Y450054D01*
X827279Y449971D01*
X827071Y449762D01*
X826987Y449512D01*
Y449096D01*
X826862Y448721D01*
X826612Y448471D01*
X826321Y448387D01*
X826029Y448471D01*
X825821Y448679D01*
X825696Y449012D01*
X825654Y449304D01*
G01X854748Y448696D02*
Y451196D01*
X853707D01*
X853373Y451071D01*
X853165Y450904D01*
X853082Y450571D01*
X853165Y450238D01*
X853415Y450029D01*
X853707Y449904D01*
X854748D01*
G01X853707D02*
X853082Y448696D01*
G01X851607Y450779D02*
X851357Y451029D01*
X851065Y451154D01*
X850732Y451196D01*
X850315Y451113D01*
X850023Y450904D01*
X849940Y450654D01*
X849982Y450404D01*
X850148Y450196D01*
X850982Y449779D01*
X851357Y449488D01*
X851607Y449071D01*
X851690Y448696D01*
X849940D01*
G01X848632Y449071D02*
X848382Y448863D01*
X848090Y448738D01*
X847715Y448696D01*
X847340Y448779D01*
X847048Y448946D01*
X846840Y449238D01*
X846798Y449571D01*
X846882Y449904D01*
X847090Y450113D01*
X847382Y450279D01*
X847673Y450321D01*
X847965Y450279D01*
X848340Y450113D01*
X848215Y451196D01*
X847090D01*
G01X845865D02*
X845282Y448696D01*
X844615Y451196D01*
X843948Y448696D01*
X843365Y451196D01*
G01X841515Y448696D02*
Y451196D01*
X842015Y450696D01*
G01Y448696D02*
X841015D01*
G01X838415Y451196D02*
X838748Y451113D01*
X838998Y450904D01*
X839165Y450654D01*
X839290Y450321D01*
X839332Y449946D01*
X839290Y449571D01*
X839165Y449238D01*
X838998Y448988D01*
X838748Y448779D01*
X838415Y448696D01*
X838082Y448779D01*
X837832Y448988D01*
X837665Y449238D01*
X837540Y449571D01*
X837498Y449946D01*
X837540Y450321D01*
X837665Y450654D01*
X837832Y450904D01*
X838082Y451113D01*
X838415Y451196D01*
G01X836023Y448988D02*
X835732Y448779D01*
X835398Y448696D01*
X835065Y448779D01*
X834773Y449029D01*
X834565Y449404D01*
X834482Y449779D01*
Y450238D01*
X834565Y450613D01*
X834773Y450946D01*
X835023Y451113D01*
X835315Y451196D01*
X835648Y451113D01*
X835898Y450946D01*
X836065Y450696D01*
X836148Y450363D01*
X836065Y450071D01*
X835857Y449779D01*
X835607Y449613D01*
X835315Y449571D01*
X834982Y449654D01*
X834732Y449863D01*
X834482Y450238D01*
G01X854758Y445101D02*
Y447601D01*
X853717D01*
X853383Y447476D01*
X853175Y447309D01*
X853092Y446976D01*
X853175Y446643D01*
X853425Y446434D01*
X853717Y446309D01*
X854758D01*
G01X853717D02*
X853092Y445101D01*
G01X851617Y447184D02*
X851367Y447434D01*
X851075Y447559D01*
X850742Y447601D01*
X850325Y447518D01*
X850033Y447309D01*
X849950Y447059D01*
X849992Y446809D01*
X850158Y446601D01*
X850992Y446184D01*
X851367Y445893D01*
X851617Y445476D01*
X851700Y445101D01*
X849950D01*
G01X848642Y445476D02*
X848392Y445268D01*
X848100Y445143D01*
X847725Y445101D01*
X847350Y445184D01*
X847058Y445351D01*
X846850Y445643D01*
X846808Y445976D01*
X846892Y446309D01*
X847100Y446518D01*
X847392Y446684D01*
X847683Y446726D01*
X847975Y446684D01*
X848350Y446518D01*
X848225Y447601D01*
X847100D01*
G01X845875D02*
X845292Y445101D01*
X844625Y447601D01*
X843958Y445101D01*
X843375Y447601D01*
G01X842442Y445476D02*
X842192Y445268D01*
X841900Y445143D01*
X841525Y445101D01*
X841150Y445184D01*
X840858Y445351D01*
X840650Y445643D01*
X840608Y445976D01*
X840692Y446309D01*
X840900Y446518D01*
X841192Y446684D01*
X841483Y446726D01*
X841775Y446684D01*
X842150Y446518D01*
X842025Y447601D01*
X840900D01*
G01X839133Y445393D02*
X838842Y445184D01*
X838508Y445101D01*
X838175Y445184D01*
X837883Y445434D01*
X837675Y445809D01*
X837592Y446184D01*
Y446643D01*
X837675Y447018D01*
X837883Y447351D01*
X838133Y447518D01*
X838425Y447601D01*
X838758Y447518D01*
X839008Y447351D01*
X839175Y447101D01*
X839258Y446768D01*
X839175Y446476D01*
X838967Y446184D01*
X838717Y446018D01*
X838425Y445976D01*
X838092Y446059D01*
X837842Y446268D01*
X837592Y446643D01*
G01X856093Y464543D02*
Y467043D01*
X855052D01*
X854718Y466918D01*
X854510Y466751D01*
X854427Y466418D01*
X854510Y466085D01*
X854760Y465876D01*
X855052Y465751D01*
X856093D01*
G01X855052D02*
X854427Y464543D01*
G01X852952Y466626D02*
X852702Y466876D01*
X852410Y467001D01*
X852077Y467043D01*
X851660Y466960D01*
X851368Y466751D01*
X851285Y466501D01*
X851327Y466251D01*
X851493Y466043D01*
X852327Y465626D01*
X852702Y465335D01*
X852952Y464918D01*
X853035Y464543D01*
X851285D01*
G01X849977Y464918D02*
X849727Y464710D01*
X849435Y464585D01*
X849060Y464543D01*
X848685Y464626D01*
X848393Y464793D01*
X848185Y465085D01*
X848143Y465418D01*
X848227Y465751D01*
X848435Y465960D01*
X848727Y466126D01*
X849018Y466168D01*
X849310Y466126D01*
X849685Y465960D01*
X849560Y467043D01*
X848435D01*
G01X847210D02*
X846627Y464543D01*
X845960Y467043D01*
X845293Y464543D01*
X844710Y467043D01*
G01X842860Y464543D02*
Y467043D01*
X843360Y466543D01*
G01Y464543D02*
X842360D01*
G01X840677Y464918D02*
X840427Y464710D01*
X840135Y464585D01*
X839760Y464543D01*
X839385Y464626D01*
X839093Y464793D01*
X838885Y465085D01*
X838843Y465418D01*
X838927Y465751D01*
X839135Y465960D01*
X839427Y466126D01*
X839718Y466168D01*
X840010Y466126D01*
X840385Y465960D01*
X840260Y467043D01*
X839135D01*
G01X837452Y466626D02*
X837202Y466876D01*
X836910Y467001D01*
X836577Y467043D01*
X836160Y466960D01*
X835868Y466751D01*
X835785Y466501D01*
X835827Y466251D01*
X835993Y466043D01*
X836827Y465626D01*
X837202Y465335D01*
X837452Y464918D01*
X837535Y464543D01*
X835785D01*
G01X842346Y460864D02*
Y463364D01*
X841305D01*
X840971Y463239D01*
X840763Y463072D01*
X840680Y462739D01*
X840763Y462406D01*
X841013Y462197D01*
X841305Y462072D01*
X842346D01*
G01X841305D02*
X840680Y460864D01*
G01X839205Y462947D02*
X838955Y463197D01*
X838663Y463322D01*
X838330Y463364D01*
X837913Y463281D01*
X837621Y463072D01*
X837538Y462822D01*
X837580Y462572D01*
X837746Y462364D01*
X838580Y461947D01*
X838955Y461656D01*
X839205Y461239D01*
X839288Y460864D01*
X837538D01*
G01X836230Y461239D02*
X835980Y461031D01*
X835688Y460906D01*
X835313Y460864D01*
X834938Y460947D01*
X834646Y461114D01*
X834438Y461406D01*
X834396Y461739D01*
X834480Y462072D01*
X834688Y462281D01*
X834980Y462447D01*
X835271Y462489D01*
X835563Y462447D01*
X835938Y462281D01*
X835813Y463364D01*
X834688D01*
G01X833463D02*
X832880Y460864D01*
X832213Y463364D01*
X831546Y460864D01*
X830963Y463364D01*
G01X829113Y460864D02*
Y463364D01*
X829613Y462864D01*
G01Y460864D02*
X828613D01*
G01X826013D02*
Y463364D01*
X826513Y462864D01*
G01Y460864D02*
X825513D01*
G01X823830Y461239D02*
X823580Y461031D01*
X823288Y460906D01*
X822913Y460864D01*
X822538Y460947D01*
X822246Y461114D01*
X822038Y461406D01*
X821996Y461739D01*
X822080Y462072D01*
X822288Y462281D01*
X822580Y462447D01*
X822871Y462489D01*
X823163Y462447D01*
X823538Y462281D01*
X823413Y463364D01*
X822288D01*
G01X809685Y464440D02*
Y466940D01*
X808644D01*
X808310Y466815D01*
X808102Y466648D01*
X808019Y466315D01*
X808102Y465982D01*
X808352Y465773D01*
X808644Y465648D01*
X809685D01*
G01X808644D02*
X808019Y464440D01*
G01X806544Y466523D02*
X806294Y466773D01*
X806002Y466898D01*
X805669Y466940D01*
X805252Y466857D01*
X804960Y466648D01*
X804877Y466398D01*
X804919Y466148D01*
X805085Y465940D01*
X805919Y465523D01*
X806294Y465232D01*
X806544Y464815D01*
X806627Y464440D01*
X804877D01*
G01X803569Y464815D02*
X803319Y464607D01*
X803027Y464482D01*
X802652Y464440D01*
X802277Y464523D01*
X801985Y464690D01*
X801777Y464982D01*
X801735Y465315D01*
X801819Y465648D01*
X802027Y465857D01*
X802319Y466023D01*
X802610Y466065D01*
X802902Y466023D01*
X803277Y465857D01*
X803152Y466940D01*
X802027D01*
G01X800802D02*
X800219Y464440D01*
X799552Y466940D01*
X798885Y464440D01*
X798302Y466940D01*
G01X796452Y464440D02*
Y466940D01*
X796952Y466440D01*
G01Y464440D02*
X795952D01*
G01X793352Y466940D02*
X793685Y466857D01*
X793935Y466648D01*
X794102Y466398D01*
X794227Y466065D01*
X794269Y465690D01*
X794227Y465315D01*
X794102Y464982D01*
X793935Y464732D01*
X793685Y464523D01*
X793352Y464440D01*
X793019Y464523D01*
X792769Y464732D01*
X792602Y464982D01*
X792477Y465315D01*
X792435Y465690D01*
X792477Y466065D01*
X792602Y466398D01*
X792769Y466648D01*
X793019Y466857D01*
X793352Y466940D01*
G01X791169Y464815D02*
X790919Y464607D01*
X790627Y464482D01*
X790252Y464440D01*
X789877Y464523D01*
X789585Y464690D01*
X789377Y464982D01*
X789335Y465315D01*
X789419Y465648D01*
X789627Y465857D01*
X789919Y466023D01*
X790210Y466065D01*
X790502Y466023D01*
X790877Y465857D01*
X790752Y466940D01*
X789627D01*
G01X809685Y460440D02*
Y462940D01*
X808644D01*
X808310Y462815D01*
X808102Y462648D01*
X808019Y462315D01*
X808102Y461982D01*
X808352Y461773D01*
X808644Y461648D01*
X809685D01*
G01X808644D02*
X808019Y460440D01*
G01X806544Y462523D02*
X806294Y462773D01*
X806002Y462898D01*
X805669Y462940D01*
X805252Y462857D01*
X804960Y462648D01*
X804877Y462398D01*
X804919Y462148D01*
X805085Y461940D01*
X805919Y461523D01*
X806294Y461232D01*
X806544Y460815D01*
X806627Y460440D01*
X804877D01*
G01X803569Y460815D02*
X803319Y460607D01*
X803027Y460482D01*
X802652Y460440D01*
X802277Y460523D01*
X801985Y460690D01*
X801777Y460982D01*
X801735Y461315D01*
X801819Y461648D01*
X802027Y461857D01*
X802319Y462023D01*
X802610Y462065D01*
X802902Y462023D01*
X803277Y461857D01*
X803152Y462940D01*
X802027D01*
G01X800802D02*
X800219Y460440D01*
X799552Y462940D01*
X798885Y460440D01*
X798302Y462940D01*
G01X796452Y460440D02*
Y462940D01*
X796952Y462440D01*
G01Y460440D02*
X795952D01*
G01X793352Y462940D02*
X793685Y462857D01*
X793935Y462648D01*
X794102Y462398D01*
X794227Y462065D01*
X794269Y461690D01*
X794227Y461315D01*
X794102Y460982D01*
X793935Y460732D01*
X793685Y460523D01*
X793352Y460440D01*
X793019Y460523D01*
X792769Y460732D01*
X792602Y460982D01*
X792477Y461315D01*
X792435Y461690D01*
X792477Y462065D01*
X792602Y462398D01*
X792769Y462648D01*
X793019Y462857D01*
X793352Y462940D01*
G01X790335Y460440D02*
X790252Y460982D01*
X790127Y461440D01*
X789960Y461857D01*
X789752Y462315D01*
X789419Y462940D01*
X791085D01*
G01X842380Y456783D02*
Y459283D01*
X841339D01*
X841005Y459158D01*
X840797Y458991D01*
X840714Y458658D01*
X840797Y458325D01*
X841047Y458116D01*
X841339Y457991D01*
X842380D01*
G01X841339D02*
X840714Y456783D01*
G01X839239Y458866D02*
X838989Y459116D01*
X838697Y459241D01*
X838364Y459283D01*
X837947Y459200D01*
X837655Y458991D01*
X837572Y458741D01*
X837614Y458491D01*
X837780Y458283D01*
X838614Y457866D01*
X838989Y457575D01*
X839239Y457158D01*
X839322Y456783D01*
X837572D01*
G01X836264Y457158D02*
X836014Y456950D01*
X835722Y456825D01*
X835347Y456783D01*
X834972Y456866D01*
X834680Y457033D01*
X834472Y457325D01*
X834430Y457658D01*
X834514Y457991D01*
X834722Y458200D01*
X835014Y458366D01*
X835305Y458408D01*
X835597Y458366D01*
X835972Y458200D01*
X835847Y459283D01*
X834722D01*
G01X833497D02*
X832914Y456783D01*
X832247Y459283D01*
X831580Y456783D01*
X830997Y459283D01*
G01X829147Y456783D02*
Y459283D01*
X829647Y458783D01*
G01Y456783D02*
X828647D01*
G01X826047D02*
Y459283D01*
X826547Y458783D01*
G01Y456783D02*
X825547D01*
G01X822447D02*
Y459283D01*
X823989Y457491D01*
X821905D01*
G01X841280Y452783D02*
Y455283D01*
X840239D01*
X839905Y455158D01*
X839697Y454991D01*
X839614Y454658D01*
X839697Y454325D01*
X839947Y454116D01*
X840239Y453991D01*
X841280D01*
G01X840239D02*
X839614Y452783D01*
G01X838139Y454866D02*
X837889Y455116D01*
X837597Y455241D01*
X837264Y455283D01*
X836847Y455200D01*
X836555Y454991D01*
X836472Y454741D01*
X836514Y454491D01*
X836680Y454283D01*
X837514Y453866D01*
X837889Y453575D01*
X838139Y453158D01*
X838222Y452783D01*
X836472D01*
G01X835164Y453158D02*
X834914Y452950D01*
X834622Y452825D01*
X834247Y452783D01*
X833872Y452866D01*
X833580Y453033D01*
X833372Y453325D01*
X833330Y453658D01*
X833414Y453991D01*
X833622Y454200D01*
X833914Y454366D01*
X834205Y454408D01*
X834497Y454366D01*
X834872Y454200D01*
X834747Y455283D01*
X833622D01*
G01X832397D02*
X831814Y452783D01*
X831147Y455283D01*
X830480Y452783D01*
X829897Y455283D01*
G01X828047Y452783D02*
Y455283D01*
X828547Y454783D01*
G01Y452783D02*
X827547D01*
G01X824947D02*
Y455283D01*
X825447Y454783D01*
G01Y452783D02*
X824447D01*
G01X821847Y455283D02*
X822180Y455200D01*
X822430Y454991D01*
X822597Y454741D01*
X822722Y454408D01*
X822764Y454033D01*
X822722Y453658D01*
X822597Y453325D01*
X822430Y453075D01*
X822180Y452866D01*
X821847Y452783D01*
X821514Y452866D01*
X821264Y453075D01*
X821097Y453325D01*
X820972Y453658D01*
X820930Y454033D01*
X820972Y454408D01*
X821097Y454741D01*
X821264Y454991D01*
X821514Y455200D01*
X821847Y455283D01*
G01X811529Y437445D02*
X814029D01*
Y438486D01*
X813904Y438820D01*
X813737Y439028D01*
X813404Y439111D01*
X813071Y439028D01*
X812862Y438778D01*
X812737Y438486D01*
Y437445D01*
G01Y438486D02*
X811529Y439111D01*
G01X813612Y440586D02*
X813862Y440836D01*
X813987Y441128D01*
X814029Y441461D01*
X813946Y441878D01*
X813737Y442170D01*
X813487Y442253D01*
X813237Y442211D01*
X813029Y442045D01*
X812612Y441211D01*
X812321Y440836D01*
X811904Y440586D01*
X811529Y440503D01*
Y442253D01*
G01X811904Y443561D02*
X811696Y443811D01*
X811571Y444103D01*
X811529Y444478D01*
X811612Y444853D01*
X811779Y445145D01*
X812071Y445353D01*
X812404Y445395D01*
X812737Y445311D01*
X812946Y445103D01*
X813112Y444811D01*
X813154Y444520D01*
X813112Y444228D01*
X812946Y443853D01*
X814029Y443978D01*
Y445103D01*
G01Y446328D02*
X811529Y446911D01*
X814029Y447578D01*
X811529Y448245D01*
X814029Y448828D01*
G01X811529Y450678D02*
X814029D01*
X813529Y450178D01*
G01X811529D02*
Y451178D01*
G01X813612Y452986D02*
X813862Y453236D01*
X813987Y453528D01*
X814029Y453861D01*
X813946Y454278D01*
X813737Y454570D01*
X813487Y454653D01*
X813237Y454611D01*
X813029Y454445D01*
X812612Y453611D01*
X812321Y453236D01*
X811904Y452986D01*
X811529Y452903D01*
Y454653D01*
G01X814029Y456878D02*
X813946Y456545D01*
X813737Y456295D01*
X813487Y456128D01*
X813154Y456003D01*
X812779Y455961D01*
X812404Y456003D01*
X812071Y456128D01*
X811821Y456295D01*
X811612Y456545D01*
X811529Y456878D01*
X811612Y457211D01*
X811821Y457461D01*
X812071Y457628D01*
X812404Y457753D01*
X812779Y457795D01*
X813154Y457753D01*
X813487Y457628D01*
X813737Y457461D01*
X813946Y457211D01*
X814029Y456878D01*
G01X818184Y459731D02*
X818309Y459481D01*
X818392Y459189D01*
Y458856D01*
X818267Y458481D01*
X818059Y458189D01*
X817809Y457981D01*
X817392Y457814D01*
X817017Y457772D01*
X816642Y457856D01*
X816392Y457981D01*
X816142Y458231D01*
X815975Y458522D01*
X815892Y458814D01*
Y459106D01*
X815975Y459397D01*
X816100Y459647D01*
X816267Y459856D01*
G01X817975Y461122D02*
X818225Y461372D01*
X818350Y461664D01*
X818392Y461997D01*
X818309Y462414D01*
X818100Y462706D01*
X817850Y462789D01*
X817600Y462747D01*
X817392Y462581D01*
X816975Y461747D01*
X816684Y461372D01*
X816267Y461122D01*
X815892Y461039D01*
Y462789D01*
G01X816267Y464097D02*
X816059Y464347D01*
X815934Y464639D01*
X815892Y465014D01*
X815975Y465389D01*
X816142Y465681D01*
X816434Y465889D01*
X816767Y465931D01*
X817100Y465847D01*
X817309Y465639D01*
X817475Y465347D01*
X817517Y465056D01*
X817475Y464764D01*
X817309Y464389D01*
X818392Y464514D01*
Y465639D01*
G01Y466864D02*
X815892Y467447D01*
X818392Y468114D01*
X815892Y468781D01*
X818392Y469364D01*
G01X816392Y470297D02*
X816100Y470547D01*
X815934Y470881D01*
X815892Y471256D01*
X815934Y471589D01*
X816142Y471922D01*
X816392Y472131D01*
X816642Y472172D01*
X816934Y472089D01*
X817142Y471797D01*
X817225Y471506D01*
Y471131D01*
G01Y471506D02*
X817350Y471756D01*
X817559Y471964D01*
X817809Y472047D01*
X818059Y471964D01*
X818267Y471756D01*
X818392Y471381D01*
X818350Y471006D01*
X818184Y470631D01*
G01X816934Y473522D02*
X817225Y473814D01*
X817392Y474064D01*
X817475Y474397D01*
X817392Y474689D01*
X817225Y474897D01*
X816975Y475064D01*
X816684Y475106D01*
X816434Y475064D01*
X816184Y474897D01*
X815975Y474647D01*
X815892Y474356D01*
X815975Y474022D01*
X816225Y473731D01*
X816600Y473564D01*
X817017Y473522D01*
X817559Y473606D01*
X817850Y473731D01*
X818142Y473939D01*
X818350Y474231D01*
X818392Y474522D01*
X818309Y474814D01*
X818100Y475022D01*
G01X862648Y440376D02*
X862898Y440501D01*
X863190Y440584D01*
X863523D01*
X863898Y440459D01*
X864190Y440251D01*
X864398Y440001D01*
X864565Y439584D01*
X864607Y439209D01*
X864523Y438834D01*
X864398Y438584D01*
X864148Y438334D01*
X863857Y438167D01*
X863565Y438084D01*
X863273D01*
X862982Y438167D01*
X862732Y438292D01*
X862523Y438459D01*
G01X861257Y440167D02*
X861007Y440417D01*
X860715Y440542D01*
X860382Y440584D01*
X859965Y440501D01*
X859673Y440292D01*
X859590Y440042D01*
X859632Y439792D01*
X859798Y439584D01*
X860632Y439167D01*
X861007Y438876D01*
X861257Y438459D01*
X861340Y438084D01*
X859590D01*
G01X858282Y438459D02*
X858032Y438251D01*
X857740Y438126D01*
X857365Y438084D01*
X856990Y438167D01*
X856698Y438334D01*
X856490Y438626D01*
X856448Y438959D01*
X856532Y439292D01*
X856740Y439501D01*
X857032Y439667D01*
X857323Y439709D01*
X857615Y439667D01*
X857990Y439501D01*
X857865Y440584D01*
X856740D01*
G01X855515D02*
X854932Y438084D01*
X854265Y440584D01*
X853598Y438084D01*
X853015Y440584D01*
G01X851957Y439126D02*
X851665Y439417D01*
X851415Y439584D01*
X851082Y439667D01*
X850790Y439584D01*
X850582Y439417D01*
X850415Y439167D01*
X850373Y438876D01*
X850415Y438626D01*
X850582Y438376D01*
X850832Y438167D01*
X851123Y438084D01*
X851457Y438167D01*
X851748Y438417D01*
X851915Y438792D01*
X851957Y439209D01*
X851873Y439751D01*
X851748Y440042D01*
X851540Y440334D01*
X851248Y440542D01*
X850957Y440584D01*
X850665Y440501D01*
X850457Y440292D01*
G01X848773Y438376D02*
X848482Y438167D01*
X848148Y438084D01*
X847815Y438167D01*
X847523Y438417D01*
X847315Y438792D01*
X847232Y439167D01*
Y439626D01*
X847315Y440001D01*
X847523Y440334D01*
X847773Y440501D01*
X848065Y440584D01*
X848398Y440501D01*
X848648Y440334D01*
X848815Y440084D01*
X848898Y439751D01*
X848815Y439459D01*
X848607Y439167D01*
X848357Y439001D01*
X848065Y438959D01*
X847732Y439042D01*
X847482Y439251D01*
X847232Y439626D01*
G01X809821Y439195D02*
X809946Y438945D01*
X810029Y438653D01*
Y438320D01*
X809904Y437945D01*
X809696Y437653D01*
X809446Y437445D01*
X809029Y437278D01*
X808654Y437236D01*
X808279Y437320D01*
X808029Y437445D01*
X807779Y437695D01*
X807612Y437986D01*
X807529Y438278D01*
Y438570D01*
X807612Y438861D01*
X807737Y439111D01*
X807904Y439320D01*
G01X809612Y440586D02*
X809862Y440836D01*
X809987Y441128D01*
X810029Y441461D01*
X809946Y441878D01*
X809737Y442170D01*
X809487Y442253D01*
X809237Y442211D01*
X809029Y442045D01*
X808612Y441211D01*
X808321Y440836D01*
X807904Y440586D01*
X807529Y440503D01*
Y442253D01*
G01X807904Y443561D02*
X807696Y443811D01*
X807571Y444103D01*
X807529Y444478D01*
X807612Y444853D01*
X807779Y445145D01*
X808071Y445353D01*
X808404Y445395D01*
X808737Y445311D01*
X808946Y445103D01*
X809112Y444811D01*
X809154Y444520D01*
X809112Y444228D01*
X808946Y443853D01*
X810029Y443978D01*
Y445103D01*
G01Y446328D02*
X807529Y446911D01*
X810029Y447578D01*
X807529Y448245D01*
X810029Y448828D01*
G01X807529Y450595D02*
X808071Y450678D01*
X808529Y450803D01*
X808946Y450970D01*
X809404Y451178D01*
X810029Y451511D01*
Y449845D01*
G01Y453778D02*
X809946Y453445D01*
X809737Y453195D01*
X809487Y453028D01*
X809154Y452903D01*
X808779Y452861D01*
X808404Y452903D01*
X808071Y453028D01*
X807821Y453195D01*
X807612Y453445D01*
X807529Y453778D01*
X807612Y454111D01*
X807821Y454361D01*
X808071Y454528D01*
X808404Y454653D01*
X808779Y454695D01*
X809154Y454653D01*
X809487Y454528D01*
X809737Y454361D01*
X809946Y454111D01*
X810029Y453778D01*
G01X810446Y423372D02*
X810571Y423122D01*
X810654Y422830D01*
Y422497D01*
X810529Y422122D01*
X810321Y421830D01*
X810071Y421622D01*
X809654Y421455D01*
X809279Y421413D01*
X808904Y421497D01*
X808654Y421622D01*
X808404Y421872D01*
X808237Y422163D01*
X808154Y422455D01*
Y422747D01*
X808237Y423038D01*
X808362Y423288D01*
X808529Y423497D01*
G01X808446Y424847D02*
X808237Y425138D01*
X808154Y425472D01*
X808237Y425805D01*
X808487Y426097D01*
X808862Y426305D01*
X809237Y426388D01*
X809696D01*
X810071Y426305D01*
X810404Y426097D01*
X810571Y425847D01*
X810654Y425555D01*
X810571Y425222D01*
X810404Y424972D01*
X810154Y424805D01*
X809821Y424722D01*
X809529Y424805D01*
X809237Y425013D01*
X809071Y425263D01*
X809029Y425555D01*
X809112Y425888D01*
X809321Y426138D01*
X809696Y426388D01*
G01X809404Y428905D02*
Y429738D01*
X808654D01*
X808404Y429488D01*
X808237Y429197D01*
X808154Y428780D01*
X808237Y428363D01*
X808404Y428072D01*
X808654Y427822D01*
X808946Y427655D01*
X809279Y427572D01*
X809571D01*
X809821Y427655D01*
X810112Y427822D01*
X810362Y428072D01*
X810529Y428322D01*
X810654Y428655D01*
Y428947D01*
X810571Y429280D01*
X810404Y429530D01*
G01X808154Y431755D02*
X810654D01*
X810154Y431255D01*
G01X808154D02*
Y432255D01*
G01Y434772D02*
X808696Y434855D01*
X809154Y434980D01*
X809571Y435147D01*
X810029Y435355D01*
X810654Y435688D01*
Y434022D01*
G01X829540Y423963D02*
X829790Y424088D01*
X830082Y424171D01*
X830415D01*
X830790Y424046D01*
X831082Y423838D01*
X831290Y423588D01*
X831457Y423171D01*
X831499Y422796D01*
X831415Y422421D01*
X831290Y422171D01*
X831040Y421921D01*
X830749Y421754D01*
X830457Y421671D01*
X830165D01*
X829874Y421754D01*
X829624Y421879D01*
X829415Y422046D01*
G01X828065Y421963D02*
X827774Y421754D01*
X827440Y421671D01*
X827107Y421754D01*
X826815Y422004D01*
X826607Y422379D01*
X826524Y422754D01*
Y423213D01*
X826607Y423588D01*
X826815Y423921D01*
X827065Y424088D01*
X827357Y424171D01*
X827690Y424088D01*
X827940Y423921D01*
X828107Y423671D01*
X828190Y423338D01*
X828107Y423046D01*
X827899Y422754D01*
X827649Y422588D01*
X827357Y422546D01*
X827024Y422629D01*
X826774Y422838D01*
X826524Y423213D01*
G01X824007Y422921D02*
X823174D01*
Y422171D01*
X823424Y421921D01*
X823715Y421754D01*
X824132Y421671D01*
X824549Y421754D01*
X824840Y421921D01*
X825090Y422171D01*
X825257Y422463D01*
X825340Y422796D01*
Y423088D01*
X825257Y423338D01*
X825090Y423629D01*
X824840Y423879D01*
X824590Y424046D01*
X824257Y424171D01*
X823965D01*
X823632Y424088D01*
X823382Y423921D01*
G01X821949Y423754D02*
X821699Y424004D01*
X821407Y424129D01*
X821074Y424171D01*
X820657Y424088D01*
X820365Y423879D01*
X820282Y423629D01*
X820324Y423379D01*
X820490Y423171D01*
X821324Y422754D01*
X821699Y422463D01*
X821949Y422046D01*
X822032Y421671D01*
X820282D01*
G01X818057D02*
Y424171D01*
X818557Y423671D01*
G01Y421671D02*
X817557D01*
G01X823946Y437821D02*
X824071Y437571D01*
X824154Y437279D01*
Y436946D01*
X824029Y436571D01*
X823821Y436279D01*
X823571Y436071D01*
X823154Y435904D01*
X822779Y435862D01*
X822404Y435946D01*
X822154Y436071D01*
X821904Y436321D01*
X821737Y436612D01*
X821654Y436904D01*
Y437196D01*
X821737Y437487D01*
X821862Y437737D01*
X822029Y437946D01*
G01X821946Y439296D02*
X821737Y439587D01*
X821654Y439921D01*
X821737Y440254D01*
X821987Y440546D01*
X822362Y440754D01*
X822737Y440837D01*
X823196D01*
X823571Y440754D01*
X823904Y440546D01*
X824071Y440296D01*
X824154Y440004D01*
X824071Y439671D01*
X823904Y439421D01*
X823654Y439254D01*
X823321Y439171D01*
X823029Y439254D01*
X822737Y439462D01*
X822571Y439712D01*
X822529Y440004D01*
X822612Y440337D01*
X822821Y440587D01*
X823196Y440837D01*
G01X822904Y443354D02*
Y444187D01*
X822154D01*
X821904Y443937D01*
X821737Y443646D01*
X821654Y443229D01*
X821737Y442812D01*
X821904Y442521D01*
X822154Y442271D01*
X822446Y442104D01*
X822779Y442021D01*
X823071D01*
X823321Y442104D01*
X823612Y442271D01*
X823862Y442521D01*
X824029Y442771D01*
X824154Y443104D01*
Y443396D01*
X824071Y443729D01*
X823904Y443979D01*
G01X823737Y445412D02*
X823987Y445662D01*
X824112Y445954D01*
X824154Y446287D01*
X824071Y446704D01*
X823862Y446996D01*
X823612Y447079D01*
X823362Y447037D01*
X823154Y446871D01*
X822737Y446037D01*
X822446Y445662D01*
X822029Y445412D01*
X821654Y445329D01*
Y447079D01*
G01X824154Y449304D02*
X824071Y448971D01*
X823862Y448721D01*
X823612Y448554D01*
X823279Y448429D01*
X822904Y448387D01*
X822529Y448429D01*
X822196Y448554D01*
X821946Y448721D01*
X821737Y448971D01*
X821654Y449304D01*
X821737Y449637D01*
X821946Y449887D01*
X822196Y450054D01*
X822529Y450179D01*
X822904Y450221D01*
X823279Y450179D01*
X823612Y450054D01*
X823862Y449887D01*
X824071Y449637D01*
X824154Y449304D01*
G01X862648Y433876D02*
X862898Y434001D01*
X863190Y434084D01*
X863523D01*
X863898Y433959D01*
X864190Y433751D01*
X864398Y433501D01*
X864565Y433084D01*
X864607Y432709D01*
X864523Y432334D01*
X864398Y432084D01*
X864148Y431834D01*
X863857Y431667D01*
X863565Y431584D01*
X863273D01*
X862982Y431667D01*
X862732Y431792D01*
X862523Y431959D01*
G01X861257Y433667D02*
X861007Y433917D01*
X860715Y434042D01*
X860382Y434084D01*
X859965Y434001D01*
X859673Y433792D01*
X859590Y433542D01*
X859632Y433292D01*
X859798Y433084D01*
X860632Y432667D01*
X861007Y432376D01*
X861257Y431959D01*
X861340Y431584D01*
X859590D01*
G01X858282Y431959D02*
X858032Y431751D01*
X857740Y431626D01*
X857365Y431584D01*
X856990Y431667D01*
X856698Y431834D01*
X856490Y432126D01*
X856448Y432459D01*
X856532Y432792D01*
X856740Y433001D01*
X857032Y433167D01*
X857323Y433209D01*
X857615Y433167D01*
X857990Y433001D01*
X857865Y434084D01*
X856740D01*
G01X855515D02*
X854932Y431584D01*
X854265Y434084D01*
X853598Y431584D01*
X853015Y434084D01*
G01X851957Y432626D02*
X851665Y432917D01*
X851415Y433084D01*
X851082Y433167D01*
X850790Y433084D01*
X850582Y432917D01*
X850415Y432667D01*
X850373Y432376D01*
X850415Y432126D01*
X850582Y431876D01*
X850832Y431667D01*
X851123Y431584D01*
X851457Y431667D01*
X851748Y431917D01*
X851915Y432292D01*
X851957Y432709D01*
X851873Y433251D01*
X851748Y433542D01*
X851540Y433834D01*
X851248Y434042D01*
X850957Y434084D01*
X850665Y434001D01*
X850457Y433792D01*
G01X848065Y434084D02*
X848398Y434001D01*
X848648Y433792D01*
X848815Y433542D01*
X848940Y433209D01*
X848982Y432834D01*
X848940Y432459D01*
X848815Y432126D01*
X848648Y431876D01*
X848398Y431667D01*
X848065Y431584D01*
X847732Y431667D01*
X847482Y431876D01*
X847315Y432126D01*
X847190Y432459D01*
X847148Y432834D01*
X847190Y433209D01*
X847315Y433542D01*
X847482Y433792D01*
X847732Y434001D01*
X848065Y434084D01*
G01X806235Y439232D02*
X806360Y438982D01*
X806443Y438690D01*
Y438357D01*
X806318Y437982D01*
X806110Y437690D01*
X805860Y437482D01*
X805443Y437315D01*
X805068Y437273D01*
X804693Y437357D01*
X804443Y437482D01*
X804193Y437732D01*
X804026Y438023D01*
X803943Y438315D01*
Y438607D01*
X804026Y438898D01*
X804151Y439148D01*
X804318Y439357D01*
G01X806026Y440623D02*
X806276Y440873D01*
X806401Y441165D01*
X806443Y441498D01*
X806360Y441915D01*
X806151Y442207D01*
X805901Y442290D01*
X805651Y442248D01*
X805443Y442082D01*
X805026Y441248D01*
X804735Y440873D01*
X804318Y440623D01*
X803943Y440540D01*
Y442290D01*
G01X804318Y443598D02*
X804110Y443848D01*
X803985Y444140D01*
X803943Y444515D01*
X804026Y444890D01*
X804193Y445182D01*
X804485Y445390D01*
X804818Y445432D01*
X805151Y445348D01*
X805360Y445140D01*
X805526Y444848D01*
X805568Y444557D01*
X805526Y444265D01*
X805360Y443890D01*
X806443Y444015D01*
Y445140D01*
G01Y446365D02*
X803943Y446948D01*
X806443Y447615D01*
X803943Y448282D01*
X806443Y448865D01*
G01X803943Y450632D02*
X804485Y450715D01*
X804943Y450840D01*
X805360Y451007D01*
X805818Y451215D01*
X806443Y451548D01*
Y449882D01*
G01X803943Y453815D02*
X806443D01*
X805943Y453315D01*
G01X803943D02*
Y454315D01*
G01X800182Y405363D02*
X822757D01*
G01X812154Y421622D02*
X814654D01*
Y422663D01*
X814529Y422997D01*
X814362Y423205D01*
X814029Y423288D01*
X813696Y423205D01*
X813487Y422955D01*
X813362Y422663D01*
Y421622D01*
G01Y422663D02*
X812154Y423288D01*
G01Y425555D02*
X814654D01*
X814154Y425055D01*
G01X812154D02*
Y426055D01*
G01X814654Y427738D02*
X812862D01*
X812487Y427905D01*
X812237Y428238D01*
X812154Y428655D01*
X812237Y429072D01*
X812487Y429405D01*
X812862Y429572D01*
X814654D01*
G01X812654Y430838D02*
X812362Y431088D01*
X812196Y431422D01*
X812154Y431797D01*
X812196Y432130D01*
X812404Y432463D01*
X812654Y432672D01*
X812904Y432713D01*
X813196Y432630D01*
X813404Y432338D01*
X813487Y432047D01*
Y431672D01*
G01Y432047D02*
X813612Y432297D01*
X813821Y432505D01*
X814071Y432588D01*
X814321Y432505D01*
X814529Y432297D01*
X814654Y431922D01*
X814612Y431547D01*
X814446Y431172D01*
G01X812654Y433938D02*
X812362Y434188D01*
X812196Y434522D01*
X812154Y434897D01*
X812196Y435230D01*
X812404Y435563D01*
X812654Y435772D01*
X812904Y435813D01*
X813196Y435730D01*
X813404Y435438D01*
X813487Y435147D01*
Y434772D01*
G01Y435147D02*
X813612Y435397D01*
X813821Y435605D01*
X814071Y435688D01*
X814321Y435605D01*
X814529Y435397D01*
X814654Y435022D01*
X814612Y434647D01*
X814446Y434272D01*
G01X808532Y527283D02*
Y529783D01*
X807491D01*
X807157Y529658D01*
X806949Y529491D01*
X806866Y529158D01*
X806949Y528825D01*
X807199Y528616D01*
X807491Y528491D01*
X808532D01*
G01X807491D02*
X806866Y527283D01*
G01X805391Y528325D02*
X805099Y528616D01*
X804849Y528783D01*
X804516Y528866D01*
X804224Y528783D01*
X804016Y528616D01*
X803849Y528366D01*
X803807Y528075D01*
X803849Y527825D01*
X804016Y527575D01*
X804266Y527366D01*
X804557Y527283D01*
X804891Y527366D01*
X805182Y527616D01*
X805349Y527991D01*
X805391Y528408D01*
X805307Y528950D01*
X805182Y529241D01*
X804974Y529533D01*
X804682Y529741D01*
X804391Y529783D01*
X804099Y529700D01*
X803891Y529491D01*
G01X802582Y527283D02*
Y529783D01*
X801499Y527700D01*
X800416Y529783D01*
Y527283D01*
G01X798399D02*
Y529783D01*
X798899Y529283D01*
G01Y527283D02*
X797899D01*
G01X810038Y492370D02*
Y494870D01*
X808997D01*
X808663Y494745D01*
X808455Y494578D01*
X808372Y494245D01*
X808455Y493912D01*
X808705Y493703D01*
X808997Y493578D01*
X810038D01*
G01X808997D02*
X808372Y492370D01*
G01X806897Y494453D02*
X806647Y494703D01*
X806355Y494828D01*
X806022Y494870D01*
X805605Y494787D01*
X805313Y494578D01*
X805230Y494328D01*
X805272Y494078D01*
X805438Y493870D01*
X806272Y493453D01*
X806647Y493162D01*
X806897Y492745D01*
X806980Y492370D01*
X805230D01*
G01X803922Y492745D02*
X803672Y492537D01*
X803380Y492412D01*
X803005Y492370D01*
X802630Y492453D01*
X802338Y492620D01*
X802130Y492912D01*
X802088Y493245D01*
X802172Y493578D01*
X802380Y493787D01*
X802672Y493953D01*
X802963Y493995D01*
X803255Y493953D01*
X803630Y493787D01*
X803505Y494870D01*
X802380D01*
G01X801155D02*
X800572Y492370D01*
X799905Y494870D01*
X799238Y492370D01*
X798655Y494870D01*
G01X796888Y492370D02*
X796805Y492912D01*
X796680Y493370D01*
X796513Y493787D01*
X796305Y494245D01*
X795972Y494870D01*
X797638D01*
G01X794622Y492745D02*
X794372Y492537D01*
X794080Y492412D01*
X793705Y492370D01*
X793330Y492453D01*
X793038Y492620D01*
X792830Y492912D01*
X792788Y493245D01*
X792872Y493578D01*
X793080Y493787D01*
X793372Y493953D01*
X793663Y493995D01*
X793955Y493953D01*
X794330Y493787D01*
X794205Y494870D01*
X793080D01*
G01X810038Y480370D02*
Y482870D01*
X808997D01*
X808663Y482745D01*
X808455Y482578D01*
X808372Y482245D01*
X808455Y481912D01*
X808705Y481703D01*
X808997Y481578D01*
X810038D01*
G01X808997D02*
X808372Y480370D01*
G01X806897Y482453D02*
X806647Y482703D01*
X806355Y482828D01*
X806022Y482870D01*
X805605Y482787D01*
X805313Y482578D01*
X805230Y482328D01*
X805272Y482078D01*
X805438Y481870D01*
X806272Y481453D01*
X806647Y481162D01*
X806897Y480745D01*
X806980Y480370D01*
X805230D01*
G01X803922Y482870D02*
Y481078D01*
X803755Y480703D01*
X803422Y480453D01*
X803005Y480370D01*
X802588Y480453D01*
X802255Y480703D01*
X802088Y481078D01*
Y482870D01*
G01X800822Y480745D02*
X800572Y480537D01*
X800280Y480412D01*
X799905Y480370D01*
X799530Y480453D01*
X799238Y480620D01*
X799030Y480912D01*
X798988Y481245D01*
X799072Y481578D01*
X799280Y481787D01*
X799572Y481953D01*
X799863Y481995D01*
X800155Y481953D01*
X800530Y481787D01*
X800405Y482870D01*
X799280D01*
G01X810038Y476370D02*
Y478870D01*
X808997D01*
X808663Y478745D01*
X808455Y478578D01*
X808372Y478245D01*
X808455Y477912D01*
X808705Y477703D01*
X808997Y477578D01*
X810038D01*
G01X808997D02*
X808372Y476370D01*
G01X806897Y478453D02*
X806647Y478703D01*
X806355Y478828D01*
X806022Y478870D01*
X805605Y478787D01*
X805313Y478578D01*
X805230Y478328D01*
X805272Y478078D01*
X805438Y477870D01*
X806272Y477453D01*
X806647Y477162D01*
X806897Y476745D01*
X806980Y476370D01*
X805230D01*
G01X803922Y478870D02*
Y477078D01*
X803755Y476703D01*
X803422Y476453D01*
X803005Y476370D01*
X802588Y476453D01*
X802255Y476703D01*
X802088Y477078D01*
Y478870D01*
G01X799988Y476370D02*
X799905Y476912D01*
X799780Y477370D01*
X799613Y477787D01*
X799405Y478245D01*
X799072Y478870D01*
X800738D01*
G01X810038Y468370D02*
Y470870D01*
X808997D01*
X808663Y470745D01*
X808455Y470578D01*
X808372Y470245D01*
X808455Y469912D01*
X808705Y469703D01*
X808997Y469578D01*
X810038D01*
G01X808997D02*
X808372Y468370D01*
G01X806897Y470453D02*
X806647Y470703D01*
X806355Y470828D01*
X806022Y470870D01*
X805605Y470787D01*
X805313Y470578D01*
X805230Y470328D01*
X805272Y470078D01*
X805438Y469870D01*
X806272Y469453D01*
X806647Y469162D01*
X806897Y468745D01*
X806980Y468370D01*
X805230D01*
G01X803922Y470870D02*
Y469078D01*
X803755Y468703D01*
X803422Y468453D01*
X803005Y468370D01*
X802588Y468453D01*
X802255Y468703D01*
X802088Y469078D01*
Y470870D01*
G01X799905Y468370D02*
Y470870D01*
X800405Y470370D01*
G01Y468370D02*
X799405D01*
G01X797722Y468870D02*
X797472Y468578D01*
X797138Y468412D01*
X796763Y468370D01*
X796430Y468412D01*
X796097Y468620D01*
X795888Y468870D01*
X795847Y469120D01*
X795930Y469412D01*
X796222Y469620D01*
X796513Y469703D01*
X796888D01*
G01X796513D02*
X796263Y469828D01*
X796055Y470037D01*
X795972Y470287D01*
X796055Y470537D01*
X796263Y470745D01*
X796638Y470870D01*
X797013Y470828D01*
X797388Y470662D01*
G01X810038Y472370D02*
Y474870D01*
X808997D01*
X808663Y474745D01*
X808455Y474578D01*
X808372Y474245D01*
X808455Y473912D01*
X808705Y473703D01*
X808997Y473578D01*
X810038D01*
G01X808997D02*
X808372Y472370D01*
G01X806897Y474453D02*
X806647Y474703D01*
X806355Y474828D01*
X806022Y474870D01*
X805605Y474787D01*
X805313Y474578D01*
X805230Y474328D01*
X805272Y474078D01*
X805438Y473870D01*
X806272Y473453D01*
X806647Y473162D01*
X806897Y472745D01*
X806980Y472370D01*
X805230D01*
G01X803922Y474870D02*
Y473078D01*
X803755Y472703D01*
X803422Y472453D01*
X803005Y472370D01*
X802588Y472453D01*
X802255Y472703D01*
X802088Y473078D01*
Y474870D01*
G01X799905Y472370D02*
Y474870D01*
X800405Y474370D01*
G01Y472370D02*
X799405D01*
G01X796805Y474870D02*
X797138Y474787D01*
X797388Y474578D01*
X797555Y474328D01*
X797680Y473995D01*
X797722Y473620D01*
X797680Y473245D01*
X797555Y472912D01*
X797388Y472662D01*
X797138Y472453D01*
X796805Y472370D01*
X796472Y472453D01*
X796222Y472662D01*
X796055Y472912D01*
X795930Y473245D01*
X795888Y473620D01*
X795930Y473995D01*
X796055Y474328D01*
X796222Y474578D01*
X796472Y474787D01*
X796805Y474870D01*
G01X810038Y488370D02*
Y490870D01*
X808997D01*
X808663Y490745D01*
X808455Y490578D01*
X808372Y490245D01*
X808455Y489912D01*
X808705Y489703D01*
X808997Y489578D01*
X810038D01*
G01X808997D02*
X808372Y488370D01*
G01X806105D02*
X805813Y488412D01*
X805480Y488537D01*
X805272Y488745D01*
X805188Y489037D01*
X805272Y489328D01*
X805522Y489578D01*
X805897Y489703D01*
X806313D01*
X806563Y489787D01*
X806772Y489995D01*
X806855Y490287D01*
X806730Y490578D01*
X806438Y490787D01*
X806105Y490870D01*
X805772Y490787D01*
X805480Y490578D01*
X805355Y490287D01*
X805438Y489995D01*
X805647Y489787D01*
X805897Y489703D01*
X806313D01*
X806688Y489578D01*
X806938Y489328D01*
X807022Y489037D01*
X806938Y488745D01*
X806730Y488537D01*
X806397Y488412D01*
X806105Y488370D01*
G01X803797D02*
Y490870D01*
X802213D01*
G01X802797Y489662D02*
X803797D01*
G01X800697Y490453D02*
X800447Y490703D01*
X800155Y490828D01*
X799822Y490870D01*
X799405Y490787D01*
X799113Y490578D01*
X799030Y490328D01*
X799072Y490078D01*
X799238Y489870D01*
X800072Y489453D01*
X800447Y489162D01*
X800697Y488745D01*
X800780Y488370D01*
X799030D01*
G01X797722Y488870D02*
X797472Y488578D01*
X797138Y488412D01*
X796763Y488370D01*
X796430Y488412D01*
X796097Y488620D01*
X795888Y488870D01*
X795847Y489120D01*
X795930Y489412D01*
X796222Y489620D01*
X796513Y489703D01*
X796888D01*
G01X796513D02*
X796263Y489828D01*
X796055Y490037D01*
X795972Y490287D01*
X796055Y490537D01*
X796263Y490745D01*
X796638Y490870D01*
X797013Y490828D01*
X797388Y490662D01*
G01X810038Y484370D02*
Y486870D01*
X808997D01*
X808663Y486745D01*
X808455Y486578D01*
X808372Y486245D01*
X808455Y485912D01*
X808705Y485703D01*
X808997Y485578D01*
X810038D01*
G01X808997D02*
X808372Y484370D01*
G01X806897Y486453D02*
X806647Y486703D01*
X806355Y486828D01*
X806022Y486870D01*
X805605Y486787D01*
X805313Y486578D01*
X805230Y486328D01*
X805272Y486078D01*
X805438Y485870D01*
X806272Y485453D01*
X806647Y485162D01*
X806897Y484745D01*
X806980Y484370D01*
X805230D01*
G01X803922Y486870D02*
Y485078D01*
X803755Y484703D01*
X803422Y484453D01*
X803005Y484370D01*
X802588Y484453D01*
X802255Y484703D01*
X802088Y485078D01*
Y486870D01*
G01X799405Y484370D02*
Y486870D01*
X800947Y485078D01*
X798863D01*
G01X810038Y496370D02*
Y498870D01*
X808997D01*
X808663Y498745D01*
X808455Y498578D01*
X808372Y498245D01*
X808455Y497912D01*
X808705Y497703D01*
X808997Y497578D01*
X810038D01*
G01X808997D02*
X808372Y496370D01*
G01X806897Y498453D02*
X806647Y498703D01*
X806355Y498828D01*
X806022Y498870D01*
X805605Y498787D01*
X805313Y498578D01*
X805230Y498328D01*
X805272Y498078D01*
X805438Y497870D01*
X806272Y497453D01*
X806647Y497162D01*
X806897Y496745D01*
X806980Y496370D01*
X805230D01*
G01X803922Y496745D02*
X803672Y496537D01*
X803380Y496412D01*
X803005Y496370D01*
X802630Y496453D01*
X802338Y496620D01*
X802130Y496912D01*
X802088Y497245D01*
X802172Y497578D01*
X802380Y497787D01*
X802672Y497953D01*
X802963Y497995D01*
X803255Y497953D01*
X803630Y497787D01*
X803505Y498870D01*
X802380D01*
G01X801155D02*
X800572Y496370D01*
X799905Y498870D01*
X799238Y496370D01*
X798655Y498870D01*
G01X796888Y496370D02*
X796805Y496912D01*
X796680Y497370D01*
X796513Y497787D01*
X796305Y498245D01*
X795972Y498870D01*
X797638D01*
G01X793705D02*
X794038Y498787D01*
X794288Y498578D01*
X794455Y498328D01*
X794580Y497995D01*
X794622Y497620D01*
X794580Y497245D01*
X794455Y496912D01*
X794288Y496662D01*
X794038Y496453D01*
X793705Y496370D01*
X793372Y496453D01*
X793122Y496662D01*
X792955Y496912D01*
X792830Y497245D01*
X792788Y497620D01*
X792830Y497995D01*
X792955Y498328D01*
X793122Y498578D01*
X793372Y498787D01*
X793705Y498870D01*
G01X858557Y468813D02*
Y471313D01*
X857516D01*
X857182Y471188D01*
X856974Y471021D01*
X856891Y470688D01*
X856974Y470355D01*
X857224Y470146D01*
X857516Y470021D01*
X858557D01*
G01X857516D02*
X856891Y468813D01*
G01X855416Y470896D02*
X855166Y471146D01*
X854874Y471271D01*
X854541Y471313D01*
X854124Y471230D01*
X853832Y471021D01*
X853749Y470771D01*
X853791Y470521D01*
X853957Y470313D01*
X854791Y469896D01*
X855166Y469605D01*
X855416Y469188D01*
X855499Y468813D01*
X853749D01*
G01X852441Y469188D02*
X852191Y468980D01*
X851899Y468855D01*
X851524Y468813D01*
X851149Y468896D01*
X850857Y469063D01*
X850649Y469355D01*
X850607Y469688D01*
X850691Y470021D01*
X850899Y470230D01*
X851191Y470396D01*
X851482Y470438D01*
X851774Y470396D01*
X852149Y470230D01*
X852024Y471313D01*
X850899D01*
G01X849674D02*
X849091Y468813D01*
X848424Y471313D01*
X847757Y468813D01*
X847174Y471313D01*
G01X845324Y468813D02*
Y471313D01*
X845824Y470813D01*
G01Y468813D02*
X844824D01*
G01X841724D02*
Y471313D01*
X843266Y469521D01*
X841182D01*
G01X839832Y469105D02*
X839541Y468896D01*
X839207Y468813D01*
X838874Y468896D01*
X838582Y469146D01*
X838374Y469521D01*
X838291Y469896D01*
Y470355D01*
X838374Y470730D01*
X838582Y471063D01*
X838832Y471230D01*
X839124Y471313D01*
X839457Y471230D01*
X839707Y471063D01*
X839874Y470813D01*
X839957Y470480D01*
X839874Y470188D01*
X839666Y469896D01*
X839416Y469730D01*
X839124Y469688D01*
X838791Y469771D01*
X838541Y469980D01*
X838291Y470355D01*
G01X852022Y477984D02*
Y480484D01*
X850981D01*
X850647Y480359D01*
X850439Y480192D01*
X850356Y479859D01*
X850439Y479526D01*
X850689Y479317D01*
X850981Y479192D01*
X852022D01*
G01X850981D02*
X850356Y477984D01*
G01X848089D02*
Y480484D01*
X848589Y479984D01*
G01Y477984D02*
X847589D01*
G01X844989Y480484D02*
Y477984D01*
G01X845947Y480484D02*
X844031D01*
G01X842681Y480067D02*
X842431Y480317D01*
X842139Y480442D01*
X841806Y480484D01*
X841389Y480401D01*
X841097Y480192D01*
X841014Y479942D01*
X841056Y479692D01*
X841222Y479484D01*
X842056Y479067D01*
X842431Y478776D01*
X842681Y478359D01*
X842764Y477984D01*
X841014D01*
G01X839581Y479026D02*
X839289Y479317D01*
X839039Y479484D01*
X838706Y479567D01*
X838414Y479484D01*
X838206Y479317D01*
X838039Y479067D01*
X837997Y478776D01*
X838039Y478526D01*
X838206Y478276D01*
X838456Y478067D01*
X838747Y477984D01*
X839081Y478067D01*
X839372Y478317D01*
X839539Y478692D01*
X839581Y479109D01*
X839497Y479651D01*
X839372Y479942D01*
X839164Y480234D01*
X838872Y480442D01*
X838581Y480484D01*
X838289Y480401D01*
X838081Y480192D01*
G01X851719Y491068D02*
Y493568D01*
X850678D01*
X850344Y493443D01*
X850136Y493276D01*
X850053Y492943D01*
X850136Y492610D01*
X850386Y492401D01*
X850678Y492276D01*
X851719D01*
G01X850678D02*
X850053Y491068D01*
G01X848578Y493151D02*
X848328Y493401D01*
X848036Y493526D01*
X847703Y493568D01*
X847286Y493485D01*
X846994Y493276D01*
X846911Y493026D01*
X846953Y492776D01*
X847119Y492568D01*
X847953Y492151D01*
X848328Y491860D01*
X848578Y491443D01*
X848661Y491068D01*
X846911D01*
G01X845603Y491443D02*
X845353Y491235D01*
X845061Y491110D01*
X844686Y491068D01*
X844311Y491151D01*
X844019Y491318D01*
X843811Y491610D01*
X843769Y491943D01*
X843853Y492276D01*
X844061Y492485D01*
X844353Y492651D01*
X844644Y492693D01*
X844936Y492651D01*
X845311Y492485D01*
X845186Y493568D01*
X844061D01*
G01X842836D02*
X842253Y491068D01*
X841586Y493568D01*
X840919Y491068D01*
X840336Y493568D01*
G01X838486Y491068D02*
Y493568D01*
X838986Y493068D01*
G01Y491068D02*
X837986D01*
G01X836178Y493151D02*
X835928Y493401D01*
X835636Y493526D01*
X835303Y493568D01*
X834886Y493485D01*
X834594Y493276D01*
X834511Y493026D01*
X834553Y492776D01*
X834719Y492568D01*
X835553Y492151D01*
X835928Y491860D01*
X836178Y491443D01*
X836261Y491068D01*
X834511D01*
G01X833078Y493151D02*
X832828Y493401D01*
X832536Y493526D01*
X832203Y493568D01*
X831786Y493485D01*
X831494Y493276D01*
X831411Y493026D01*
X831453Y492776D01*
X831619Y492568D01*
X832453Y492151D01*
X832828Y491860D01*
X833078Y491443D01*
X833161Y491068D01*
X831411D01*
G01X851718Y487095D02*
Y489595D01*
X850677D01*
X850343Y489470D01*
X850135Y489303D01*
X850052Y488970D01*
X850135Y488637D01*
X850385Y488428D01*
X850677Y488303D01*
X851718D01*
G01X850677D02*
X850052Y487095D01*
G01X848577Y489178D02*
X848327Y489428D01*
X848035Y489553D01*
X847702Y489595D01*
X847285Y489512D01*
X846993Y489303D01*
X846910Y489053D01*
X846952Y488803D01*
X847118Y488595D01*
X847952Y488178D01*
X848327Y487887D01*
X848577Y487470D01*
X848660Y487095D01*
X846910D01*
G01X845602Y487470D02*
X845352Y487262D01*
X845060Y487137D01*
X844685Y487095D01*
X844310Y487178D01*
X844018Y487345D01*
X843810Y487637D01*
X843768Y487970D01*
X843852Y488303D01*
X844060Y488512D01*
X844352Y488678D01*
X844643Y488720D01*
X844935Y488678D01*
X845310Y488512D01*
X845185Y489595D01*
X844060D01*
G01X842835D02*
X842252Y487095D01*
X841585Y489595D01*
X840918Y487095D01*
X840335Y489595D01*
G01X838485Y487095D02*
Y489595D01*
X838985Y489095D01*
G01Y487095D02*
X837985D01*
G01X836177Y489178D02*
X835927Y489428D01*
X835635Y489553D01*
X835302Y489595D01*
X834885Y489512D01*
X834593Y489303D01*
X834510Y489053D01*
X834552Y488803D01*
X834718Y488595D01*
X835552Y488178D01*
X835927Y487887D01*
X836177Y487470D01*
X836260Y487095D01*
X834510D01*
G01X832285D02*
Y489595D01*
X832785Y489095D01*
G01Y487095D02*
X831785D01*
G01X852101Y482614D02*
Y485114D01*
X851060D01*
X850726Y484989D01*
X850518Y484822D01*
X850435Y484489D01*
X850518Y484156D01*
X850768Y483947D01*
X851060Y483822D01*
X852101D01*
G01X851060D02*
X850435Y482614D01*
G01X848960Y484697D02*
X848710Y484947D01*
X848418Y485072D01*
X848085Y485114D01*
X847668Y485031D01*
X847376Y484822D01*
X847293Y484572D01*
X847335Y484322D01*
X847501Y484114D01*
X848335Y483697D01*
X848710Y483406D01*
X848960Y482989D01*
X849043Y482614D01*
X847293D01*
G01X845985Y482989D02*
X845735Y482781D01*
X845443Y482656D01*
X845068Y482614D01*
X844693Y482697D01*
X844401Y482864D01*
X844193Y483156D01*
X844151Y483489D01*
X844235Y483822D01*
X844443Y484031D01*
X844735Y484197D01*
X845026Y484239D01*
X845318Y484197D01*
X845693Y484031D01*
X845568Y485114D01*
X844443D01*
G01X843218D02*
X842635Y482614D01*
X841968Y485114D01*
X841301Y482614D01*
X840718Y485114D01*
G01X838868Y482614D02*
Y485114D01*
X839368Y484614D01*
G01Y482614D02*
X838368D01*
G01X835268D02*
Y485114D01*
X836810Y483322D01*
X834726D01*
G01X833460Y483656D02*
X833168Y483947D01*
X832918Y484114D01*
X832585Y484197D01*
X832293Y484114D01*
X832085Y483947D01*
X831918Y483697D01*
X831876Y483406D01*
X831918Y483156D01*
X832085Y482906D01*
X832335Y482697D01*
X832626Y482614D01*
X832960Y482697D01*
X833251Y482947D01*
X833418Y483322D01*
X833460Y483739D01*
X833376Y484281D01*
X833251Y484572D01*
X833043Y484864D01*
X832751Y485072D01*
X832460Y485114D01*
X832168Y485031D01*
X831960Y484822D01*
G01X850685Y475364D02*
X850935Y475489D01*
X851227Y475572D01*
X851560D01*
X851935Y475447D01*
X852227Y475239D01*
X852435Y474989D01*
X852602Y474572D01*
X852644Y474197D01*
X852560Y473822D01*
X852435Y473572D01*
X852185Y473322D01*
X851894Y473155D01*
X851602Y473072D01*
X851310D01*
X851019Y473155D01*
X850769Y473280D01*
X850560Y473447D01*
G01X848502Y473072D02*
Y475572D01*
X849002Y475072D01*
G01Y473072D02*
X848002D01*
G01X846652Y475572D02*
X846069Y473072D01*
X845402Y475572D01*
X844735Y473072D01*
X844152Y475572D01*
G01X843094Y475155D02*
X842844Y475405D01*
X842552Y475530D01*
X842219Y475572D01*
X841802Y475489D01*
X841510Y475280D01*
X841427Y475030D01*
X841469Y474780D01*
X841635Y474572D01*
X842469Y474155D01*
X842844Y473864D01*
X843094Y473447D01*
X843177Y473072D01*
X841427D01*
G01X839202D02*
Y475572D01*
X839702Y475072D01*
G01Y473072D02*
X838702D01*
G01X826086Y467317D02*
X826211Y467067D01*
X826294Y466775D01*
Y466442D01*
X826169Y466067D01*
X825961Y465775D01*
X825711Y465567D01*
X825294Y465400D01*
X824919Y465358D01*
X824544Y465442D01*
X824294Y465567D01*
X824044Y465817D01*
X823877Y466108D01*
X823794Y466400D01*
Y466692D01*
X823877Y466983D01*
X824002Y467233D01*
X824169Y467442D01*
G01X825877Y468708D02*
X826127Y468958D01*
X826252Y469250D01*
X826294Y469583D01*
X826211Y470000D01*
X826002Y470292D01*
X825752Y470375D01*
X825502Y470333D01*
X825294Y470167D01*
X824877Y469333D01*
X824586Y468958D01*
X824169Y468708D01*
X823794Y468625D01*
Y470375D01*
G01X824169Y471683D02*
X823961Y471933D01*
X823836Y472225D01*
X823794Y472600D01*
X823877Y472975D01*
X824044Y473267D01*
X824336Y473475D01*
X824669Y473517D01*
X825002Y473433D01*
X825211Y473225D01*
X825377Y472933D01*
X825419Y472642D01*
X825377Y472350D01*
X825211Y471975D01*
X826294Y472100D01*
Y473225D01*
G01Y474450D02*
X823794Y475033D01*
X826294Y475700D01*
X823794Y476367D01*
X826294Y476950D01*
G01X824294Y477883D02*
X824002Y478133D01*
X823836Y478467D01*
X823794Y478842D01*
X823836Y479175D01*
X824044Y479508D01*
X824294Y479717D01*
X824544Y479758D01*
X824836Y479675D01*
X825044Y479383D01*
X825127Y479092D01*
Y478717D01*
G01Y479092D02*
X825252Y479342D01*
X825461Y479550D01*
X825711Y479633D01*
X825961Y479550D01*
X826169Y479342D01*
X826294Y478967D01*
X826252Y478592D01*
X826086Y478217D01*
G01X823794Y482400D02*
X826294D01*
X824502Y480858D01*
Y482942D01*
G01X822636Y467317D02*
X822761Y467067D01*
X822844Y466775D01*
Y466442D01*
X822719Y466067D01*
X822511Y465775D01*
X822261Y465567D01*
X821844Y465400D01*
X821469Y465358D01*
X821094Y465442D01*
X820844Y465567D01*
X820594Y465817D01*
X820427Y466108D01*
X820344Y466400D01*
Y466692D01*
X820427Y466983D01*
X820552Y467233D01*
X820719Y467442D01*
G01X822427Y468708D02*
X822677Y468958D01*
X822802Y469250D01*
X822844Y469583D01*
X822761Y470000D01*
X822552Y470292D01*
X822302Y470375D01*
X822052Y470333D01*
X821844Y470167D01*
X821427Y469333D01*
X821136Y468958D01*
X820719Y468708D01*
X820344Y468625D01*
Y470375D01*
G01X820719Y471683D02*
X820511Y471933D01*
X820386Y472225D01*
X820344Y472600D01*
X820427Y472975D01*
X820594Y473267D01*
X820886Y473475D01*
X821219Y473517D01*
X821552Y473433D01*
X821761Y473225D01*
X821927Y472933D01*
X821969Y472642D01*
X821927Y472350D01*
X821761Y471975D01*
X822844Y472100D01*
Y473225D01*
G01Y474450D02*
X820344Y475033D01*
X822844Y475700D01*
X820344Y476367D01*
X822844Y476950D01*
G01X820844Y477883D02*
X820552Y478133D01*
X820386Y478467D01*
X820344Y478842D01*
X820386Y479175D01*
X820594Y479508D01*
X820844Y479717D01*
X821094Y479758D01*
X821386Y479675D01*
X821594Y479383D01*
X821677Y479092D01*
Y478717D01*
G01Y479092D02*
X821802Y479342D01*
X822011Y479550D01*
X822261Y479633D01*
X822511Y479550D01*
X822719Y479342D01*
X822844Y478967D01*
X822802Y478592D01*
X822636Y478217D01*
G01X820719Y480983D02*
X820511Y481233D01*
X820386Y481525D01*
X820344Y481900D01*
X820427Y482275D01*
X820594Y482567D01*
X820886Y482775D01*
X821219Y482817D01*
X821552Y482733D01*
X821761Y482525D01*
X821927Y482233D01*
X821969Y481942D01*
X821927Y481650D01*
X821761Y481275D01*
X822844Y481400D01*
Y482525D01*
G01X808803Y567942D02*
Y570442D01*
X807762D01*
X807428Y570317D01*
X807220Y570150D01*
X807137Y569817D01*
X807220Y569484D01*
X807470Y569275D01*
X807762Y569150D01*
X808803D01*
G01X807762D02*
X807137Y567942D01*
G01X805662Y568984D02*
X805370Y569275D01*
X805120Y569442D01*
X804787Y569525D01*
X804495Y569442D01*
X804287Y569275D01*
X804120Y569025D01*
X804078Y568734D01*
X804120Y568484D01*
X804287Y568234D01*
X804537Y568025D01*
X804828Y567942D01*
X805162Y568025D01*
X805453Y568275D01*
X805620Y568650D01*
X805662Y569067D01*
X805578Y569609D01*
X805453Y569900D01*
X805245Y570192D01*
X804953Y570400D01*
X804662Y570442D01*
X804370Y570359D01*
X804162Y570150D01*
G01X802603Y570442D02*
Y567942D01*
X800937D01*
G01X798670D02*
Y570442D01*
X799170Y569942D01*
G01Y567942D02*
X798170D01*
G01X796362Y570025D02*
X796112Y570275D01*
X795820Y570400D01*
X795487Y570442D01*
X795070Y570359D01*
X794778Y570150D01*
X794695Y569900D01*
X794737Y569650D01*
X794903Y569442D01*
X795737Y569025D01*
X796112Y568734D01*
X796362Y568317D01*
X796445Y567942D01*
X794695D01*
G01X802267Y573315D02*
Y575815D01*
X801226D01*
X800892Y575690D01*
X800684Y575523D01*
X800601Y575190D01*
X800684Y574857D01*
X800934Y574648D01*
X801226Y574523D01*
X802267D01*
G01X801226D02*
X800601Y573315D01*
G01X799126Y574357D02*
X798834Y574648D01*
X798584Y574815D01*
X798251Y574898D01*
X797959Y574815D01*
X797751Y574648D01*
X797584Y574398D01*
X797542Y574107D01*
X797584Y573857D01*
X797751Y573607D01*
X798001Y573398D01*
X798292Y573315D01*
X798626Y573398D01*
X798917Y573648D01*
X799084Y574023D01*
X799126Y574440D01*
X799042Y574982D01*
X798917Y575273D01*
X798709Y575565D01*
X798417Y575773D01*
X798126Y575815D01*
X797834Y575732D01*
X797626Y575523D01*
G01X796067Y575815D02*
Y573315D01*
X794401D01*
G01X792134D02*
Y575815D01*
X792634Y575315D01*
G01Y573315D02*
X791634D01*
G01X789951Y573815D02*
X789701Y573523D01*
X789367Y573357D01*
X788992Y573315D01*
X788659Y573357D01*
X788326Y573565D01*
X788117Y573815D01*
X788076Y574065D01*
X788159Y574357D01*
X788451Y574565D01*
X788742Y574648D01*
X789117D01*
G01X788742D02*
X788492Y574773D01*
X788284Y574982D01*
X788201Y575232D01*
X788284Y575482D01*
X788492Y575690D01*
X788867Y575815D01*
X789242Y575773D01*
X789617Y575607D01*
G01X800654Y530531D02*
Y533031D01*
X799613D01*
X799279Y532906D01*
X799071Y532739D01*
X798988Y532406D01*
X799071Y532073D01*
X799321Y531864D01*
X799613Y531739D01*
X800654D01*
G01X799613D02*
X798988Y530531D01*
G01X797513Y531573D02*
X797221Y531864D01*
X796971Y532031D01*
X796638Y532114D01*
X796346Y532031D01*
X796138Y531864D01*
X795971Y531614D01*
X795929Y531323D01*
X795971Y531073D01*
X796138Y530823D01*
X796388Y530614D01*
X796679Y530531D01*
X797013Y530614D01*
X797304Y530864D01*
X797471Y531239D01*
X797513Y531656D01*
X797429Y532198D01*
X797304Y532489D01*
X797096Y532781D01*
X796804Y532989D01*
X796513Y533031D01*
X796221Y532948D01*
X796013Y532739D01*
G01X794704Y530531D02*
Y533031D01*
X793621Y530948D01*
X792538Y533031D01*
Y530531D01*
G01X791313Y532614D02*
X791063Y532864D01*
X790771Y532989D01*
X790438Y533031D01*
X790021Y532948D01*
X789729Y532739D01*
X789646Y532489D01*
X789688Y532239D01*
X789854Y532031D01*
X790688Y531614D01*
X791063Y531323D01*
X791313Y530906D01*
X791396Y530531D01*
X789646D01*
G01X815249Y535323D02*
Y537823D01*
X814208D01*
X813874Y537698D01*
X813666Y537531D01*
X813583Y537198D01*
X813666Y536865D01*
X813916Y536656D01*
X814208Y536531D01*
X815249D01*
G01X814208D02*
X813583Y535323D01*
G01X812108Y536365D02*
X811816Y536656D01*
X811566Y536823D01*
X811233Y536906D01*
X810941Y536823D01*
X810733Y536656D01*
X810566Y536406D01*
X810524Y536115D01*
X810566Y535865D01*
X810733Y535615D01*
X810983Y535406D01*
X811274Y535323D01*
X811608Y535406D01*
X811899Y535656D01*
X812066Y536031D01*
X812108Y536448D01*
X812024Y536990D01*
X811899Y537281D01*
X811691Y537573D01*
X811399Y537781D01*
X811108Y537823D01*
X810816Y537740D01*
X810608Y537531D01*
G01X809049Y537823D02*
Y535323D01*
X807383D01*
G01X805116D02*
Y537823D01*
X805616Y537323D01*
G01Y535323D02*
X804616D01*
G01X802808Y536365D02*
X802516Y536656D01*
X802266Y536823D01*
X801933Y536906D01*
X801641Y536823D01*
X801433Y536656D01*
X801266Y536406D01*
X801224Y536115D01*
X801266Y535865D01*
X801433Y535615D01*
X801683Y535406D01*
X801974Y535323D01*
X802308Y535406D01*
X802599Y535656D01*
X802766Y536031D01*
X802808Y536448D01*
X802724Y536990D01*
X802599Y537281D01*
X802391Y537573D01*
X802099Y537781D01*
X801808Y537823D01*
X801516Y537740D01*
X801308Y537531D01*
G01X820447Y568369D02*
X820697Y568494D01*
X820989Y568577D01*
X821322D01*
X821697Y568452D01*
X821989Y568244D01*
X822197Y567994D01*
X822364Y567577D01*
X822406Y567202D01*
X822322Y566827D01*
X822197Y566577D01*
X821947Y566327D01*
X821656Y566160D01*
X821364Y566077D01*
X821072D01*
X820781Y566160D01*
X820531Y566285D01*
X820322Y566452D01*
G01X819056Y567119D02*
X818764Y567410D01*
X818514Y567577D01*
X818181Y567660D01*
X817889Y567577D01*
X817681Y567410D01*
X817514Y567160D01*
X817472Y566869D01*
X817514Y566619D01*
X817681Y566369D01*
X817931Y566160D01*
X818222Y566077D01*
X818556Y566160D01*
X818847Y566410D01*
X819014Y566785D01*
X819056Y567202D01*
X818972Y567744D01*
X818847Y568035D01*
X818639Y568327D01*
X818347Y568535D01*
X818056Y568577D01*
X817764Y568494D01*
X817556Y568285D01*
G01X815997Y568577D02*
Y566077D01*
X814331D01*
G01X812856Y567119D02*
X812564Y567410D01*
X812314Y567577D01*
X811981Y567660D01*
X811689Y567577D01*
X811481Y567410D01*
X811314Y567160D01*
X811272Y566869D01*
X811314Y566619D01*
X811481Y566369D01*
X811731Y566160D01*
X812022Y566077D01*
X812356Y566160D01*
X812647Y566410D01*
X812814Y566785D01*
X812856Y567202D01*
X812772Y567744D01*
X812647Y568035D01*
X812439Y568327D01*
X812147Y568535D01*
X811856Y568577D01*
X811564Y568494D01*
X811356Y568285D01*
G01X817445Y533953D02*
X817695Y534078D01*
X817987Y534161D01*
X818320D01*
X818695Y534036D01*
X818987Y533828D01*
X819195Y533578D01*
X819362Y533161D01*
X819404Y532786D01*
X819320Y532411D01*
X819195Y532161D01*
X818945Y531911D01*
X818654Y531744D01*
X818362Y531661D01*
X818070D01*
X817779Y531744D01*
X817529Y531869D01*
X817320Y532036D01*
G01X816054Y532703D02*
X815762Y532994D01*
X815512Y533161D01*
X815179Y533244D01*
X814887Y533161D01*
X814679Y532994D01*
X814512Y532744D01*
X814470Y532453D01*
X814512Y532203D01*
X814679Y531953D01*
X814929Y531744D01*
X815220Y531661D01*
X815554Y531744D01*
X815845Y531994D01*
X816012Y532369D01*
X816054Y532786D01*
X815970Y533328D01*
X815845Y533619D01*
X815637Y533911D01*
X815345Y534119D01*
X815054Y534161D01*
X814762Y534078D01*
X814554Y533869D01*
G01X813245Y531661D02*
Y534161D01*
X812162Y532078D01*
X811079Y534161D01*
Y531661D01*
G01X809062D02*
Y534161D01*
X809562Y533661D01*
G01Y531661D02*
X808562D01*
G01X799883Y616500D02*
Y619000D01*
X798842D01*
X798508Y618875D01*
X798300Y618708D01*
X798217Y618375D01*
X798300Y618042D01*
X798550Y617833D01*
X798842Y617708D01*
X799883D01*
G01X798842D02*
X798217Y616500D01*
G01X796742Y617542D02*
X796450Y617833D01*
X796200Y618000D01*
X795867Y618083D01*
X795575Y618000D01*
X795367Y617833D01*
X795200Y617583D01*
X795158Y617292D01*
X795200Y617042D01*
X795367Y616792D01*
X795617Y616583D01*
X795908Y616500D01*
X796242Y616583D01*
X796533Y616833D01*
X796700Y617208D01*
X796742Y617625D01*
X796658Y618167D01*
X796533Y618458D01*
X796325Y618750D01*
X796033Y618958D01*
X795742Y619000D01*
X795450Y618917D01*
X795242Y618708D01*
G01X793683Y619000D02*
Y616500D01*
X792017D01*
G01X789750D02*
Y619000D01*
X790250Y618500D01*
G01Y616500D02*
X789250D01*
G01X811333Y618792D02*
X811583Y618917D01*
X811875Y619000D01*
X812208D01*
X812583Y618875D01*
X812875Y618667D01*
X813083Y618417D01*
X813250Y618000D01*
X813292Y617625D01*
X813208Y617250D01*
X813083Y617000D01*
X812833Y616750D01*
X812542Y616583D01*
X812250Y616500D01*
X811958D01*
X811667Y616583D01*
X811417Y616708D01*
X811208Y616875D01*
G01X809942Y617542D02*
X809650Y617833D01*
X809400Y618000D01*
X809067Y618083D01*
X808775Y618000D01*
X808567Y617833D01*
X808400Y617583D01*
X808358Y617292D01*
X808400Y617042D01*
X808567Y616792D01*
X808817Y616583D01*
X809108Y616500D01*
X809442Y616583D01*
X809733Y616833D01*
X809900Y617208D01*
X809942Y617625D01*
X809858Y618167D01*
X809733Y618458D01*
X809525Y618750D01*
X809233Y618958D01*
X808942Y619000D01*
X808650Y618917D01*
X808442Y618708D01*
G01X806883Y619000D02*
Y616500D01*
X805217D01*
G01X802950D02*
Y619000D01*
X803450Y618500D01*
G01Y616500D02*
X802450D01*
G01X870499Y137851D02*
X870500Y137852D01*
G01Y144400D02*
Y137852D01*
X870499Y137851D01*
G01X870501Y144400D02*
X870500Y144399D01*
Y150590D01*
X938820D01*
Y144400D01*
X1034300D01*
Y122000D01*
X1010800D01*
Y114861D01*
X1010805Y114856D01*
X1012305Y116356D01*
X1009305D01*
X1010805Y114856D01*
G01X884394Y144130D02*
X884644Y144255D01*
X884936Y144338D01*
X885269D01*
X885644Y144213D01*
X885936Y144005D01*
X886144Y143755D01*
X886311Y143338D01*
X886353Y142963D01*
X886269Y142588D01*
X886144Y142338D01*
X885894Y142088D01*
X885603Y141921D01*
X885311Y141838D01*
X885019D01*
X884728Y141921D01*
X884478Y142046D01*
X884269Y142213D01*
G01X883128D02*
X882878Y142005D01*
X882586Y141880D01*
X882211Y141838D01*
X881836Y141921D01*
X881544Y142088D01*
X881336Y142380D01*
X881294Y142713D01*
X881378Y143046D01*
X881586Y143255D01*
X881878Y143421D01*
X882169Y143463D01*
X882461Y143421D01*
X882836Y143255D01*
X882711Y144338D01*
X881586D01*
G01X878861Y143088D02*
X878028D01*
Y142338D01*
X878278Y142088D01*
X878569Y141921D01*
X878986Y141838D01*
X879403Y141921D01*
X879694Y142088D01*
X879944Y142338D01*
X880111Y142630D01*
X880194Y142963D01*
Y143255D01*
X880111Y143505D01*
X879944Y143796D01*
X879694Y144046D01*
X879444Y144213D01*
X879111Y144338D01*
X878819D01*
X878486Y144255D01*
X878236Y144088D01*
G01X875511Y141838D02*
Y144338D01*
X877053Y142546D01*
X874969D01*
G01X872911Y141838D02*
Y144338D01*
X873411Y143838D01*
G01Y141838D02*
X872411D01*
G01X916837Y136351D02*
X917087Y136476D01*
X917379Y136559D01*
X917712D01*
X918087Y136434D01*
X918379Y136226D01*
X918587Y135976D01*
X918754Y135559D01*
X918796Y135184D01*
X918712Y134809D01*
X918587Y134559D01*
X918337Y134309D01*
X918046Y134142D01*
X917754Y134059D01*
X917462D01*
X917171Y134142D01*
X916921Y134267D01*
X916712Y134434D01*
G01X915571D02*
X915321Y134226D01*
X915029Y134101D01*
X914654Y134059D01*
X914279Y134142D01*
X913987Y134309D01*
X913779Y134601D01*
X913737Y134934D01*
X913821Y135267D01*
X914029Y135476D01*
X914321Y135642D01*
X914612Y135684D01*
X914904Y135642D01*
X915279Y135476D01*
X915154Y136559D01*
X914029D01*
G01X911304Y135309D02*
X910471D01*
Y134559D01*
X910721Y134309D01*
X911012Y134142D01*
X911429Y134059D01*
X911846Y134142D01*
X912137Y134309D01*
X912387Y134559D01*
X912554Y134851D01*
X912637Y135184D01*
Y135476D01*
X912554Y135726D01*
X912387Y136017D01*
X912137Y136267D01*
X911887Y136434D01*
X911554Y136559D01*
X911262D01*
X910929Y136476D01*
X910679Y136309D01*
G01X909371Y134434D02*
X909121Y134226D01*
X908829Y134101D01*
X908454Y134059D01*
X908079Y134142D01*
X907787Y134309D01*
X907579Y134601D01*
X907537Y134934D01*
X907621Y135267D01*
X907829Y135476D01*
X908121Y135642D01*
X908412Y135684D01*
X908704Y135642D01*
X909079Y135476D01*
X908954Y136559D01*
X907829D01*
G01X906146Y136142D02*
X905896Y136392D01*
X905604Y136517D01*
X905271Y136559D01*
X904854Y136476D01*
X904562Y136267D01*
X904479Y136017D01*
X904521Y135767D01*
X904687Y135559D01*
X905521Y135142D01*
X905896Y134851D01*
X906146Y134434D01*
X906229Y134059D01*
X904479D01*
G01X900271Y136249D02*
X900521Y136374D01*
X900813Y136457D01*
X901146D01*
X901521Y136332D01*
X901813Y136124D01*
X902021Y135874D01*
X902188Y135457D01*
X902230Y135082D01*
X902146Y134707D01*
X902021Y134457D01*
X901771Y134207D01*
X901480Y134040D01*
X901188Y133957D01*
X900896D01*
X900605Y134040D01*
X900355Y134165D01*
X900146Y134332D01*
G01X899005D02*
X898755Y134124D01*
X898463Y133999D01*
X898088Y133957D01*
X897713Y134040D01*
X897421Y134207D01*
X897213Y134499D01*
X897171Y134832D01*
X897255Y135165D01*
X897463Y135374D01*
X897755Y135540D01*
X898046Y135582D01*
X898338Y135540D01*
X898713Y135374D01*
X898588Y136457D01*
X897463D01*
G01X894738Y135207D02*
X893905D01*
Y134457D01*
X894155Y134207D01*
X894446Y134040D01*
X894863Y133957D01*
X895280Y134040D01*
X895571Y134207D01*
X895821Y134457D01*
X895988Y134749D01*
X896071Y135082D01*
Y135374D01*
X895988Y135624D01*
X895821Y135915D01*
X895571Y136165D01*
X895321Y136332D01*
X894988Y136457D01*
X894696D01*
X894363Y136374D01*
X894113Y136207D01*
G01X892805Y134332D02*
X892555Y134124D01*
X892263Y133999D01*
X891888Y133957D01*
X891513Y134040D01*
X891221Y134207D01*
X891013Y134499D01*
X890971Y134832D01*
X891055Y135165D01*
X891263Y135374D01*
X891555Y135540D01*
X891846Y135582D01*
X892138Y135540D01*
X892513Y135374D01*
X892388Y136457D01*
X891263D01*
G01X888788Y133957D02*
Y136457D01*
X889288Y135957D01*
G01Y133957D02*
X888288D01*
G01X900271Y144249D02*
X900521Y144374D01*
X900813Y144457D01*
X901146D01*
X901521Y144332D01*
X901813Y144124D01*
X902021Y143874D01*
X902188Y143457D01*
X902230Y143082D01*
X902146Y142707D01*
X902021Y142457D01*
X901771Y142207D01*
X901480Y142040D01*
X901188Y141957D01*
X900896D01*
X900605Y142040D01*
X900355Y142165D01*
X900146Y142332D01*
G01X899005D02*
X898755Y142124D01*
X898463Y141999D01*
X898088Y141957D01*
X897713Y142040D01*
X897421Y142207D01*
X897213Y142499D01*
X897171Y142832D01*
X897255Y143165D01*
X897463Y143374D01*
X897755Y143540D01*
X898046Y143582D01*
X898338Y143540D01*
X898713Y143374D01*
X898588Y144457D01*
X897463D01*
G01X894738Y143207D02*
X893905D01*
Y142457D01*
X894155Y142207D01*
X894446Y142040D01*
X894863Y141957D01*
X895280Y142040D01*
X895571Y142207D01*
X895821Y142457D01*
X895988Y142749D01*
X896071Y143082D01*
Y143374D01*
X895988Y143624D01*
X895821Y143915D01*
X895571Y144165D01*
X895321Y144332D01*
X894988Y144457D01*
X894696D01*
X894363Y144374D01*
X894113Y144207D01*
G01X891388Y141957D02*
Y144457D01*
X892930Y142665D01*
X890846D01*
G01X889580Y144040D02*
X889330Y144290D01*
X889038Y144415D01*
X888705Y144457D01*
X888288Y144374D01*
X887996Y144165D01*
X887913Y143915D01*
X887955Y143665D01*
X888121Y143457D01*
X888955Y143040D01*
X889330Y142749D01*
X889580Y142332D01*
X889663Y141957D01*
X887913D01*
G01X916837Y144351D02*
X917087Y144476D01*
X917379Y144559D01*
X917712D01*
X918087Y144434D01*
X918379Y144226D01*
X918587Y143976D01*
X918754Y143559D01*
X918796Y143184D01*
X918712Y142809D01*
X918587Y142559D01*
X918337Y142309D01*
X918046Y142142D01*
X917754Y142059D01*
X917462D01*
X917171Y142142D01*
X916921Y142267D01*
X916712Y142434D01*
G01X915571D02*
X915321Y142226D01*
X915029Y142101D01*
X914654Y142059D01*
X914279Y142142D01*
X913987Y142309D01*
X913779Y142601D01*
X913737Y142934D01*
X913821Y143267D01*
X914029Y143476D01*
X914321Y143642D01*
X914612Y143684D01*
X914904Y143642D01*
X915279Y143476D01*
X915154Y144559D01*
X914029D01*
G01X911304Y143309D02*
X910471D01*
Y142559D01*
X910721Y142309D01*
X911012Y142142D01*
X911429Y142059D01*
X911846Y142142D01*
X912137Y142309D01*
X912387Y142559D01*
X912554Y142851D01*
X912637Y143184D01*
Y143476D01*
X912554Y143726D01*
X912387Y144017D01*
X912137Y144267D01*
X911887Y144434D01*
X911554Y144559D01*
X911262D01*
X910929Y144476D01*
X910679Y144309D01*
G01X907954Y142059D02*
Y144559D01*
X909496Y142767D01*
X907412D01*
G01X906271Y142559D02*
X906021Y142267D01*
X905687Y142101D01*
X905312Y142059D01*
X904979Y142101D01*
X904646Y142309D01*
X904437Y142559D01*
X904396Y142809D01*
X904479Y143101D01*
X904771Y143309D01*
X905062Y143392D01*
X905437D01*
G01X905062D02*
X904812Y143517D01*
X904604Y143726D01*
X904521Y143976D01*
X904604Y144226D01*
X904812Y144434D01*
X905187Y144559D01*
X905562Y144517D01*
X905937Y144351D01*
G01X884394Y136130D02*
X884644Y136255D01*
X884936Y136338D01*
X885269D01*
X885644Y136213D01*
X885936Y136005D01*
X886144Y135755D01*
X886311Y135338D01*
X886353Y134963D01*
X886269Y134588D01*
X886144Y134338D01*
X885894Y134088D01*
X885603Y133921D01*
X885311Y133838D01*
X885019D01*
X884728Y133921D01*
X884478Y134046D01*
X884269Y134213D01*
G01X883128D02*
X882878Y134005D01*
X882586Y133880D01*
X882211Y133838D01*
X881836Y133921D01*
X881544Y134088D01*
X881336Y134380D01*
X881294Y134713D01*
X881378Y135046D01*
X881586Y135255D01*
X881878Y135421D01*
X882169Y135463D01*
X882461Y135421D01*
X882836Y135255D01*
X882711Y136338D01*
X881586D01*
G01X878861Y135088D02*
X878028D01*
Y134338D01*
X878278Y134088D01*
X878569Y133921D01*
X878986Y133838D01*
X879403Y133921D01*
X879694Y134088D01*
X879944Y134338D01*
X880111Y134630D01*
X880194Y134963D01*
Y135255D01*
X880111Y135505D01*
X879944Y135796D01*
X879694Y136046D01*
X879444Y136213D01*
X879111Y136338D01*
X878819D01*
X878486Y136255D01*
X878236Y136088D01*
G01X876928Y134213D02*
X876678Y134005D01*
X876386Y133880D01*
X876011Y133838D01*
X875636Y133921D01*
X875344Y134088D01*
X875136Y134380D01*
X875094Y134713D01*
X875178Y135046D01*
X875386Y135255D01*
X875678Y135421D01*
X875969Y135463D01*
X876261Y135421D01*
X876636Y135255D01*
X876511Y136338D01*
X875386D01*
G01X872911D02*
X873244Y136255D01*
X873494Y136046D01*
X873661Y135796D01*
X873786Y135463D01*
X873828Y135088D01*
X873786Y134713D01*
X873661Y134380D01*
X873494Y134130D01*
X873244Y133921D01*
X872911Y133838D01*
X872578Y133921D01*
X872328Y134130D01*
X872161Y134380D01*
X872036Y134713D01*
X871994Y135088D01*
X872036Y135463D01*
X872161Y135796D01*
X872328Y136046D01*
X872578Y136255D01*
X872911Y136338D01*
G01X868780Y149498D02*
X868905Y149248D01*
X868988Y148956D01*
Y148623D01*
X868863Y148248D01*
X868655Y147956D01*
X868405Y147748D01*
X867988Y147581D01*
X867613Y147539D01*
X867238Y147623D01*
X866988Y147748D01*
X866738Y147998D01*
X866571Y148289D01*
X866488Y148581D01*
Y148873D01*
X866571Y149164D01*
X866696Y149414D01*
X866863Y149623D01*
G01X868571Y150889D02*
X868821Y151139D01*
X868946Y151431D01*
X868988Y151764D01*
X868905Y152181D01*
X868696Y152473D01*
X868446Y152556D01*
X868196Y152514D01*
X867988Y152348D01*
X867571Y151514D01*
X867280Y151139D01*
X866863Y150889D01*
X866488Y150806D01*
Y152556D01*
G01X866863Y153864D02*
X866655Y154114D01*
X866530Y154406D01*
X866488Y154781D01*
X866571Y155156D01*
X866738Y155448D01*
X867030Y155656D01*
X867363Y155698D01*
X867696Y155614D01*
X867905Y155406D01*
X868071Y155114D01*
X868113Y154823D01*
X868071Y154531D01*
X867905Y154156D01*
X868988Y154281D01*
Y155406D01*
G01Y156631D02*
X866488Y157214D01*
X868988Y157881D01*
X866488Y158548D01*
X868988Y159131D01*
G01X866988Y160064D02*
X866696Y160314D01*
X866530Y160648D01*
X866488Y161023D01*
X866530Y161356D01*
X866738Y161689D01*
X866988Y161898D01*
X867238Y161939D01*
X867530Y161856D01*
X867738Y161564D01*
X867821Y161273D01*
Y160898D01*
G01Y161273D02*
X867946Y161523D01*
X868155Y161731D01*
X868405Y161814D01*
X868655Y161731D01*
X868863Y161523D01*
X868988Y161148D01*
X868946Y160773D01*
X868780Y160398D01*
G01X866780Y163373D02*
X866571Y163664D01*
X866488Y163998D01*
X866571Y164331D01*
X866821Y164623D01*
X867196Y164831D01*
X867571Y164914D01*
X868030D01*
X868405Y164831D01*
X868738Y164623D01*
X868905Y164373D01*
X868988Y164081D01*
X868905Y163748D01*
X868738Y163498D01*
X868488Y163331D01*
X868155Y163248D01*
X867863Y163331D01*
X867571Y163539D01*
X867405Y163789D01*
X867363Y164081D01*
X867446Y164414D01*
X867655Y164664D01*
X868030Y164914D01*
G01X888023Y155472D02*
X888273Y155597D01*
X888565Y155680D01*
X888898D01*
X889273Y155555D01*
X889565Y155347D01*
X889773Y155097D01*
X889940Y154680D01*
X889982Y154305D01*
X889898Y153930D01*
X889773Y153680D01*
X889523Y153430D01*
X889232Y153263D01*
X888940Y153180D01*
X888648D01*
X888357Y153263D01*
X888107Y153388D01*
X887898Y153555D01*
G01X886632Y155263D02*
X886382Y155513D01*
X886090Y155638D01*
X885757Y155680D01*
X885340Y155597D01*
X885048Y155388D01*
X884965Y155138D01*
X885007Y154888D01*
X885173Y154680D01*
X886007Y154263D01*
X886382Y153972D01*
X886632Y153555D01*
X886715Y153180D01*
X884965D01*
G01X883657Y153555D02*
X883407Y153347D01*
X883115Y153222D01*
X882740Y153180D01*
X882365Y153263D01*
X882073Y153430D01*
X881865Y153722D01*
X881823Y154055D01*
X881907Y154388D01*
X882115Y154597D01*
X882407Y154763D01*
X882698Y154805D01*
X882990Y154763D01*
X883365Y154597D01*
X883240Y155680D01*
X882115D01*
G01X880890D02*
X880307Y153180D01*
X879640Y155680D01*
X878973Y153180D01*
X878390Y155680D01*
G01X876040Y153180D02*
Y155680D01*
X877582Y153888D01*
X875498D01*
G01X874357Y153680D02*
X874107Y153388D01*
X873773Y153222D01*
X873398Y153180D01*
X873065Y153222D01*
X872732Y153430D01*
X872523Y153680D01*
X872482Y153930D01*
X872565Y154222D01*
X872857Y154430D01*
X873148Y154513D01*
X873523D01*
G01X873148D02*
X872898Y154638D01*
X872690Y154847D01*
X872607Y155097D01*
X872690Y155347D01*
X872898Y155555D01*
X873273Y155680D01*
X873648Y155638D01*
X874023Y155472D01*
G01X864280Y148998D02*
X864405Y148748D01*
X864488Y148456D01*
Y148123D01*
X864363Y147748D01*
X864155Y147456D01*
X863905Y147248D01*
X863488Y147081D01*
X863113Y147039D01*
X862738Y147123D01*
X862488Y147248D01*
X862238Y147498D01*
X862071Y147789D01*
X861988Y148081D01*
Y148373D01*
X862071Y148664D01*
X862196Y148914D01*
X862363Y149123D01*
G01X864071Y150389D02*
X864321Y150639D01*
X864446Y150931D01*
X864488Y151264D01*
X864405Y151681D01*
X864196Y151973D01*
X863946Y152056D01*
X863696Y152014D01*
X863488Y151848D01*
X863071Y151014D01*
X862780Y150639D01*
X862363Y150389D01*
X861988Y150306D01*
Y152056D01*
G01X862363Y153364D02*
X862155Y153614D01*
X862030Y153906D01*
X861988Y154281D01*
X862071Y154656D01*
X862238Y154948D01*
X862530Y155156D01*
X862863Y155198D01*
X863196Y155114D01*
X863405Y154906D01*
X863571Y154614D01*
X863613Y154323D01*
X863571Y154031D01*
X863405Y153656D01*
X864488Y153781D01*
Y154906D01*
G01Y156131D02*
X861988Y156714D01*
X864488Y157381D01*
X861988Y158048D01*
X864488Y158631D01*
G01X862488Y159564D02*
X862196Y159814D01*
X862030Y160148D01*
X861988Y160523D01*
X862030Y160856D01*
X862238Y161189D01*
X862488Y161398D01*
X862738Y161439D01*
X863030Y161356D01*
X863238Y161064D01*
X863321Y160773D01*
Y160398D01*
G01Y160773D02*
X863446Y161023D01*
X863655Y161231D01*
X863905Y161314D01*
X864155Y161231D01*
X864363Y161023D01*
X864488Y160648D01*
X864446Y160273D01*
X864280Y159898D01*
G01X861988Y163581D02*
X862030Y163873D01*
X862155Y164206D01*
X862363Y164414D01*
X862655Y164498D01*
X862946Y164414D01*
X863196Y164164D01*
X863321Y163789D01*
Y163373D01*
X863405Y163123D01*
X863613Y162914D01*
X863905Y162831D01*
X864196Y162956D01*
X864405Y163248D01*
X864488Y163581D01*
X864405Y163914D01*
X864196Y164206D01*
X863905Y164331D01*
X863613Y164248D01*
X863405Y164039D01*
X863321Y163789D01*
Y163373D01*
X863196Y162998D01*
X862946Y162748D01*
X862655Y162664D01*
X862363Y162748D01*
X862155Y162956D01*
X862030Y163289D01*
X861988Y163581D01*
G01X884394Y140130D02*
X884644Y140255D01*
X884936Y140338D01*
X885269D01*
X885644Y140213D01*
X885936Y140005D01*
X886144Y139755D01*
X886311Y139338D01*
X886353Y138963D01*
X886269Y138588D01*
X886144Y138338D01*
X885894Y138088D01*
X885603Y137921D01*
X885311Y137838D01*
X885019D01*
X884728Y137921D01*
X884478Y138046D01*
X884269Y138213D01*
G01X883128D02*
X882878Y138005D01*
X882586Y137880D01*
X882211Y137838D01*
X881836Y137921D01*
X881544Y138088D01*
X881336Y138380D01*
X881294Y138713D01*
X881378Y139046D01*
X881586Y139255D01*
X881878Y139421D01*
X882169Y139463D01*
X882461Y139421D01*
X882836Y139255D01*
X882711Y140338D01*
X881586D01*
G01X880028D02*
Y138546D01*
X879861Y138171D01*
X879528Y137921D01*
X879111Y137838D01*
X878694Y137921D01*
X878361Y138171D01*
X878194Y138546D01*
Y140338D01*
G01X876719Y138130D02*
X876428Y137921D01*
X876094Y137838D01*
X875761Y137921D01*
X875469Y138171D01*
X875261Y138546D01*
X875178Y138921D01*
Y139380D01*
X875261Y139755D01*
X875469Y140088D01*
X875719Y140255D01*
X876011Y140338D01*
X876344Y140255D01*
X876594Y140088D01*
X876761Y139838D01*
X876844Y139505D01*
X876761Y139213D01*
X876553Y138921D01*
X876303Y138755D01*
X876011Y138713D01*
X875678Y138796D01*
X875428Y139005D01*
X875178Y139380D01*
G01X900271Y140249D02*
X900521Y140374D01*
X900813Y140457D01*
X901146D01*
X901521Y140332D01*
X901813Y140124D01*
X902021Y139874D01*
X902188Y139457D01*
X902230Y139082D01*
X902146Y138707D01*
X902021Y138457D01*
X901771Y138207D01*
X901480Y138040D01*
X901188Y137957D01*
X900896D01*
X900605Y138040D01*
X900355Y138165D01*
X900146Y138332D01*
G01X899005D02*
X898755Y138124D01*
X898463Y137999D01*
X898088Y137957D01*
X897713Y138040D01*
X897421Y138207D01*
X897213Y138499D01*
X897171Y138832D01*
X897255Y139165D01*
X897463Y139374D01*
X897755Y139540D01*
X898046Y139582D01*
X898338Y139540D01*
X898713Y139374D01*
X898588Y140457D01*
X897463D01*
G01X895905D02*
Y138665D01*
X895738Y138290D01*
X895405Y138040D01*
X894988Y137957D01*
X894571Y138040D01*
X894238Y138290D01*
X894071Y138665D01*
Y140457D01*
G01X891888Y137957D02*
X891596Y137999D01*
X891263Y138124D01*
X891055Y138332D01*
X890971Y138624D01*
X891055Y138915D01*
X891305Y139165D01*
X891680Y139290D01*
X892096D01*
X892346Y139374D01*
X892555Y139582D01*
X892638Y139874D01*
X892513Y140165D01*
X892221Y140374D01*
X891888Y140457D01*
X891555Y140374D01*
X891263Y140165D01*
X891138Y139874D01*
X891221Y139582D01*
X891430Y139374D01*
X891680Y139290D01*
X892096D01*
X892471Y139165D01*
X892721Y138915D01*
X892805Y138624D01*
X892721Y138332D01*
X892513Y138124D01*
X892180Y137999D01*
X891888Y137957D01*
G01X916837Y140351D02*
X917087Y140476D01*
X917379Y140559D01*
X917712D01*
X918087Y140434D01*
X918379Y140226D01*
X918587Y139976D01*
X918754Y139559D01*
X918796Y139184D01*
X918712Y138809D01*
X918587Y138559D01*
X918337Y138309D01*
X918046Y138142D01*
X917754Y138059D01*
X917462D01*
X917171Y138142D01*
X916921Y138267D01*
X916712Y138434D01*
G01X915571D02*
X915321Y138226D01*
X915029Y138101D01*
X914654Y138059D01*
X914279Y138142D01*
X913987Y138309D01*
X913779Y138601D01*
X913737Y138934D01*
X913821Y139267D01*
X914029Y139476D01*
X914321Y139642D01*
X914612Y139684D01*
X914904Y139642D01*
X915279Y139476D01*
X915154Y140559D01*
X914029D01*
G01X912471D02*
Y138767D01*
X912304Y138392D01*
X911971Y138142D01*
X911554Y138059D01*
X911137Y138142D01*
X910804Y138392D01*
X910637Y138767D01*
Y140559D01*
G01X908537Y138059D02*
X908454Y138601D01*
X908329Y139059D01*
X908162Y139476D01*
X907954Y139934D01*
X907621Y140559D01*
X909287D01*
G01X884394Y148130D02*
X884644Y148255D01*
X884936Y148338D01*
X885269D01*
X885644Y148213D01*
X885936Y148005D01*
X886144Y147755D01*
X886311Y147338D01*
X886353Y146963D01*
X886269Y146588D01*
X886144Y146338D01*
X885894Y146088D01*
X885603Y145921D01*
X885311Y145838D01*
X885019D01*
X884728Y145921D01*
X884478Y146046D01*
X884269Y146213D01*
G01X883128D02*
X882878Y146005D01*
X882586Y145880D01*
X882211Y145838D01*
X881836Y145921D01*
X881544Y146088D01*
X881336Y146380D01*
X881294Y146713D01*
X881378Y147046D01*
X881586Y147255D01*
X881878Y147421D01*
X882169Y147463D01*
X882461Y147421D01*
X882836Y147255D01*
X882711Y148338D01*
X881586D01*
G01X879111D02*
Y145838D01*
G01X880069Y148338D02*
X878153D01*
G01X876011Y145838D02*
Y148338D01*
X876511Y147838D01*
G01Y145838D02*
X875511D01*
G01X873703Y147921D02*
X873453Y148171D01*
X873161Y148296D01*
X872828Y148338D01*
X872411Y148255D01*
X872119Y148046D01*
X872036Y147796D01*
X872078Y147546D01*
X872244Y147338D01*
X873078Y146921D01*
X873453Y146630D01*
X873703Y146213D01*
X873786Y145838D01*
X872036D01*
G01X900271Y148249D02*
X900521Y148374D01*
X900813Y148457D01*
X901146D01*
X901521Y148332D01*
X901813Y148124D01*
X902021Y147874D01*
X902188Y147457D01*
X902230Y147082D01*
X902146Y146707D01*
X902021Y146457D01*
X901771Y146207D01*
X901480Y146040D01*
X901188Y145957D01*
X900896D01*
X900605Y146040D01*
X900355Y146165D01*
X900146Y146332D01*
G01X899005D02*
X898755Y146124D01*
X898463Y145999D01*
X898088Y145957D01*
X897713Y146040D01*
X897421Y146207D01*
X897213Y146499D01*
X897171Y146832D01*
X897255Y147165D01*
X897463Y147374D01*
X897755Y147540D01*
X898046Y147582D01*
X898338Y147540D01*
X898713Y147374D01*
X898588Y148457D01*
X897463D01*
G01X894988D02*
Y145957D01*
G01X895946Y148457D02*
X894030D01*
G01X891888Y145957D02*
Y148457D01*
X892388Y147957D01*
G01Y145957D02*
X891388D01*
G01X888788D02*
Y148457D01*
X889288Y147957D01*
G01Y145957D02*
X888288D01*
G01X916837Y148351D02*
X917087Y148476D01*
X917379Y148559D01*
X917712D01*
X918087Y148434D01*
X918379Y148226D01*
X918587Y147976D01*
X918754Y147559D01*
X918796Y147184D01*
X918712Y146809D01*
X918587Y146559D01*
X918337Y146309D01*
X918046Y146142D01*
X917754Y146059D01*
X917462D01*
X917171Y146142D01*
X916921Y146267D01*
X916712Y146434D01*
G01X915571D02*
X915321Y146226D01*
X915029Y146101D01*
X914654Y146059D01*
X914279Y146142D01*
X913987Y146309D01*
X913779Y146601D01*
X913737Y146934D01*
X913821Y147267D01*
X914029Y147476D01*
X914321Y147642D01*
X914612Y147684D01*
X914904Y147642D01*
X915279Y147476D01*
X915154Y148559D01*
X914029D01*
G01X911554D02*
Y146059D01*
G01X912512Y148559D02*
X910596D01*
G01X908454Y146059D02*
Y148559D01*
X908954Y148059D01*
G01Y146059D02*
X907954D01*
G01X905354Y148559D02*
X905687Y148476D01*
X905937Y148267D01*
X906104Y148017D01*
X906229Y147684D01*
X906271Y147309D01*
X906229Y146934D01*
X906104Y146601D01*
X905937Y146351D01*
X905687Y146142D01*
X905354Y146059D01*
X905021Y146142D01*
X904771Y146351D01*
X904604Y146601D01*
X904479Y146934D01*
X904437Y147309D01*
X904479Y147684D01*
X904604Y148017D01*
X904771Y148267D01*
X905021Y148476D01*
X905354Y148559D01*
G01X856988Y148339D02*
X859488D01*
Y149923D01*
G01X858280Y149339D02*
Y148339D01*
G01X858321Y152564D02*
X858446Y152731D01*
X858655Y152856D01*
X858946Y152939D01*
X859196Y152856D01*
X859363Y152689D01*
X859488Y152398D01*
Y151273D01*
X856988D01*
Y152648D01*
X857155Y152939D01*
X857405Y153106D01*
X857696Y153189D01*
X857988Y153106D01*
X858238Y152856D01*
X858321Y152564D01*
Y151273D01*
G01X859071Y154539D02*
X859321Y154789D01*
X859446Y155081D01*
X859488Y155414D01*
X859405Y155831D01*
X859196Y156123D01*
X858946Y156206D01*
X858696Y156164D01*
X858488Y155998D01*
X858071Y155164D01*
X857780Y154789D01*
X857363Y154539D01*
X856988Y154456D01*
Y156206D01*
G01X859488Y158431D02*
X856988D01*
G01X859488Y157473D02*
Y159389D01*
G01X856988Y161448D02*
X857530Y161531D01*
X857988Y161656D01*
X858405Y161823D01*
X858863Y162031D01*
X859488Y162364D01*
Y160698D01*
G01X906655Y214500D02*
X905045Y217600D01*
G01X906655D02*
X905045Y214500D01*
G01X903593Y217600D02*
Y215378D01*
X903440Y214913D01*
X903133Y214603D01*
X902750Y214500D01*
X902367Y214603D01*
X902060Y214913D01*
X901907Y215378D01*
Y217600D01*
G01X900148Y215533D02*
X899152D01*
G01X897278Y217083D02*
X897048Y217393D01*
X896780Y217548D01*
X896473Y217600D01*
X896090Y217497D01*
X895822Y217238D01*
X895745Y216928D01*
X895783Y216618D01*
X895937Y216360D01*
X896703Y215843D01*
X897048Y215482D01*
X897278Y214965D01*
X897355Y214500D01*
X895745D01*
G01X867833Y168600D02*
Y175600D01*
X862767D01*
G01X864633Y172217D02*
X867833D01*
G01X875906Y205822D02*
X876156Y205947D01*
X876448Y206030D01*
X876781D01*
X877156Y205905D01*
X877448Y205697D01*
X877656Y205447D01*
X877823Y205030D01*
X877865Y204655D01*
X877781Y204280D01*
X877656Y204030D01*
X877406Y203780D01*
X877115Y203613D01*
X876823Y203530D01*
X876531D01*
X876240Y203613D01*
X875990Y203738D01*
X875781Y203905D01*
G01X874515Y205613D02*
X874265Y205863D01*
X873973Y205988D01*
X873640Y206030D01*
X873223Y205947D01*
X872931Y205738D01*
X872848Y205488D01*
X872890Y205238D01*
X873056Y205030D01*
X873890Y204613D01*
X874265Y204322D01*
X874515Y203905D01*
X874598Y203530D01*
X872848D01*
G01X871540Y203905D02*
X871290Y203697D01*
X870998Y203572D01*
X870623Y203530D01*
X870248Y203613D01*
X869956Y203780D01*
X869748Y204072D01*
X869706Y204405D01*
X869790Y204738D01*
X869998Y204947D01*
X870290Y205113D01*
X870581Y205155D01*
X870873Y205113D01*
X871248Y204947D01*
X871123Y206030D01*
X869998D01*
G01X868773D02*
X868190Y203530D01*
X867523Y206030D01*
X866856Y203530D01*
X866273Y206030D01*
G01X863923Y203530D02*
Y206030D01*
X865465Y204238D01*
X863381D01*
G01X861406Y203530D02*
X861323Y204072D01*
X861198Y204530D01*
X861031Y204947D01*
X860823Y205405D01*
X860490Y206030D01*
X862156D01*
G01X859780Y167498D02*
X859905Y167248D01*
X859988Y166956D01*
Y166623D01*
X859863Y166248D01*
X859655Y165956D01*
X859405Y165748D01*
X858988Y165581D01*
X858613Y165539D01*
X858238Y165623D01*
X857988Y165748D01*
X857738Y165998D01*
X857571Y166289D01*
X857488Y166581D01*
Y166873D01*
X857571Y167164D01*
X857696Y167414D01*
X857863Y167623D01*
G01X859571Y168889D02*
X859821Y169139D01*
X859946Y169431D01*
X859988Y169764D01*
X859905Y170181D01*
X859696Y170473D01*
X859446Y170556D01*
X859196Y170514D01*
X858988Y170348D01*
X858571Y169514D01*
X858280Y169139D01*
X857863Y168889D01*
X857488Y168806D01*
Y170556D01*
G01X857863Y171864D02*
X857655Y172114D01*
X857530Y172406D01*
X857488Y172781D01*
X857571Y173156D01*
X857738Y173448D01*
X858030Y173656D01*
X858363Y173698D01*
X858696Y173614D01*
X858905Y173406D01*
X859071Y173114D01*
X859113Y172823D01*
X859071Y172531D01*
X858905Y172156D01*
X859988Y172281D01*
Y173406D01*
G01Y174631D02*
X857488Y175214D01*
X859988Y175881D01*
X857488Y176548D01*
X859988Y177131D01*
G01X857988Y178064D02*
X857696Y178314D01*
X857530Y178648D01*
X857488Y179023D01*
X857530Y179356D01*
X857738Y179689D01*
X857988Y179898D01*
X858238Y179939D01*
X858530Y179856D01*
X858738Y179564D01*
X858821Y179273D01*
Y178898D01*
G01Y179273D02*
X858946Y179523D01*
X859155Y179731D01*
X859405Y179814D01*
X859655Y179731D01*
X859863Y179523D01*
X859988Y179148D01*
X859946Y178773D01*
X859780Y178398D01*
G01X859988Y182081D02*
X859905Y181748D01*
X859696Y181498D01*
X859446Y181331D01*
X859113Y181206D01*
X858738Y181164D01*
X858363Y181206D01*
X858030Y181331D01*
X857780Y181498D01*
X857571Y181748D01*
X857488Y182081D01*
X857571Y182414D01*
X857780Y182664D01*
X858030Y182831D01*
X858363Y182956D01*
X858738Y182998D01*
X859113Y182956D01*
X859446Y182831D01*
X859696Y182664D01*
X859905Y182414D01*
X859988Y182081D01*
G01X879333Y185392D02*
X879583Y185517D01*
X879875Y185600D01*
X880208D01*
X880583Y185475D01*
X880875Y185267D01*
X881083Y185017D01*
X881250Y184600D01*
X881292Y184225D01*
X881208Y183850D01*
X881083Y183600D01*
X880833Y183350D01*
X880542Y183183D01*
X880250Y183100D01*
X879958D01*
X879667Y183183D01*
X879417Y183308D01*
X879208Y183475D01*
G01X877942Y185183D02*
X877692Y185433D01*
X877400Y185558D01*
X877067Y185600D01*
X876650Y185517D01*
X876358Y185308D01*
X876275Y185058D01*
X876317Y184808D01*
X876483Y184600D01*
X877317Y184183D01*
X877692Y183892D01*
X877942Y183475D01*
X878025Y183100D01*
X876275D01*
G01X874967Y183475D02*
X874717Y183267D01*
X874425Y183142D01*
X874050Y183100D01*
X873675Y183183D01*
X873383Y183350D01*
X873175Y183642D01*
X873133Y183975D01*
X873217Y184308D01*
X873425Y184517D01*
X873717Y184683D01*
X874008Y184725D01*
X874300Y184683D01*
X874675Y184517D01*
X874550Y185600D01*
X873425D01*
G01X872200D02*
X871617Y183100D01*
X870950Y185600D01*
X870283Y183100D01*
X869700Y185600D01*
G01X868642Y185183D02*
X868392Y185433D01*
X868100Y185558D01*
X867767Y185600D01*
X867350Y185517D01*
X867058Y185308D01*
X866975Y185058D01*
X867017Y184808D01*
X867183Y184600D01*
X868017Y184183D01*
X868392Y183892D01*
X868642Y183475D01*
X868725Y183100D01*
X866975D01*
G01X865458Y183392D02*
X865167Y183183D01*
X864833Y183100D01*
X864500Y183183D01*
X864208Y183433D01*
X864000Y183808D01*
X863917Y184183D01*
Y184642D01*
X864000Y185017D01*
X864208Y185350D01*
X864458Y185517D01*
X864750Y185600D01*
X865083Y185517D01*
X865333Y185350D01*
X865500Y185100D01*
X865583Y184767D01*
X865500Y184475D01*
X865292Y184183D01*
X865042Y184017D01*
X864750Y183975D01*
X864417Y184058D01*
X864167Y184267D01*
X863917Y184642D01*
G01X879333Y188892D02*
X879583Y189017D01*
X879875Y189100D01*
X880208D01*
X880583Y188975D01*
X880875Y188767D01*
X881083Y188517D01*
X881250Y188100D01*
X881292Y187725D01*
X881208Y187350D01*
X881083Y187100D01*
X880833Y186850D01*
X880542Y186683D01*
X880250Y186600D01*
X879958D01*
X879667Y186683D01*
X879417Y186808D01*
X879208Y186975D01*
G01X877942Y188683D02*
X877692Y188933D01*
X877400Y189058D01*
X877067Y189100D01*
X876650Y189017D01*
X876358Y188808D01*
X876275Y188558D01*
X876317Y188308D01*
X876483Y188100D01*
X877317Y187683D01*
X877692Y187392D01*
X877942Y186975D01*
X878025Y186600D01*
X876275D01*
G01X874967Y186975D02*
X874717Y186767D01*
X874425Y186642D01*
X874050Y186600D01*
X873675Y186683D01*
X873383Y186850D01*
X873175Y187142D01*
X873133Y187475D01*
X873217Y187808D01*
X873425Y188017D01*
X873717Y188183D01*
X874008Y188225D01*
X874300Y188183D01*
X874675Y188017D01*
X874550Y189100D01*
X873425D01*
G01X872200D02*
X871617Y186600D01*
X870950Y189100D01*
X870283Y186600D01*
X869700Y189100D01*
G01X868642Y188683D02*
X868392Y188933D01*
X868100Y189058D01*
X867767Y189100D01*
X867350Y189017D01*
X867058Y188808D01*
X866975Y188558D01*
X867017Y188308D01*
X867183Y188100D01*
X868017Y187683D01*
X868392Y187392D01*
X868642Y186975D01*
X868725Y186600D01*
X866975D01*
G01X864250D02*
Y189100D01*
X865792Y187308D01*
X863708D01*
G01X873261Y195478D02*
X873511Y195603D01*
X873803Y195686D01*
X874136D01*
X874511Y195561D01*
X874803Y195353D01*
X875011Y195103D01*
X875178Y194686D01*
X875220Y194311D01*
X875136Y193936D01*
X875011Y193686D01*
X874761Y193436D01*
X874470Y193269D01*
X874178Y193186D01*
X873886D01*
X873595Y193269D01*
X873345Y193394D01*
X873136Y193561D01*
G01X871870Y195269D02*
X871620Y195519D01*
X871328Y195644D01*
X870995Y195686D01*
X870578Y195603D01*
X870286Y195394D01*
X870203Y195144D01*
X870245Y194894D01*
X870411Y194686D01*
X871245Y194269D01*
X871620Y193978D01*
X871870Y193561D01*
X871953Y193186D01*
X870203D01*
G01X868895Y193561D02*
X868645Y193353D01*
X868353Y193228D01*
X867978Y193186D01*
X867603Y193269D01*
X867311Y193436D01*
X867103Y193728D01*
X867061Y194061D01*
X867145Y194394D01*
X867353Y194603D01*
X867645Y194769D01*
X867936Y194811D01*
X868228Y194769D01*
X868603Y194603D01*
X868478Y195686D01*
X867353D01*
G01X866128D02*
X865545Y193186D01*
X864878Y195686D01*
X864211Y193186D01*
X863628Y195686D01*
G01X862570Y195269D02*
X862320Y195519D01*
X862028Y195644D01*
X861695Y195686D01*
X861278Y195603D01*
X860986Y195394D01*
X860903Y195144D01*
X860945Y194894D01*
X861111Y194686D01*
X861945Y194269D01*
X862320Y193978D01*
X862570Y193561D01*
X862653Y193186D01*
X860903D01*
G01X859470Y194228D02*
X859178Y194519D01*
X858928Y194686D01*
X858595Y194769D01*
X858303Y194686D01*
X858095Y194519D01*
X857928Y194269D01*
X857886Y193978D01*
X857928Y193728D01*
X858095Y193478D01*
X858345Y193269D01*
X858636Y193186D01*
X858970Y193269D01*
X859261Y193519D01*
X859428Y193894D01*
X859470Y194311D01*
X859386Y194853D01*
X859261Y195144D01*
X859053Y195436D01*
X858761Y195644D01*
X858470Y195686D01*
X858178Y195603D01*
X857970Y195394D01*
G01X889492Y173767D02*
X889617Y173517D01*
X889700Y173225D01*
Y172892D01*
X889575Y172517D01*
X889367Y172225D01*
X889117Y172017D01*
X888700Y171850D01*
X888325Y171808D01*
X887950Y171892D01*
X887700Y172017D01*
X887450Y172267D01*
X887283Y172558D01*
X887200Y172850D01*
Y173142D01*
X887283Y173433D01*
X887408Y173683D01*
X887575Y173892D01*
G01X889283Y175158D02*
X889533Y175408D01*
X889658Y175700D01*
X889700Y176033D01*
X889617Y176450D01*
X889408Y176742D01*
X889158Y176825D01*
X888908Y176783D01*
X888700Y176617D01*
X888283Y175783D01*
X887992Y175408D01*
X887575Y175158D01*
X887200Y175075D01*
Y176825D01*
G01X887575Y178133D02*
X887367Y178383D01*
X887242Y178675D01*
X887200Y179050D01*
X887283Y179425D01*
X887450Y179717D01*
X887742Y179925D01*
X888075Y179967D01*
X888408Y179883D01*
X888617Y179675D01*
X888783Y179383D01*
X888825Y179092D01*
X888783Y178800D01*
X888617Y178425D01*
X889700Y178550D01*
Y179675D01*
G01Y180900D02*
X887200Y181483D01*
X889700Y182150D01*
X887200Y182817D01*
X889700Y183400D01*
G01X887575Y184333D02*
X887367Y184583D01*
X887242Y184875D01*
X887200Y185250D01*
X887283Y185625D01*
X887450Y185917D01*
X887742Y186125D01*
X888075Y186167D01*
X888408Y186083D01*
X888617Y185875D01*
X888783Y185583D01*
X888825Y185292D01*
X888783Y185000D01*
X888617Y184625D01*
X889700Y184750D01*
Y185875D01*
G01X887700Y187433D02*
X887408Y187683D01*
X887242Y188017D01*
X887200Y188392D01*
X887242Y188725D01*
X887450Y189058D01*
X887700Y189267D01*
X887950Y189308D01*
X888242Y189225D01*
X888450Y188933D01*
X888533Y188642D01*
Y188267D01*
G01Y188642D02*
X888658Y188892D01*
X888867Y189100D01*
X889117Y189183D01*
X889367Y189100D01*
X889575Y188892D01*
X889700Y188517D01*
X889658Y188142D01*
X889492Y187767D01*
G01X896353Y206482D02*
X896603Y206607D01*
X896895Y206690D01*
X897228D01*
X897603Y206565D01*
X897895Y206357D01*
X898103Y206107D01*
X898270Y205690D01*
X898312Y205315D01*
X898228Y204940D01*
X898103Y204690D01*
X897853Y204440D01*
X897562Y204273D01*
X897270Y204190D01*
X896978D01*
X896687Y204273D01*
X896437Y204398D01*
X896228Y204565D01*
G01X894962Y206273D02*
X894712Y206523D01*
X894420Y206648D01*
X894087Y206690D01*
X893670Y206607D01*
X893378Y206398D01*
X893295Y206148D01*
X893337Y205898D01*
X893503Y205690D01*
X894337Y205273D01*
X894712Y204982D01*
X894962Y204565D01*
X895045Y204190D01*
X893295D01*
G01X891987Y204565D02*
X891737Y204357D01*
X891445Y204232D01*
X891070Y204190D01*
X890695Y204273D01*
X890403Y204440D01*
X890195Y204732D01*
X890153Y205065D01*
X890237Y205398D01*
X890445Y205607D01*
X890737Y205773D01*
X891028Y205815D01*
X891320Y205773D01*
X891695Y205607D01*
X891570Y206690D01*
X890445D01*
G01X889220D02*
X888637Y204190D01*
X887970Y206690D01*
X887303Y204190D01*
X886720Y206690D01*
G01X884370Y204190D02*
Y206690D01*
X885912Y204898D01*
X883828D01*
G01X881770Y204190D02*
Y206690D01*
X882270Y206190D01*
G01Y204190D02*
X881270D01*
G01X892439Y201491D02*
X892689Y201616D01*
X892981Y201699D01*
X893314D01*
X893689Y201574D01*
X893981Y201366D01*
X894189Y201116D01*
X894356Y200699D01*
X894398Y200324D01*
X894314Y199949D01*
X894189Y199699D01*
X893939Y199449D01*
X893648Y199282D01*
X893356Y199199D01*
X893064D01*
X892773Y199282D01*
X892523Y199407D01*
X892314Y199574D01*
G01X891048Y201282D02*
X890798Y201532D01*
X890506Y201657D01*
X890173Y201699D01*
X889756Y201616D01*
X889464Y201407D01*
X889381Y201157D01*
X889423Y200907D01*
X889589Y200699D01*
X890423Y200282D01*
X890798Y199991D01*
X891048Y199574D01*
X891131Y199199D01*
X889381D01*
G01X888073Y199574D02*
X887823Y199366D01*
X887531Y199241D01*
X887156Y199199D01*
X886781Y199282D01*
X886489Y199449D01*
X886281Y199741D01*
X886239Y200074D01*
X886323Y200407D01*
X886531Y200616D01*
X886823Y200782D01*
X887114Y200824D01*
X887406Y200782D01*
X887781Y200616D01*
X887656Y201699D01*
X886531D01*
G01X885306D02*
X884723Y199199D01*
X884056Y201699D01*
X883389Y199199D01*
X882806Y201699D01*
G01X880456Y199199D02*
Y201699D01*
X881998Y199907D01*
X879914D01*
G01X877356Y199199D02*
Y201699D01*
X878898Y199907D01*
X876814D01*
G01X895223Y193640D02*
X895473Y193765D01*
X895765Y193848D01*
X896098D01*
X896473Y193723D01*
X896765Y193515D01*
X896973Y193265D01*
X897140Y192848D01*
X897182Y192473D01*
X897098Y192098D01*
X896973Y191848D01*
X896723Y191598D01*
X896432Y191431D01*
X896140Y191348D01*
X895848D01*
X895557Y191431D01*
X895307Y191556D01*
X895098Y191723D01*
G01X893832Y193431D02*
X893582Y193681D01*
X893290Y193806D01*
X892957Y193848D01*
X892540Y193765D01*
X892248Y193556D01*
X892165Y193306D01*
X892207Y193056D01*
X892373Y192848D01*
X893207Y192431D01*
X893582Y192140D01*
X893832Y191723D01*
X893915Y191348D01*
X892165D01*
G01X890857Y191723D02*
X890607Y191515D01*
X890315Y191390D01*
X889940Y191348D01*
X889565Y191431D01*
X889273Y191598D01*
X889065Y191890D01*
X889023Y192223D01*
X889107Y192556D01*
X889315Y192765D01*
X889607Y192931D01*
X889898Y192973D01*
X890190Y192931D01*
X890565Y192765D01*
X890440Y193848D01*
X889315D01*
G01X888090D02*
X887507Y191348D01*
X886840Y193848D01*
X886173Y191348D01*
X885590Y193848D01*
G01X884657Y191723D02*
X884407Y191515D01*
X884115Y191390D01*
X883740Y191348D01*
X883365Y191431D01*
X883073Y191598D01*
X882865Y191890D01*
X882823Y192223D01*
X882907Y192556D01*
X883115Y192765D01*
X883407Y192931D01*
X883698Y192973D01*
X883990Y192931D01*
X884365Y192765D01*
X884240Y193848D01*
X883115D01*
G01X881432Y193431D02*
X881182Y193681D01*
X880890Y193806D01*
X880557Y193848D01*
X880140Y193765D01*
X879848Y193556D01*
X879765Y193306D01*
X879807Y193056D01*
X879973Y192848D01*
X880807Y192431D01*
X881182Y192140D01*
X881432Y191723D01*
X881515Y191348D01*
X879765D01*
G01X877992Y162567D02*
X878117Y162317D01*
X878200Y162025D01*
Y161692D01*
X878075Y161317D01*
X877867Y161025D01*
X877617Y160817D01*
X877200Y160650D01*
X876825Y160608D01*
X876450Y160692D01*
X876200Y160817D01*
X875950Y161067D01*
X875783Y161358D01*
X875700Y161650D01*
Y161942D01*
X875783Y162233D01*
X875908Y162483D01*
X876075Y162692D01*
G01X877783Y163958D02*
X878033Y164208D01*
X878158Y164500D01*
X878200Y164833D01*
X878117Y165250D01*
X877908Y165542D01*
X877658Y165625D01*
X877408Y165583D01*
X877200Y165417D01*
X876783Y164583D01*
X876492Y164208D01*
X876075Y163958D01*
X875700Y163875D01*
Y165625D01*
G01X876075Y166933D02*
X875867Y167183D01*
X875742Y167475D01*
X875700Y167850D01*
X875783Y168225D01*
X875950Y168517D01*
X876242Y168725D01*
X876575Y168767D01*
X876908Y168683D01*
X877117Y168475D01*
X877283Y168183D01*
X877325Y167892D01*
X877283Y167600D01*
X877117Y167225D01*
X878200Y167350D01*
Y168475D01*
G01Y169700D02*
X875700Y170283D01*
X878200Y170950D01*
X875700Y171617D01*
X878200Y172200D01*
G01X877783Y173258D02*
X878033Y173508D01*
X878158Y173800D01*
X878200Y174133D01*
X878117Y174550D01*
X877908Y174842D01*
X877658Y174925D01*
X877408Y174883D01*
X877200Y174717D01*
X876783Y173883D01*
X876492Y173508D01*
X876075Y173258D01*
X875700Y173175D01*
Y174925D01*
G01Y177067D02*
X876242Y177150D01*
X876700Y177275D01*
X877117Y177442D01*
X877575Y177650D01*
X878200Y177983D01*
Y176317D01*
G01X894590Y159328D02*
X894715Y159078D01*
X894798Y158786D01*
Y158453D01*
X894673Y158078D01*
X894465Y157786D01*
X894215Y157578D01*
X893798Y157411D01*
X893423Y157369D01*
X893048Y157453D01*
X892798Y157578D01*
X892548Y157828D01*
X892381Y158119D01*
X892298Y158411D01*
Y158703D01*
X892381Y158994D01*
X892506Y159244D01*
X892673Y159453D01*
G01X894381Y160719D02*
X894631Y160969D01*
X894756Y161261D01*
X894798Y161594D01*
X894715Y162011D01*
X894506Y162303D01*
X894256Y162386D01*
X894006Y162344D01*
X893798Y162178D01*
X893381Y161344D01*
X893090Y160969D01*
X892673Y160719D01*
X892298Y160636D01*
Y162386D01*
G01X892673Y163694D02*
X892465Y163944D01*
X892340Y164236D01*
X892298Y164611D01*
X892381Y164986D01*
X892548Y165278D01*
X892840Y165486D01*
X893173Y165528D01*
X893506Y165444D01*
X893715Y165236D01*
X893881Y164944D01*
X893923Y164653D01*
X893881Y164361D01*
X893715Y163986D01*
X894798Y164111D01*
Y165236D01*
G01Y166461D02*
X892298Y167044D01*
X894798Y167711D01*
X892298Y168378D01*
X894798Y168961D01*
G01X892673Y169894D02*
X892465Y170144D01*
X892340Y170436D01*
X892298Y170811D01*
X892381Y171186D01*
X892548Y171478D01*
X892840Y171686D01*
X893173Y171728D01*
X893506Y171644D01*
X893715Y171436D01*
X893881Y171144D01*
X893923Y170853D01*
X893881Y170561D01*
X893715Y170186D01*
X894798Y170311D01*
Y171436D01*
G01X892298Y174411D02*
X894798D01*
X893006Y172869D01*
Y174953D01*
G01X853280Y160498D02*
X853405Y160248D01*
X853488Y159956D01*
Y159623D01*
X853363Y159248D01*
X853155Y158956D01*
X852905Y158748D01*
X852488Y158581D01*
X852113Y158539D01*
X851738Y158623D01*
X851488Y158748D01*
X851238Y158998D01*
X851071Y159289D01*
X850988Y159581D01*
Y159873D01*
X851071Y160164D01*
X851196Y160414D01*
X851363Y160623D01*
G01X853071Y161889D02*
X853321Y162139D01*
X853446Y162431D01*
X853488Y162764D01*
X853405Y163181D01*
X853196Y163473D01*
X852946Y163556D01*
X852696Y163514D01*
X852488Y163348D01*
X852071Y162514D01*
X851780Y162139D01*
X851363Y161889D01*
X850988Y161806D01*
Y163556D01*
G01X851363Y164864D02*
X851155Y165114D01*
X851030Y165406D01*
X850988Y165781D01*
X851071Y166156D01*
X851238Y166448D01*
X851530Y166656D01*
X851863Y166698D01*
X852196Y166614D01*
X852405Y166406D01*
X852571Y166114D01*
X852613Y165823D01*
X852571Y165531D01*
X852405Y165156D01*
X853488Y165281D01*
Y166406D01*
G01Y167631D02*
X850988Y168214D01*
X853488Y168881D01*
X850988Y169548D01*
X853488Y170131D01*
G01X853071Y171189D02*
X853321Y171439D01*
X853446Y171731D01*
X853488Y172064D01*
X853405Y172481D01*
X853196Y172773D01*
X852946Y172856D01*
X852696Y172814D01*
X852488Y172648D01*
X852071Y171814D01*
X851780Y171439D01*
X851363Y171189D01*
X850988Y171106D01*
Y172856D01*
G01X851488Y174164D02*
X851196Y174414D01*
X851030Y174748D01*
X850988Y175123D01*
X851030Y175456D01*
X851238Y175789D01*
X851488Y175998D01*
X851738Y176039D01*
X852030Y175956D01*
X852238Y175664D01*
X852321Y175373D01*
Y174998D01*
G01Y175373D02*
X852446Y175623D01*
X852655Y175831D01*
X852905Y175914D01*
X853155Y175831D01*
X853363Y175623D01*
X853488Y175248D01*
X853446Y174873D01*
X853280Y174498D01*
G01X856175Y182170D02*
X856300Y181920D01*
X856383Y181628D01*
Y181295D01*
X856258Y180920D01*
X856050Y180628D01*
X855800Y180420D01*
X855383Y180253D01*
X855008Y180211D01*
X854633Y180295D01*
X854383Y180420D01*
X854133Y180670D01*
X853966Y180961D01*
X853883Y181253D01*
Y181545D01*
X853966Y181836D01*
X854091Y182086D01*
X854258Y182295D01*
G01X855966Y183561D02*
X856216Y183811D01*
X856341Y184103D01*
X856383Y184436D01*
X856300Y184853D01*
X856091Y185145D01*
X855841Y185228D01*
X855591Y185186D01*
X855383Y185020D01*
X854966Y184186D01*
X854675Y183811D01*
X854258Y183561D01*
X853883Y183478D01*
Y185228D01*
G01X854258Y186536D02*
X854050Y186786D01*
X853925Y187078D01*
X853883Y187453D01*
X853966Y187828D01*
X854133Y188120D01*
X854425Y188328D01*
X854758Y188370D01*
X855091Y188286D01*
X855300Y188078D01*
X855466Y187786D01*
X855508Y187495D01*
X855466Y187203D01*
X855300Y186828D01*
X856383Y186953D01*
Y188078D01*
G01Y189303D02*
X853883Y189886D01*
X856383Y190553D01*
X853883Y191220D01*
X856383Y191803D01*
G01X855966Y192861D02*
X856216Y193111D01*
X856341Y193403D01*
X856383Y193736D01*
X856300Y194153D01*
X856091Y194445D01*
X855841Y194528D01*
X855591Y194486D01*
X855383Y194320D01*
X854966Y193486D01*
X854675Y193111D01*
X854258Y192861D01*
X853883Y192778D01*
Y194528D01*
G01Y196753D02*
X853925Y197045D01*
X854050Y197378D01*
X854258Y197586D01*
X854550Y197670D01*
X854841Y197586D01*
X855091Y197336D01*
X855216Y196961D01*
Y196545D01*
X855300Y196295D01*
X855508Y196086D01*
X855800Y196003D01*
X856091Y196128D01*
X856300Y196420D01*
X856383Y196753D01*
X856300Y197086D01*
X856091Y197378D01*
X855800Y197503D01*
X855508Y197420D01*
X855300Y197211D01*
X855216Y196961D01*
Y196545D01*
X855091Y196170D01*
X854841Y195920D01*
X854550Y195836D01*
X854258Y195920D01*
X854050Y196128D01*
X853925Y196461D01*
X853883Y196753D01*
G01X885492Y173767D02*
X885617Y173517D01*
X885700Y173225D01*
Y172892D01*
X885575Y172517D01*
X885367Y172225D01*
X885117Y172017D01*
X884700Y171850D01*
X884325Y171808D01*
X883950Y171892D01*
X883700Y172017D01*
X883450Y172267D01*
X883283Y172558D01*
X883200Y172850D01*
Y173142D01*
X883283Y173433D01*
X883408Y173683D01*
X883575Y173892D01*
G01X885283Y175158D02*
X885533Y175408D01*
X885658Y175700D01*
X885700Y176033D01*
X885617Y176450D01*
X885408Y176742D01*
X885158Y176825D01*
X884908Y176783D01*
X884700Y176617D01*
X884283Y175783D01*
X883992Y175408D01*
X883575Y175158D01*
X883200Y175075D01*
Y176825D01*
G01X883575Y178133D02*
X883367Y178383D01*
X883242Y178675D01*
X883200Y179050D01*
X883283Y179425D01*
X883450Y179717D01*
X883742Y179925D01*
X884075Y179967D01*
X884408Y179883D01*
X884617Y179675D01*
X884783Y179383D01*
X884825Y179092D01*
X884783Y178800D01*
X884617Y178425D01*
X885700Y178550D01*
Y179675D01*
G01Y180900D02*
X883200Y181483D01*
X885700Y182150D01*
X883200Y182817D01*
X885700Y183400D01*
G01X883575Y184333D02*
X883367Y184583D01*
X883242Y184875D01*
X883200Y185250D01*
X883283Y185625D01*
X883450Y185917D01*
X883742Y186125D01*
X884075Y186167D01*
X884408Y186083D01*
X884617Y185875D01*
X884783Y185583D01*
X884825Y185292D01*
X884783Y185000D01*
X884617Y184625D01*
X885700Y184750D01*
Y185875D01*
G01X883575Y187433D02*
X883367Y187683D01*
X883242Y187975D01*
X883200Y188350D01*
X883283Y188725D01*
X883450Y189017D01*
X883742Y189225D01*
X884075Y189267D01*
X884408Y189183D01*
X884617Y188975D01*
X884783Y188683D01*
X884825Y188392D01*
X884783Y188100D01*
X884617Y187725D01*
X885700Y187850D01*
Y188975D01*
G01X895933Y197776D02*
X896183Y197901D01*
X896475Y197984D01*
X896808D01*
X897183Y197859D01*
X897475Y197651D01*
X897683Y197401D01*
X897850Y196984D01*
X897892Y196609D01*
X897808Y196234D01*
X897683Y195984D01*
X897433Y195734D01*
X897142Y195567D01*
X896850Y195484D01*
X896558D01*
X896267Y195567D01*
X896017Y195692D01*
X895808Y195859D01*
G01X894542Y197567D02*
X894292Y197817D01*
X894000Y197942D01*
X893667Y197984D01*
X893250Y197901D01*
X892958Y197692D01*
X892875Y197442D01*
X892917Y197192D01*
X893083Y196984D01*
X893917Y196567D01*
X894292Y196276D01*
X894542Y195859D01*
X894625Y195484D01*
X892875D01*
G01X891567Y195859D02*
X891317Y195651D01*
X891025Y195526D01*
X890650Y195484D01*
X890275Y195567D01*
X889983Y195734D01*
X889775Y196026D01*
X889733Y196359D01*
X889817Y196692D01*
X890025Y196901D01*
X890317Y197067D01*
X890608Y197109D01*
X890900Y197067D01*
X891275Y196901D01*
X891150Y197984D01*
X890025D01*
G01X888800D02*
X888217Y195484D01*
X887550Y197984D01*
X886883Y195484D01*
X886300Y197984D01*
G01X885367Y195859D02*
X885117Y195651D01*
X884825Y195526D01*
X884450Y195484D01*
X884075Y195567D01*
X883783Y195734D01*
X883575Y196026D01*
X883533Y196359D01*
X883617Y196692D01*
X883825Y196901D01*
X884117Y197067D01*
X884408Y197109D01*
X884700Y197067D01*
X885075Y196901D01*
X884950Y197984D01*
X883825D01*
G01X881350Y195484D02*
Y197984D01*
X881850Y197484D01*
G01Y195484D02*
X880850D01*
G01X909753Y245847D02*
Y248347D01*
X908712D01*
X908378Y248222D01*
X908170Y248055D01*
X908087Y247722D01*
X908170Y247389D01*
X908420Y247180D01*
X908712Y247055D01*
X909753D01*
G01X908712D02*
X908087Y245847D01*
G01X906737Y246222D02*
X906487Y246014D01*
X906195Y245889D01*
X905820Y245847D01*
X905445Y245930D01*
X905153Y246097D01*
X904945Y246389D01*
X904903Y246722D01*
X904987Y247055D01*
X905195Y247264D01*
X905487Y247430D01*
X905778Y247472D01*
X906070Y247430D01*
X906445Y247264D01*
X906320Y248347D01*
X905195D01*
G01X903553Y245847D02*
Y248347D01*
X902512D01*
X902178Y248222D01*
X901970Y248055D01*
X901887Y247722D01*
X901970Y247389D01*
X902220Y247180D01*
X902512Y247055D01*
X903553D01*
G01X902512D02*
X901887Y245847D01*
G01X899620D02*
Y248347D01*
X900120Y247847D01*
G01Y245847D02*
X899120D01*
G01X910053Y249447D02*
Y251947D01*
X909012D01*
X908678Y251822D01*
X908470Y251655D01*
X908387Y251322D01*
X908470Y250989D01*
X908720Y250780D01*
X909012Y250655D01*
X910053D01*
G01X909012D02*
X908387Y249447D01*
G01X907037Y249822D02*
X906787Y249614D01*
X906495Y249489D01*
X906120Y249447D01*
X905745Y249530D01*
X905453Y249697D01*
X905245Y249989D01*
X905203Y250322D01*
X905287Y250655D01*
X905495Y250864D01*
X905787Y251030D01*
X906078Y251072D01*
X906370Y251030D01*
X906745Y250864D01*
X906620Y251947D01*
X905495D01*
G01X903853Y249447D02*
Y251947D01*
X902853D01*
X902520Y251822D01*
X902270Y251530D01*
X902187Y251197D01*
X902270Y250864D01*
X902478Y250614D01*
X902853Y250489D01*
X903853D01*
G01X899420Y249447D02*
Y251947D01*
X900962Y250155D01*
X898878D01*
G01X898050Y260367D02*
X900550D01*
Y261408D01*
X900425Y261742D01*
X900258Y261950D01*
X899925Y262033D01*
X899592Y261950D01*
X899383Y261700D01*
X899258Y261408D01*
Y260367D01*
G01Y261408D02*
X898050Y262033D01*
G01Y264800D02*
X900550D01*
X898758Y263258D01*
Y265342D01*
G01X898050Y268233D02*
Y266567D01*
X900550D01*
Y268233D01*
G01X899342Y267567D02*
Y266567D01*
G01X898050Y270500D02*
X900550D01*
X900050Y270000D01*
G01X898050D02*
Y271000D01*
G01Y274100D02*
X900550D01*
X898758Y272558D01*
Y274642D01*
G01X901650Y260267D02*
X904150D01*
Y261308D01*
X904025Y261642D01*
X903858Y261850D01*
X903525Y261933D01*
X903192Y261850D01*
X902983Y261600D01*
X902858Y261308D01*
Y260267D01*
G01Y261308D02*
X901650Y261933D01*
G01Y264700D02*
X904150D01*
X902358Y263158D01*
Y265242D01*
G01X901650Y268133D02*
Y266467D01*
X904150D01*
Y268133D01*
G01X902942Y267467D02*
Y266467D01*
G01X901650Y270400D02*
X904150D01*
X903650Y269900D01*
G01X901650D02*
Y270900D01*
G01Y273500D02*
X901692Y273792D01*
X901817Y274125D01*
X902025Y274333D01*
X902317Y274417D01*
X902608Y274333D01*
X902858Y274083D01*
X902983Y273708D01*
Y273292D01*
X903067Y273042D01*
X903275Y272833D01*
X903567Y272750D01*
X903858Y272875D01*
X904067Y273167D01*
X904150Y273500D01*
X904067Y273833D01*
X903858Y274125D01*
X903567Y274250D01*
X903275Y274167D01*
X903067Y273958D01*
X902983Y273708D01*
Y273292D01*
X902858Y272917D01*
X902608Y272667D01*
X902317Y272583D01*
X902025Y272667D01*
X901817Y272875D01*
X901692Y273208D01*
X901650Y273500D01*
G01X858433Y239092D02*
X858683Y239217D01*
X858975Y239300D01*
X859308D01*
X859683Y239175D01*
X859975Y238967D01*
X860183Y238717D01*
X860350Y238300D01*
X860392Y237925D01*
X860308Y237550D01*
X860183Y237300D01*
X859933Y237050D01*
X859642Y236883D01*
X859350Y236800D01*
X859058D01*
X858767Y236883D01*
X858517Y237008D01*
X858308Y237175D01*
G01X857042Y237842D02*
X856750Y238133D01*
X856500Y238300D01*
X856167Y238383D01*
X855875Y238300D01*
X855667Y238133D01*
X855500Y237883D01*
X855458Y237592D01*
X855500Y237342D01*
X855667Y237092D01*
X855917Y236883D01*
X856208Y236800D01*
X856542Y236883D01*
X856833Y237133D01*
X857000Y237508D01*
X857042Y237925D01*
X856958Y238467D01*
X856833Y238758D01*
X856625Y239050D01*
X856333Y239258D01*
X856042Y239300D01*
X855750Y239217D01*
X855542Y239008D01*
G01X853983Y236800D02*
Y239300D01*
X852942D01*
X852608Y239175D01*
X852400Y239008D01*
X852317Y238675D01*
X852400Y238342D01*
X852650Y238133D01*
X852942Y238008D01*
X853983D01*
G01X852942D02*
X852317Y236800D01*
G01X850133D02*
X850050Y237342D01*
X849925Y237800D01*
X849758Y238217D01*
X849550Y238675D01*
X849217Y239300D01*
X850883D01*
G01X858433Y243292D02*
X858683Y243417D01*
X858975Y243500D01*
X859308D01*
X859683Y243375D01*
X859975Y243167D01*
X860183Y242917D01*
X860350Y242500D01*
X860392Y242125D01*
X860308Y241750D01*
X860183Y241500D01*
X859933Y241250D01*
X859642Y241083D01*
X859350Y241000D01*
X859058D01*
X858767Y241083D01*
X858517Y241208D01*
X858308Y241375D01*
G01X857042Y242042D02*
X856750Y242333D01*
X856500Y242500D01*
X856167Y242583D01*
X855875Y242500D01*
X855667Y242333D01*
X855500Y242083D01*
X855458Y241792D01*
X855500Y241542D01*
X855667Y241292D01*
X855917Y241083D01*
X856208Y241000D01*
X856542Y241083D01*
X856833Y241333D01*
X857000Y241708D01*
X857042Y242125D01*
X856958Y242667D01*
X856833Y242958D01*
X856625Y243250D01*
X856333Y243458D01*
X856042Y243500D01*
X855750Y243417D01*
X855542Y243208D01*
G01X853983Y241000D02*
Y243500D01*
X852942D01*
X852608Y243375D01*
X852400Y243208D01*
X852317Y242875D01*
X852400Y242542D01*
X852650Y242333D01*
X852942Y242208D01*
X853983D01*
G01X852942D02*
X852317Y241000D01*
G01X850842Y243083D02*
X850592Y243333D01*
X850300Y243458D01*
X849967Y243500D01*
X849550Y243417D01*
X849258Y243208D01*
X849175Y242958D01*
X849217Y242708D01*
X849383Y242500D01*
X850217Y242083D01*
X850592Y241792D01*
X850842Y241375D01*
X850925Y241000D01*
X849175D01*
G01X911968Y328423D02*
Y330923D01*
X910927D01*
X910593Y330798D01*
X910385Y330631D01*
X910302Y330298D01*
X910385Y329965D01*
X910635Y329756D01*
X910927Y329631D01*
X911968D01*
G01X910927D02*
X910302Y328423D01*
G01X908952Y328798D02*
X908702Y328590D01*
X908410Y328465D01*
X908035Y328423D01*
X907660Y328506D01*
X907368Y328673D01*
X907160Y328965D01*
X907118Y329298D01*
X907202Y329631D01*
X907410Y329840D01*
X907702Y330006D01*
X907993Y330048D01*
X908285Y330006D01*
X908660Y329840D01*
X908535Y330923D01*
X907410D01*
G01X905768Y328423D02*
Y330923D01*
X904768D01*
X904435Y330798D01*
X904185Y330506D01*
X904102Y330173D01*
X904185Y329840D01*
X904393Y329590D01*
X904768Y329465D01*
X905768D01*
G01X902752Y328923D02*
X902502Y328631D01*
X902168Y328465D01*
X901793Y328423D01*
X901460Y328465D01*
X901127Y328673D01*
X900918Y328923D01*
X900877Y329173D01*
X900960Y329465D01*
X901252Y329673D01*
X901543Y329756D01*
X901918D01*
G01X901543D02*
X901293Y329881D01*
X901085Y330090D01*
X901002Y330340D01*
X901085Y330590D01*
X901293Y330798D01*
X901668Y330923D01*
X902043Y330881D01*
X902418Y330715D01*
G01X911968Y332273D02*
Y334773D01*
X910927D01*
X910593Y334648D01*
X910385Y334481D01*
X910302Y334148D01*
X910385Y333815D01*
X910635Y333606D01*
X910927Y333481D01*
X911968D01*
G01X910927D02*
X910302Y332273D01*
G01X908952Y332648D02*
X908702Y332440D01*
X908410Y332315D01*
X908035Y332273D01*
X907660Y332356D01*
X907368Y332523D01*
X907160Y332815D01*
X907118Y333148D01*
X907202Y333481D01*
X907410Y333690D01*
X907702Y333856D01*
X907993Y333898D01*
X908285Y333856D01*
X908660Y333690D01*
X908535Y334773D01*
X907410D01*
G01X905768Y332273D02*
Y334773D01*
X904768D01*
X904435Y334648D01*
X904185Y334356D01*
X904102Y334023D01*
X904185Y333690D01*
X904393Y333440D01*
X904768Y333315D01*
X905768D01*
G01X902627Y334356D02*
X902377Y334606D01*
X902085Y334731D01*
X901752Y334773D01*
X901335Y334690D01*
X901043Y334481D01*
X900960Y334231D01*
X901002Y333981D01*
X901168Y333773D01*
X902002Y333356D01*
X902377Y333065D01*
X902627Y332648D01*
X902710Y332273D01*
X900960D01*
G01X895633Y339450D02*
Y341950D01*
X894592D01*
X894258Y341825D01*
X894050Y341658D01*
X893967Y341325D01*
X894050Y340992D01*
X894300Y340783D01*
X894592Y340658D01*
X895633D01*
G01X894592D02*
X893967Y339450D01*
G01X891200D02*
Y341950D01*
X892742Y340158D01*
X890658D01*
G01X887683Y341742D02*
X887933Y341867D01*
X888225Y341950D01*
X888558D01*
X888933Y341825D01*
X889225Y341617D01*
X889433Y341367D01*
X889600Y340950D01*
X889642Y340575D01*
X889558Y340200D01*
X889433Y339950D01*
X889183Y339700D01*
X888892Y339533D01*
X888600Y339450D01*
X888308D01*
X888017Y339533D01*
X887767Y339658D01*
X887558Y339825D01*
G01X886417D02*
X886167Y339617D01*
X885875Y339492D01*
X885500Y339450D01*
X885125Y339533D01*
X884833Y339700D01*
X884625Y339992D01*
X884583Y340325D01*
X884667Y340658D01*
X884875Y340867D01*
X885167Y341033D01*
X885458Y341075D01*
X885750Y341033D01*
X886125Y340867D01*
X886000Y341950D01*
X884875D01*
G01X858494Y333700D02*
X858744Y333825D01*
X859036Y333908D01*
X859369D01*
X859744Y333783D01*
X860036Y333575D01*
X860244Y333325D01*
X860411Y332908D01*
X860453Y332533D01*
X860369Y332158D01*
X860244Y331908D01*
X859994Y331658D01*
X859703Y331491D01*
X859411Y331408D01*
X859119D01*
X858828Y331491D01*
X858578Y331616D01*
X858369Y331783D01*
G01X857103Y332450D02*
X856811Y332741D01*
X856561Y332908D01*
X856228Y332991D01*
X855936Y332908D01*
X855728Y332741D01*
X855561Y332491D01*
X855519Y332200D01*
X855561Y331950D01*
X855728Y331700D01*
X855978Y331491D01*
X856269Y331408D01*
X856603Y331491D01*
X856894Y331741D01*
X857061Y332116D01*
X857103Y332533D01*
X857019Y333075D01*
X856894Y333366D01*
X856686Y333658D01*
X856394Y333866D01*
X856103Y333908D01*
X855811Y333825D01*
X855603Y333616D01*
G01X854044Y331408D02*
Y333908D01*
X853044D01*
X852711Y333783D01*
X852461Y333491D01*
X852378Y333158D01*
X852461Y332825D01*
X852669Y332575D01*
X853044Y332450D01*
X854044D01*
G01X851028Y331908D02*
X850778Y331616D01*
X850444Y331450D01*
X850069Y331408D01*
X849736Y331450D01*
X849403Y331658D01*
X849194Y331908D01*
X849153Y332158D01*
X849236Y332450D01*
X849528Y332658D01*
X849819Y332741D01*
X850194D01*
G01X849819D02*
X849569Y332866D01*
X849361Y333075D01*
X849278Y333325D01*
X849361Y333575D01*
X849569Y333783D01*
X849944Y333908D01*
X850319Y333866D01*
X850694Y333700D01*
G01X892883Y376100D02*
Y378600D01*
X891842D01*
X891508Y378475D01*
X891300Y378308D01*
X891217Y377975D01*
X891300Y377642D01*
X891550Y377433D01*
X891842Y377308D01*
X892883D01*
G01X891842D02*
X891217Y376100D01*
G01X889867Y376475D02*
X889617Y376267D01*
X889325Y376142D01*
X888950Y376100D01*
X888575Y376183D01*
X888283Y376350D01*
X888075Y376642D01*
X888033Y376975D01*
X888117Y377308D01*
X888325Y377517D01*
X888617Y377683D01*
X888908Y377725D01*
X889200Y377683D01*
X889575Y377517D01*
X889450Y378600D01*
X888325D01*
G01X886808Y376100D02*
Y378600D01*
X884892Y376100D01*
Y378600D01*
G01X882750Y376100D02*
Y378600D01*
X883250Y378100D01*
G01Y376100D02*
X882250D01*
G01X892883Y372100D02*
Y374600D01*
X891842D01*
X891508Y374475D01*
X891300Y374308D01*
X891217Y373975D01*
X891300Y373642D01*
X891550Y373433D01*
X891842Y373308D01*
X892883D01*
G01X891842D02*
X891217Y372100D01*
G01X889867Y372475D02*
X889617Y372267D01*
X889325Y372142D01*
X888950Y372100D01*
X888575Y372183D01*
X888283Y372350D01*
X888075Y372642D01*
X888033Y372975D01*
X888117Y373308D01*
X888325Y373517D01*
X888617Y373683D01*
X888908Y373725D01*
X889200Y373683D01*
X889575Y373517D01*
X889450Y374600D01*
X888325D01*
G01X886808Y372100D02*
Y374600D01*
X884892Y372100D01*
Y374600D01*
G01X883542Y374183D02*
X883292Y374433D01*
X883000Y374558D01*
X882667Y374600D01*
X882250Y374517D01*
X881958Y374308D01*
X881875Y374058D01*
X881917Y373808D01*
X882083Y373600D01*
X882917Y373183D01*
X883292Y372892D01*
X883542Y372475D01*
X883625Y372100D01*
X881875D01*
G01X892883Y368100D02*
Y370600D01*
X891842D01*
X891508Y370475D01*
X891300Y370308D01*
X891217Y369975D01*
X891300Y369642D01*
X891550Y369433D01*
X891842Y369308D01*
X892883D01*
G01X891842D02*
X891217Y368100D01*
G01X889867Y368475D02*
X889617Y368267D01*
X889325Y368142D01*
X888950Y368100D01*
X888575Y368183D01*
X888283Y368350D01*
X888075Y368642D01*
X888033Y368975D01*
X888117Y369308D01*
X888325Y369517D01*
X888617Y369683D01*
X888908Y369725D01*
X889200Y369683D01*
X889575Y369517D01*
X889450Y370600D01*
X888325D01*
G01X886808Y368100D02*
Y370600D01*
X884892Y368100D01*
Y370600D01*
G01X883667Y368600D02*
X883417Y368308D01*
X883083Y368142D01*
X882708Y368100D01*
X882375Y368142D01*
X882042Y368350D01*
X881833Y368600D01*
X881792Y368850D01*
X881875Y369142D01*
X882167Y369350D01*
X882458Y369433D01*
X882833D01*
G01X882458D02*
X882208Y369558D01*
X882000Y369767D01*
X881917Y370017D01*
X882000Y370267D01*
X882208Y370475D01*
X882583Y370600D01*
X882958Y370558D01*
X883333Y370392D01*
G01X892883Y360100D02*
Y362600D01*
X891842D01*
X891508Y362475D01*
X891300Y362308D01*
X891217Y361975D01*
X891300Y361642D01*
X891550Y361433D01*
X891842Y361308D01*
X892883D01*
G01X891842D02*
X891217Y360100D01*
G01X889867Y360475D02*
X889617Y360267D01*
X889325Y360142D01*
X888950Y360100D01*
X888575Y360183D01*
X888283Y360350D01*
X888075Y360642D01*
X888033Y360975D01*
X888117Y361308D01*
X888325Y361517D01*
X888617Y361683D01*
X888908Y361725D01*
X889200Y361683D01*
X889575Y361517D01*
X889450Y362600D01*
X888325D01*
G01X886808Y360100D02*
Y362600D01*
X884892Y360100D01*
Y362600D01*
G01X883667Y360475D02*
X883417Y360267D01*
X883125Y360142D01*
X882750Y360100D01*
X882375Y360183D01*
X882083Y360350D01*
X881875Y360642D01*
X881833Y360975D01*
X881917Y361308D01*
X882125Y361517D01*
X882417Y361683D01*
X882708Y361725D01*
X883000Y361683D01*
X883375Y361517D01*
X883250Y362600D01*
X882125D01*
G01X892883Y364100D02*
Y366600D01*
X891842D01*
X891508Y366475D01*
X891300Y366308D01*
X891217Y365975D01*
X891300Y365642D01*
X891550Y365433D01*
X891842Y365308D01*
X892883D01*
G01X891842D02*
X891217Y364100D01*
G01X889867Y364475D02*
X889617Y364267D01*
X889325Y364142D01*
X888950Y364100D01*
X888575Y364183D01*
X888283Y364350D01*
X888075Y364642D01*
X888033Y364975D01*
X888117Y365308D01*
X888325Y365517D01*
X888617Y365683D01*
X888908Y365725D01*
X889200Y365683D01*
X889575Y365517D01*
X889450Y366600D01*
X888325D01*
G01X886808Y364100D02*
Y366600D01*
X884892Y364100D01*
Y366600D01*
G01X882250Y364100D02*
Y366600D01*
X883792Y364808D01*
X881708D01*
G01X895183Y343450D02*
Y345950D01*
X894142D01*
X893808Y345825D01*
X893600Y345658D01*
X893517Y345325D01*
X893600Y344992D01*
X893850Y344783D01*
X894142Y344658D01*
X895183D01*
G01X894142D02*
X893517Y343450D01*
G01X890750D02*
Y345950D01*
X892292Y344158D01*
X890208D01*
G01X887233Y345742D02*
X887483Y345867D01*
X887775Y345950D01*
X888108D01*
X888483Y345825D01*
X888775Y345617D01*
X888983Y345367D01*
X889150Y344950D01*
X889192Y344575D01*
X889108Y344200D01*
X888983Y343950D01*
X888733Y343700D01*
X888442Y343533D01*
X888150Y343450D01*
X887858D01*
X887567Y343533D01*
X887317Y343658D01*
X887108Y343825D01*
G01X885050Y343450D02*
Y345950D01*
X885550Y345450D01*
G01Y343450D02*
X884550D01*
G01X915820Y452230D02*
Y459230D01*
G01X910220D02*
Y452230D01*
G01Y455730D02*
X915820D01*
G01X928619Y427400D02*
Y429900D01*
X927578D01*
X927244Y429775D01*
X927036Y429608D01*
X926953Y429275D01*
X927036Y428942D01*
X927286Y428733D01*
X927578Y428608D01*
X928619D01*
G01X927578D02*
X926953Y427400D01*
G01X925478Y429483D02*
X925228Y429733D01*
X924936Y429858D01*
X924603Y429900D01*
X924186Y429817D01*
X923894Y429608D01*
X923811Y429358D01*
X923853Y429108D01*
X924019Y428900D01*
X924853Y428483D01*
X925228Y428192D01*
X925478Y427775D01*
X925561Y427400D01*
X923811D01*
G01X922503Y427775D02*
X922253Y427567D01*
X921961Y427442D01*
X921586Y427400D01*
X921211Y427483D01*
X920919Y427650D01*
X920711Y427942D01*
X920669Y428275D01*
X920753Y428608D01*
X920961Y428817D01*
X921253Y428983D01*
X921544Y429025D01*
X921836Y428983D01*
X922211Y428817D01*
X922086Y429900D01*
X920961D01*
G01X919736D02*
X919153Y427400D01*
X918486Y429900D01*
X917819Y427400D01*
X917236Y429900D01*
G01X915386Y427400D02*
Y429900D01*
X915886Y429400D01*
G01Y427400D02*
X914886D01*
G01X913078Y429483D02*
X912828Y429733D01*
X912536Y429858D01*
X912203Y429900D01*
X911786Y429817D01*
X911494Y429608D01*
X911411Y429358D01*
X911453Y429108D01*
X911619Y428900D01*
X912453Y428483D01*
X912828Y428192D01*
X913078Y427775D01*
X913161Y427400D01*
X911411D01*
G01X910103Y427900D02*
X909853Y427608D01*
X909519Y427442D01*
X909144Y427400D01*
X908811Y427442D01*
X908478Y427650D01*
X908269Y427900D01*
X908228Y428150D01*
X908311Y428442D01*
X908603Y428650D01*
X908894Y428733D01*
X909269D01*
G01X908894D02*
X908644Y428858D01*
X908436Y429067D01*
X908353Y429317D01*
X908436Y429567D01*
X908644Y429775D01*
X909019Y429900D01*
X909394Y429858D01*
X909769Y429692D01*
G01X928969Y435100D02*
Y437600D01*
X927928D01*
X927594Y437475D01*
X927386Y437308D01*
X927303Y436975D01*
X927386Y436642D01*
X927636Y436433D01*
X927928Y436308D01*
X928969D01*
G01X927928D02*
X927303Y435100D01*
G01X925828Y437183D02*
X925578Y437433D01*
X925286Y437558D01*
X924953Y437600D01*
X924536Y437517D01*
X924244Y437308D01*
X924161Y437058D01*
X924203Y436808D01*
X924369Y436600D01*
X925203Y436183D01*
X925578Y435892D01*
X925828Y435475D01*
X925911Y435100D01*
X924161D01*
G01X922853Y435475D02*
X922603Y435267D01*
X922311Y435142D01*
X921936Y435100D01*
X921561Y435183D01*
X921269Y435350D01*
X921061Y435642D01*
X921019Y435975D01*
X921103Y436308D01*
X921311Y436517D01*
X921603Y436683D01*
X921894Y436725D01*
X922186Y436683D01*
X922561Y436517D01*
X922436Y437600D01*
X921311D01*
G01X920086D02*
X919503Y435100D01*
X918836Y437600D01*
X918169Y435100D01*
X917586Y437600D01*
G01X915736Y435100D02*
Y437600D01*
X916236Y437100D01*
G01Y435100D02*
X915236D01*
G01X913428Y437183D02*
X913178Y437433D01*
X912886Y437558D01*
X912553Y437600D01*
X912136Y437517D01*
X911844Y437308D01*
X911761Y437058D01*
X911803Y436808D01*
X911969Y436600D01*
X912803Y436183D01*
X913178Y435892D01*
X913428Y435475D01*
X913511Y435100D01*
X911761D01*
G01X910453Y435475D02*
X910203Y435267D01*
X909911Y435142D01*
X909536Y435100D01*
X909161Y435183D01*
X908869Y435350D01*
X908661Y435642D01*
X908619Y435975D01*
X908703Y436308D01*
X908911Y436517D01*
X909203Y436683D01*
X909494Y436725D01*
X909786Y436683D01*
X910161Y436517D01*
X910036Y437600D01*
X908911D01*
G01X928819Y431300D02*
Y433800D01*
X927778D01*
X927444Y433675D01*
X927236Y433508D01*
X927153Y433175D01*
X927236Y432842D01*
X927486Y432633D01*
X927778Y432508D01*
X928819D01*
G01X927778D02*
X927153Y431300D01*
G01X925678Y433383D02*
X925428Y433633D01*
X925136Y433758D01*
X924803Y433800D01*
X924386Y433717D01*
X924094Y433508D01*
X924011Y433258D01*
X924053Y433008D01*
X924219Y432800D01*
X925053Y432383D01*
X925428Y432092D01*
X925678Y431675D01*
X925761Y431300D01*
X924011D01*
G01X922703Y431675D02*
X922453Y431467D01*
X922161Y431342D01*
X921786Y431300D01*
X921411Y431383D01*
X921119Y431550D01*
X920911Y431842D01*
X920869Y432175D01*
X920953Y432508D01*
X921161Y432717D01*
X921453Y432883D01*
X921744Y432925D01*
X922036Y432883D01*
X922411Y432717D01*
X922286Y433800D01*
X921161D01*
G01X919936D02*
X919353Y431300D01*
X918686Y433800D01*
X918019Y431300D01*
X917436Y433800D01*
G01X915586Y431300D02*
Y433800D01*
X916086Y433300D01*
G01Y431300D02*
X915086D01*
G01X913278Y433383D02*
X913028Y433633D01*
X912736Y433758D01*
X912403Y433800D01*
X911986Y433717D01*
X911694Y433508D01*
X911611Y433258D01*
X911653Y433008D01*
X911819Y432800D01*
X912653Y432383D01*
X913028Y432092D01*
X913278Y431675D01*
X913361Y431300D01*
X911611D01*
G01X908886D02*
Y433800D01*
X910428Y432008D01*
X908344D01*
G01X891830Y441417D02*
X894330D01*
Y442458D01*
X894205Y442792D01*
X894038Y443000D01*
X893705Y443083D01*
X893372Y443000D01*
X893163Y442750D01*
X893038Y442458D01*
Y441417D01*
G01Y442458D02*
X891830Y443083D01*
G01X893913Y444558D02*
X894163Y444808D01*
X894288Y445100D01*
X894330Y445433D01*
X894247Y445850D01*
X894038Y446142D01*
X893788Y446225D01*
X893538Y446183D01*
X893330Y446017D01*
X892913Y445183D01*
X892622Y444808D01*
X892205Y444558D01*
X891830Y444475D01*
Y446225D01*
G01X892205Y447533D02*
X891997Y447783D01*
X891872Y448075D01*
X891830Y448450D01*
X891913Y448825D01*
X892080Y449117D01*
X892372Y449325D01*
X892705Y449367D01*
X893038Y449283D01*
X893247Y449075D01*
X893413Y448783D01*
X893455Y448492D01*
X893413Y448200D01*
X893247Y447825D01*
X894330Y447950D01*
Y449075D01*
G01Y450300D02*
X891830Y450883D01*
X894330Y451550D01*
X891830Y452217D01*
X894330Y452800D01*
G01X891830Y454650D02*
X894330D01*
X893830Y454150D01*
G01X891830D02*
Y455150D01*
G01Y457667D02*
X892372Y457750D01*
X892830Y457875D01*
X893247Y458042D01*
X893705Y458250D01*
X894330Y458583D01*
Y456917D01*
G01X891830Y461350D02*
X894330D01*
X892538Y459808D01*
Y461892D01*
G01X922253Y447230D02*
Y449730D01*
X921212D01*
X920878Y449605D01*
X920670Y449438D01*
X920587Y449105D01*
X920670Y448772D01*
X920920Y448563D01*
X921212Y448438D01*
X922253D01*
G01X921212D02*
X920587Y447230D01*
G01X919112Y449313D02*
X918862Y449563D01*
X918570Y449688D01*
X918237Y449730D01*
X917820Y449647D01*
X917528Y449438D01*
X917445Y449188D01*
X917487Y448938D01*
X917653Y448730D01*
X918487Y448313D01*
X918862Y448022D01*
X919112Y447605D01*
X919195Y447230D01*
X917445D01*
G01X916137Y447605D02*
X915887Y447397D01*
X915595Y447272D01*
X915220Y447230D01*
X914845Y447313D01*
X914553Y447480D01*
X914345Y447772D01*
X914303Y448105D01*
X914387Y448438D01*
X914595Y448647D01*
X914887Y448813D01*
X915178Y448855D01*
X915470Y448813D01*
X915845Y448647D01*
X915720Y449730D01*
X914595D01*
G01X913370D02*
X912787Y447230D01*
X912120Y449730D01*
X911453Y447230D01*
X910870Y449730D01*
G01X909020Y447230D02*
Y449730D01*
X909520Y449230D01*
G01Y447230D02*
X908520D01*
G01X906003D02*
X905920Y447772D01*
X905795Y448230D01*
X905628Y448647D01*
X905420Y449105D01*
X905087Y449730D01*
X906753D01*
G01X902820Y447230D02*
X902528Y447272D01*
X902195Y447397D01*
X901987Y447605D01*
X901903Y447897D01*
X901987Y448188D01*
X902237Y448438D01*
X902612Y448563D01*
X903028D01*
X903278Y448647D01*
X903487Y448855D01*
X903570Y449147D01*
X903445Y449438D01*
X903153Y449647D01*
X902820Y449730D01*
X902487Y449647D01*
X902195Y449438D01*
X902070Y449147D01*
X902153Y448855D01*
X902362Y448647D01*
X902612Y448563D01*
X903028D01*
X903403Y448438D01*
X903653Y448188D01*
X903737Y447897D01*
X903653Y447605D01*
X903445Y447397D01*
X903112Y447272D01*
X902820Y447230D01*
G01X918203Y463730D02*
Y466230D01*
X917162D01*
X916828Y466105D01*
X916620Y465938D01*
X916537Y465605D01*
X916620Y465272D01*
X916870Y465063D01*
X917162Y464938D01*
X918203D01*
G01X917162D02*
X916537Y463730D01*
G01X915062Y465813D02*
X914812Y466063D01*
X914520Y466188D01*
X914187Y466230D01*
X913770Y466147D01*
X913478Y465938D01*
X913395Y465688D01*
X913437Y465438D01*
X913603Y465230D01*
X914437Y464813D01*
X914812Y464522D01*
X915062Y464105D01*
X915145Y463730D01*
X913395D01*
G01X912087Y464105D02*
X911837Y463897D01*
X911545Y463772D01*
X911170Y463730D01*
X910795Y463813D01*
X910503Y463980D01*
X910295Y464272D01*
X910253Y464605D01*
X910337Y464938D01*
X910545Y465147D01*
X910837Y465313D01*
X911128Y465355D01*
X911420Y465313D01*
X911795Y465147D01*
X911670Y466230D01*
X910545D01*
G01X909320D02*
X908737Y463730D01*
X908070Y466230D01*
X907403Y463730D01*
X906820Y466230D01*
G01X904970Y463730D02*
Y466230D01*
X905470Y465730D01*
G01Y463730D02*
X904470D01*
G01X901870D02*
X901578Y463772D01*
X901245Y463897D01*
X901037Y464105D01*
X900953Y464397D01*
X901037Y464688D01*
X901287Y464938D01*
X901662Y465063D01*
X902078D01*
X902328Y465147D01*
X902537Y465355D01*
X902620Y465647D01*
X902495Y465938D01*
X902203Y466147D01*
X901870Y466230D01*
X901537Y466147D01*
X901245Y465938D01*
X901120Y465647D01*
X901203Y465355D01*
X901412Y465147D01*
X901662Y465063D01*
X902078D01*
X902453Y464938D01*
X902703Y464688D01*
X902787Y464397D01*
X902703Y464105D01*
X902495Y463897D01*
X902162Y463772D01*
X901870Y463730D01*
G01X898770Y466230D02*
X899103Y466147D01*
X899353Y465938D01*
X899520Y465688D01*
X899645Y465355D01*
X899687Y464980D01*
X899645Y464605D01*
X899520Y464272D01*
X899353Y464022D01*
X899103Y463813D01*
X898770Y463730D01*
X898437Y463813D01*
X898187Y464022D01*
X898020Y464272D01*
X897895Y464605D01*
X897853Y464980D01*
X897895Y465355D01*
X898020Y465688D01*
X898187Y465938D01*
X898437Y466147D01*
X898770Y466230D01*
G01X887830Y441417D02*
X890330D01*
Y442458D01*
X890205Y442792D01*
X890038Y443000D01*
X889705Y443083D01*
X889372Y443000D01*
X889163Y442750D01*
X889038Y442458D01*
Y441417D01*
G01Y442458D02*
X887830Y443083D01*
G01X889913Y444558D02*
X890163Y444808D01*
X890288Y445100D01*
X890330Y445433D01*
X890247Y445850D01*
X890038Y446142D01*
X889788Y446225D01*
X889538Y446183D01*
X889330Y446017D01*
X888913Y445183D01*
X888622Y444808D01*
X888205Y444558D01*
X887830Y444475D01*
Y446225D01*
G01X888205Y447533D02*
X887997Y447783D01*
X887872Y448075D01*
X887830Y448450D01*
X887913Y448825D01*
X888080Y449117D01*
X888372Y449325D01*
X888705Y449367D01*
X889038Y449283D01*
X889247Y449075D01*
X889413Y448783D01*
X889455Y448492D01*
X889413Y448200D01*
X889247Y447825D01*
X890330Y447950D01*
Y449075D01*
G01Y450300D02*
X887830Y450883D01*
X890330Y451550D01*
X887830Y452217D01*
X890330Y452800D01*
G01X887830Y454650D02*
X890330D01*
X889830Y454150D01*
G01X887830D02*
Y455150D01*
G01Y457750D02*
X887872Y458042D01*
X887997Y458375D01*
X888205Y458583D01*
X888497Y458667D01*
X888788Y458583D01*
X889038Y458333D01*
X889163Y457958D01*
Y457542D01*
X889247Y457292D01*
X889455Y457083D01*
X889747Y457000D01*
X890038Y457125D01*
X890247Y457417D01*
X890330Y457750D01*
X890247Y458083D01*
X890038Y458375D01*
X889747Y458500D01*
X889455Y458417D01*
X889247Y458208D01*
X889163Y457958D01*
Y457542D01*
X889038Y457167D01*
X888788Y456917D01*
X888497Y456833D01*
X888205Y456917D01*
X887997Y457125D01*
X887872Y457458D01*
X887830Y457750D01*
G01X888872Y460058D02*
X889163Y460350D01*
X889330Y460600D01*
X889413Y460933D01*
X889330Y461225D01*
X889163Y461433D01*
X888913Y461600D01*
X888622Y461642D01*
X888372Y461600D01*
X888122Y461433D01*
X887913Y461183D01*
X887830Y460892D01*
X887913Y460558D01*
X888163Y460267D01*
X888538Y460100D01*
X888955Y460058D01*
X889497Y460142D01*
X889788Y460267D01*
X890080Y460475D01*
X890288Y460767D01*
X890330Y461058D01*
X890247Y461350D01*
X890038Y461558D01*
G01X869029Y425745D02*
X869279Y425870D01*
X869571Y425953D01*
X869904D01*
X870279Y425828D01*
X870571Y425620D01*
X870779Y425370D01*
X870946Y424953D01*
X870988Y424578D01*
X870904Y424203D01*
X870779Y423953D01*
X870529Y423703D01*
X870238Y423536D01*
X869946Y423453D01*
X869654D01*
X869363Y423536D01*
X869113Y423661D01*
X868904Y423828D01*
G01X867638Y425536D02*
X867388Y425786D01*
X867096Y425911D01*
X866763Y425953D01*
X866346Y425870D01*
X866054Y425661D01*
X865971Y425411D01*
X866013Y425161D01*
X866179Y424953D01*
X867013Y424536D01*
X867388Y424245D01*
X867638Y423828D01*
X867721Y423453D01*
X865971D01*
G01X864663Y423828D02*
X864413Y423620D01*
X864121Y423495D01*
X863746Y423453D01*
X863371Y423536D01*
X863079Y423703D01*
X862871Y423995D01*
X862829Y424328D01*
X862913Y424661D01*
X863121Y424870D01*
X863413Y425036D01*
X863704Y425078D01*
X863996Y425036D01*
X864371Y424870D01*
X864246Y425953D01*
X863121D01*
G01X861896D02*
X861313Y423453D01*
X860646Y425953D01*
X859979Y423453D01*
X859396Y425953D01*
G01X858463Y423828D02*
X858213Y423620D01*
X857921Y423495D01*
X857546Y423453D01*
X857171Y423536D01*
X856879Y423703D01*
X856671Y423995D01*
X856629Y424328D01*
X856713Y424661D01*
X856921Y424870D01*
X857213Y425036D01*
X857504Y425078D01*
X857796Y425036D01*
X858171Y424870D01*
X858046Y425953D01*
X856921D01*
G01X854446D02*
X854779Y425870D01*
X855029Y425661D01*
X855196Y425411D01*
X855321Y425078D01*
X855363Y424703D01*
X855321Y424328D01*
X855196Y423995D01*
X855029Y423745D01*
X854779Y423536D01*
X854446Y423453D01*
X854113Y423536D01*
X853863Y423745D01*
X853696Y423995D01*
X853571Y424328D01*
X853529Y424703D01*
X853571Y425078D01*
X853696Y425411D01*
X853863Y425661D01*
X854113Y425870D01*
X854446Y425953D01*
G01X881725Y463190D02*
X881850Y462940D01*
X881933Y462648D01*
Y462315D01*
X881808Y461940D01*
X881600Y461648D01*
X881350Y461440D01*
X880933Y461273D01*
X880558Y461231D01*
X880183Y461315D01*
X879933Y461440D01*
X879683Y461690D01*
X879516Y461981D01*
X879433Y462273D01*
Y462565D01*
X879516Y462856D01*
X879641Y463106D01*
X879808Y463315D01*
G01X881516Y464581D02*
X881766Y464831D01*
X881891Y465123D01*
X881933Y465456D01*
X881850Y465873D01*
X881641Y466165D01*
X881391Y466248D01*
X881141Y466206D01*
X880933Y466040D01*
X880516Y465206D01*
X880225Y464831D01*
X879808Y464581D01*
X879433Y464498D01*
Y466248D01*
G01X879808Y467556D02*
X879600Y467806D01*
X879475Y468098D01*
X879433Y468473D01*
X879516Y468848D01*
X879683Y469140D01*
X879975Y469348D01*
X880308Y469390D01*
X880641Y469306D01*
X880850Y469098D01*
X881016Y468806D01*
X881058Y468515D01*
X881016Y468223D01*
X880850Y467848D01*
X881933Y467973D01*
Y469098D01*
G01Y470323D02*
X879433Y470906D01*
X881933Y471573D01*
X879433Y472240D01*
X881933Y472823D01*
G01X879933Y473756D02*
X879641Y474006D01*
X879475Y474340D01*
X879433Y474715D01*
X879475Y475048D01*
X879683Y475381D01*
X879933Y475590D01*
X880183Y475631D01*
X880475Y475548D01*
X880683Y475256D01*
X880766Y474965D01*
Y474590D01*
G01Y474965D02*
X880891Y475215D01*
X881100Y475423D01*
X881350Y475506D01*
X881600Y475423D01*
X881808Y475215D01*
X881933Y474840D01*
X881891Y474465D01*
X881725Y474090D01*
G01X879433Y477690D02*
X879975Y477773D01*
X880433Y477898D01*
X880850Y478065D01*
X881308Y478273D01*
X881933Y478606D01*
Y476940D01*
G01X904469Y429642D02*
X904719Y429767D01*
X905011Y429850D01*
X905344D01*
X905719Y429725D01*
X906011Y429517D01*
X906219Y429267D01*
X906386Y428850D01*
X906428Y428475D01*
X906344Y428100D01*
X906219Y427850D01*
X905969Y427600D01*
X905678Y427433D01*
X905386Y427350D01*
X905094D01*
X904803Y427433D01*
X904553Y427558D01*
X904344Y427725D01*
G01X903078Y429433D02*
X902828Y429683D01*
X902536Y429808D01*
X902203Y429850D01*
X901786Y429767D01*
X901494Y429558D01*
X901411Y429308D01*
X901453Y429058D01*
X901619Y428850D01*
X902453Y428433D01*
X902828Y428142D01*
X903078Y427725D01*
X903161Y427350D01*
X901411D01*
G01X900103Y427725D02*
X899853Y427517D01*
X899561Y427392D01*
X899186Y427350D01*
X898811Y427433D01*
X898519Y427600D01*
X898311Y427892D01*
X898269Y428225D01*
X898353Y428558D01*
X898561Y428767D01*
X898853Y428933D01*
X899144Y428975D01*
X899436Y428933D01*
X899811Y428767D01*
X899686Y429850D01*
X898561D01*
G01X897336D02*
X896753Y427350D01*
X896086Y429850D01*
X895419Y427350D01*
X894836Y429850D01*
G01X893069Y427350D02*
X892986Y427892D01*
X892861Y428350D01*
X892694Y428767D01*
X892486Y429225D01*
X892153Y429850D01*
X893819D01*
G01X890678Y429433D02*
X890428Y429683D01*
X890136Y429808D01*
X889803Y429850D01*
X889386Y429767D01*
X889094Y429558D01*
X889011Y429308D01*
X889053Y429058D01*
X889219Y428850D01*
X890053Y428433D01*
X890428Y428142D01*
X890678Y427725D01*
X890761Y427350D01*
X889011D01*
G01X904469Y433442D02*
X904719Y433567D01*
X905011Y433650D01*
X905344D01*
X905719Y433525D01*
X906011Y433317D01*
X906219Y433067D01*
X906386Y432650D01*
X906428Y432275D01*
X906344Y431900D01*
X906219Y431650D01*
X905969Y431400D01*
X905678Y431233D01*
X905386Y431150D01*
X905094D01*
X904803Y431233D01*
X904553Y431358D01*
X904344Y431525D01*
G01X903078Y433233D02*
X902828Y433483D01*
X902536Y433608D01*
X902203Y433650D01*
X901786Y433567D01*
X901494Y433358D01*
X901411Y433108D01*
X901453Y432858D01*
X901619Y432650D01*
X902453Y432233D01*
X902828Y431942D01*
X903078Y431525D01*
X903161Y431150D01*
X901411D01*
G01X900103Y431525D02*
X899853Y431317D01*
X899561Y431192D01*
X899186Y431150D01*
X898811Y431233D01*
X898519Y431400D01*
X898311Y431692D01*
X898269Y432025D01*
X898353Y432358D01*
X898561Y432567D01*
X898853Y432733D01*
X899144Y432775D01*
X899436Y432733D01*
X899811Y432567D01*
X899686Y433650D01*
X898561D01*
G01X897336D02*
X896753Y431150D01*
X896086Y433650D01*
X895419Y431150D01*
X894836Y433650D01*
G01X893069Y431150D02*
X892986Y431692D01*
X892861Y432150D01*
X892694Y432567D01*
X892486Y433025D01*
X892153Y433650D01*
X893819D01*
G01X890803Y431650D02*
X890553Y431358D01*
X890219Y431192D01*
X889844Y431150D01*
X889511Y431192D01*
X889178Y431400D01*
X888969Y431650D01*
X888928Y431900D01*
X889011Y432192D01*
X889303Y432400D01*
X889594Y432483D01*
X889969D01*
G01X889594D02*
X889344Y432608D01*
X889136Y432817D01*
X889053Y433067D01*
X889136Y433317D01*
X889344Y433525D01*
X889719Y433650D01*
X890094Y433608D01*
X890469Y433442D01*
G01X904469Y437592D02*
X904719Y437717D01*
X905011Y437800D01*
X905344D01*
X905719Y437675D01*
X906011Y437467D01*
X906219Y437217D01*
X906386Y436800D01*
X906428Y436425D01*
X906344Y436050D01*
X906219Y435800D01*
X905969Y435550D01*
X905678Y435383D01*
X905386Y435300D01*
X905094D01*
X904803Y435383D01*
X904553Y435508D01*
X904344Y435675D01*
G01X903078Y437383D02*
X902828Y437633D01*
X902536Y437758D01*
X902203Y437800D01*
X901786Y437717D01*
X901494Y437508D01*
X901411Y437258D01*
X901453Y437008D01*
X901619Y436800D01*
X902453Y436383D01*
X902828Y436092D01*
X903078Y435675D01*
X903161Y435300D01*
X901411D01*
G01X900103Y435675D02*
X899853Y435467D01*
X899561Y435342D01*
X899186Y435300D01*
X898811Y435383D01*
X898519Y435550D01*
X898311Y435842D01*
X898269Y436175D01*
X898353Y436508D01*
X898561Y436717D01*
X898853Y436883D01*
X899144Y436925D01*
X899436Y436883D01*
X899811Y436717D01*
X899686Y437800D01*
X898561D01*
G01X897336D02*
X896753Y435300D01*
X896086Y437800D01*
X895419Y435300D01*
X894836Y437800D01*
G01X893069Y435300D02*
X892986Y435842D01*
X892861Y436300D01*
X892694Y436717D01*
X892486Y437175D01*
X892153Y437800D01*
X893819D01*
G01X889386Y435300D02*
Y437800D01*
X890928Y436008D01*
X888844D01*
G01X875292Y457137D02*
X875542Y457262D01*
X875834Y457345D01*
X876167D01*
X876542Y457220D01*
X876834Y457012D01*
X877042Y456762D01*
X877209Y456345D01*
X877251Y455970D01*
X877167Y455595D01*
X877042Y455345D01*
X876792Y455095D01*
X876501Y454928D01*
X876209Y454845D01*
X875917D01*
X875626Y454928D01*
X875376Y455053D01*
X875167Y455220D01*
G01X873901Y456928D02*
X873651Y457178D01*
X873359Y457303D01*
X873026Y457345D01*
X872609Y457262D01*
X872317Y457053D01*
X872234Y456803D01*
X872276Y456553D01*
X872442Y456345D01*
X873276Y455928D01*
X873651Y455637D01*
X873901Y455220D01*
X873984Y454845D01*
X872234D01*
G01X870926Y455220D02*
X870676Y455012D01*
X870384Y454887D01*
X870009Y454845D01*
X869634Y454928D01*
X869342Y455095D01*
X869134Y455387D01*
X869092Y455720D01*
X869176Y456053D01*
X869384Y456262D01*
X869676Y456428D01*
X869967Y456470D01*
X870259Y456428D01*
X870634Y456262D01*
X870509Y457345D01*
X869384D01*
G01X868159D02*
X867576Y454845D01*
X866909Y457345D01*
X866242Y454845D01*
X865659Y457345D01*
G01X864601Y455887D02*
X864309Y456178D01*
X864059Y456345D01*
X863726Y456428D01*
X863434Y456345D01*
X863226Y456178D01*
X863059Y455928D01*
X863017Y455637D01*
X863059Y455387D01*
X863226Y455137D01*
X863476Y454928D01*
X863767Y454845D01*
X864101Y454928D01*
X864392Y455178D01*
X864559Y455553D01*
X864601Y455970D01*
X864517Y456512D01*
X864392Y456803D01*
X864184Y457095D01*
X863892Y457303D01*
X863601Y457345D01*
X863309Y457262D01*
X863101Y457053D01*
G01X861501Y455887D02*
X861209Y456178D01*
X860959Y456345D01*
X860626Y456428D01*
X860334Y456345D01*
X860126Y456178D01*
X859959Y455928D01*
X859917Y455637D01*
X859959Y455387D01*
X860126Y455137D01*
X860376Y454928D01*
X860667Y454845D01*
X861001Y454928D01*
X861292Y455178D01*
X861459Y455553D01*
X861501Y455970D01*
X861417Y456512D01*
X861292Y456803D01*
X861084Y457095D01*
X860792Y457303D01*
X860501Y457345D01*
X860209Y457262D01*
X860001Y457053D01*
G01X885517Y430098D02*
X885767Y430223D01*
X886059Y430306D01*
X886392D01*
X886767Y430181D01*
X887059Y429973D01*
X887267Y429723D01*
X887434Y429306D01*
X887476Y428931D01*
X887392Y428556D01*
X887267Y428306D01*
X887017Y428056D01*
X886726Y427889D01*
X886434Y427806D01*
X886142D01*
X885851Y427889D01*
X885601Y428014D01*
X885392Y428181D01*
G01X884126Y429889D02*
X883876Y430139D01*
X883584Y430264D01*
X883251Y430306D01*
X882834Y430223D01*
X882542Y430014D01*
X882459Y429764D01*
X882501Y429514D01*
X882667Y429306D01*
X883501Y428889D01*
X883876Y428598D01*
X884126Y428181D01*
X884209Y427806D01*
X882459D01*
G01X881151Y428181D02*
X880901Y427973D01*
X880609Y427848D01*
X880234Y427806D01*
X879859Y427889D01*
X879567Y428056D01*
X879359Y428348D01*
X879317Y428681D01*
X879401Y429014D01*
X879609Y429223D01*
X879901Y429389D01*
X880192Y429431D01*
X880484Y429389D01*
X880859Y429223D01*
X880734Y430306D01*
X879609D01*
G01X878384D02*
X877801Y427806D01*
X877134Y430306D01*
X876467Y427806D01*
X875884Y430306D01*
G01X874951Y428306D02*
X874701Y428014D01*
X874367Y427848D01*
X873992Y427806D01*
X873659Y427848D01*
X873326Y428056D01*
X873117Y428306D01*
X873076Y428556D01*
X873159Y428848D01*
X873451Y429056D01*
X873742Y429139D01*
X874117D01*
G01X873742D02*
X873492Y429264D01*
X873284Y429473D01*
X873201Y429723D01*
X873284Y429973D01*
X873492Y430181D01*
X873867Y430306D01*
X874242Y430264D01*
X874617Y430098D01*
G01X871726Y429889D02*
X871476Y430139D01*
X871184Y430264D01*
X870851Y430306D01*
X870434Y430223D01*
X870142Y430014D01*
X870059Y429764D01*
X870101Y429514D01*
X870267Y429306D01*
X871101Y428889D01*
X871476Y428598D01*
X871726Y428181D01*
X871809Y427806D01*
X870059D01*
G01X885517Y433598D02*
X885767Y433723D01*
X886059Y433806D01*
X886392D01*
X886767Y433681D01*
X887059Y433473D01*
X887267Y433223D01*
X887434Y432806D01*
X887476Y432431D01*
X887392Y432056D01*
X887267Y431806D01*
X887017Y431556D01*
X886726Y431389D01*
X886434Y431306D01*
X886142D01*
X885851Y431389D01*
X885601Y431514D01*
X885392Y431681D01*
G01X884126Y433389D02*
X883876Y433639D01*
X883584Y433764D01*
X883251Y433806D01*
X882834Y433723D01*
X882542Y433514D01*
X882459Y433264D01*
X882501Y433014D01*
X882667Y432806D01*
X883501Y432389D01*
X883876Y432098D01*
X884126Y431681D01*
X884209Y431306D01*
X882459D01*
G01X881151Y431681D02*
X880901Y431473D01*
X880609Y431348D01*
X880234Y431306D01*
X879859Y431389D01*
X879567Y431556D01*
X879359Y431848D01*
X879317Y432181D01*
X879401Y432514D01*
X879609Y432723D01*
X879901Y432889D01*
X880192Y432931D01*
X880484Y432889D01*
X880859Y432723D01*
X880734Y433806D01*
X879609D01*
G01X878384D02*
X877801Y431306D01*
X877134Y433806D01*
X876467Y431306D01*
X875884Y433806D01*
G01X874951Y431806D02*
X874701Y431514D01*
X874367Y431348D01*
X873992Y431306D01*
X873659Y431348D01*
X873326Y431556D01*
X873117Y431806D01*
X873076Y432056D01*
X873159Y432348D01*
X873451Y432556D01*
X873742Y432639D01*
X874117D01*
G01X873742D02*
X873492Y432764D01*
X873284Y432973D01*
X873201Y433223D01*
X873284Y433473D01*
X873492Y433681D01*
X873867Y433806D01*
X874242Y433764D01*
X874617Y433598D01*
G01X871851Y431806D02*
X871601Y431514D01*
X871267Y431348D01*
X870892Y431306D01*
X870559Y431348D01*
X870226Y431556D01*
X870017Y431806D01*
X869976Y432056D01*
X870059Y432348D01*
X870351Y432556D01*
X870642Y432639D01*
X871017D01*
G01X870642D02*
X870392Y432764D01*
X870184Y432973D01*
X870101Y433223D01*
X870184Y433473D01*
X870392Y433681D01*
X870767Y433806D01*
X871142Y433764D01*
X871517Y433598D01*
G01X885517Y437098D02*
X885767Y437223D01*
X886059Y437306D01*
X886392D01*
X886767Y437181D01*
X887059Y436973D01*
X887267Y436723D01*
X887434Y436306D01*
X887476Y435931D01*
X887392Y435556D01*
X887267Y435306D01*
X887017Y435056D01*
X886726Y434889D01*
X886434Y434806D01*
X886142D01*
X885851Y434889D01*
X885601Y435014D01*
X885392Y435181D01*
G01X884126Y436889D02*
X883876Y437139D01*
X883584Y437264D01*
X883251Y437306D01*
X882834Y437223D01*
X882542Y437014D01*
X882459Y436764D01*
X882501Y436514D01*
X882667Y436306D01*
X883501Y435889D01*
X883876Y435598D01*
X884126Y435181D01*
X884209Y434806D01*
X882459D01*
G01X881151Y435181D02*
X880901Y434973D01*
X880609Y434848D01*
X880234Y434806D01*
X879859Y434889D01*
X879567Y435056D01*
X879359Y435348D01*
X879317Y435681D01*
X879401Y436014D01*
X879609Y436223D01*
X879901Y436389D01*
X880192Y436431D01*
X880484Y436389D01*
X880859Y436223D01*
X880734Y437306D01*
X879609D01*
G01X878384D02*
X877801Y434806D01*
X877134Y437306D01*
X876467Y434806D01*
X875884Y437306D01*
G01X874951Y435306D02*
X874701Y435014D01*
X874367Y434848D01*
X873992Y434806D01*
X873659Y434848D01*
X873326Y435056D01*
X873117Y435306D01*
X873076Y435556D01*
X873159Y435848D01*
X873451Y436056D01*
X873742Y436139D01*
X874117D01*
G01X873742D02*
X873492Y436264D01*
X873284Y436473D01*
X873201Y436723D01*
X873284Y436973D01*
X873492Y437181D01*
X873867Y437306D01*
X874242Y437264D01*
X874617Y437098D01*
G01X870934Y434806D02*
Y437306D01*
X871434Y436806D01*
G01Y434806D02*
X870434D01*
G01X875533Y465892D02*
X875783Y466017D01*
X876075Y466100D01*
X876408D01*
X876783Y465975D01*
X877075Y465767D01*
X877283Y465517D01*
X877450Y465100D01*
X877492Y464725D01*
X877408Y464350D01*
X877283Y464100D01*
X877033Y463850D01*
X876742Y463683D01*
X876450Y463600D01*
X876158D01*
X875867Y463683D01*
X875617Y463808D01*
X875408Y463975D01*
G01X874142Y465683D02*
X873892Y465933D01*
X873600Y466058D01*
X873267Y466100D01*
X872850Y466017D01*
X872558Y465808D01*
X872475Y465558D01*
X872517Y465308D01*
X872683Y465100D01*
X873517Y464683D01*
X873892Y464392D01*
X874142Y463975D01*
X874225Y463600D01*
X872475D01*
G01X871167Y463975D02*
X870917Y463767D01*
X870625Y463642D01*
X870250Y463600D01*
X869875Y463683D01*
X869583Y463850D01*
X869375Y464142D01*
X869333Y464475D01*
X869417Y464808D01*
X869625Y465017D01*
X869917Y465183D01*
X870208Y465225D01*
X870500Y465183D01*
X870875Y465017D01*
X870750Y466100D01*
X869625D01*
G01X868400D02*
X867817Y463600D01*
X867150Y466100D01*
X866483Y463600D01*
X865900Y466100D01*
G01X864842Y464642D02*
X864550Y464933D01*
X864300Y465100D01*
X863967Y465183D01*
X863675Y465100D01*
X863467Y464933D01*
X863300Y464683D01*
X863258Y464392D01*
X863300Y464142D01*
X863467Y463892D01*
X863717Y463683D01*
X864008Y463600D01*
X864342Y463683D01*
X864633Y463933D01*
X864800Y464308D01*
X864842Y464725D01*
X864758Y465267D01*
X864633Y465558D01*
X864425Y465850D01*
X864133Y466058D01*
X863842Y466100D01*
X863550Y466017D01*
X863342Y465808D01*
G01X860950Y463600D02*
X860658Y463642D01*
X860325Y463767D01*
X860117Y463975D01*
X860033Y464267D01*
X860117Y464558D01*
X860367Y464808D01*
X860742Y464933D01*
X861158D01*
X861408Y465017D01*
X861617Y465225D01*
X861700Y465517D01*
X861575Y465808D01*
X861283Y466017D01*
X860950Y466100D01*
X860617Y466017D01*
X860325Y465808D01*
X860200Y465517D01*
X860283Y465225D01*
X860492Y465017D01*
X860742Y464933D01*
X861158D01*
X861533Y464808D01*
X861783Y464558D01*
X861867Y464267D01*
X861783Y463975D01*
X861575Y463767D01*
X861242Y463642D01*
X860950Y463600D01*
G01X898122Y443167D02*
X898247Y442917D01*
X898330Y442625D01*
Y442292D01*
X898205Y441917D01*
X897997Y441625D01*
X897747Y441417D01*
X897330Y441250D01*
X896955Y441208D01*
X896580Y441292D01*
X896330Y441417D01*
X896080Y441667D01*
X895913Y441958D01*
X895830Y442250D01*
Y442542D01*
X895913Y442833D01*
X896038Y443083D01*
X896205Y443292D01*
G01X897913Y444558D02*
X898163Y444808D01*
X898288Y445100D01*
X898330Y445433D01*
X898247Y445850D01*
X898038Y446142D01*
X897788Y446225D01*
X897538Y446183D01*
X897330Y446017D01*
X896913Y445183D01*
X896622Y444808D01*
X896205Y444558D01*
X895830Y444475D01*
Y446225D01*
G01X896205Y447533D02*
X895997Y447783D01*
X895872Y448075D01*
X895830Y448450D01*
X895913Y448825D01*
X896080Y449117D01*
X896372Y449325D01*
X896705Y449367D01*
X897038Y449283D01*
X897247Y449075D01*
X897413Y448783D01*
X897455Y448492D01*
X897413Y448200D01*
X897247Y447825D01*
X898330Y447950D01*
Y449075D01*
G01Y450300D02*
X895830Y450883D01*
X898330Y451550D01*
X895830Y452217D01*
X898330Y452800D01*
G01X896122Y453942D02*
X895913Y454233D01*
X895830Y454567D01*
X895913Y454900D01*
X896163Y455192D01*
X896538Y455400D01*
X896913Y455483D01*
X897372D01*
X897747Y455400D01*
X898080Y455192D01*
X898247Y454942D01*
X898330Y454650D01*
X898247Y454317D01*
X898080Y454067D01*
X897830Y453900D01*
X897497Y453817D01*
X897205Y453900D01*
X896913Y454108D01*
X896747Y454358D01*
X896705Y454650D01*
X896788Y454983D01*
X896997Y455233D01*
X897372Y455483D01*
G01X896205Y456833D02*
X895997Y457083D01*
X895872Y457375D01*
X895830Y457750D01*
X895913Y458125D01*
X896080Y458417D01*
X896372Y458625D01*
X896705Y458667D01*
X897038Y458583D01*
X897247Y458375D01*
X897413Y458083D01*
X897455Y457792D01*
X897413Y457500D01*
X897247Y457125D01*
X898330Y457250D01*
Y458375D01*
G01X920503Y445522D02*
X920753Y445647D01*
X921045Y445730D01*
X921378D01*
X921753Y445605D01*
X922045Y445397D01*
X922253Y445147D01*
X922420Y444730D01*
X922462Y444355D01*
X922378Y443980D01*
X922253Y443730D01*
X922003Y443480D01*
X921712Y443313D01*
X921420Y443230D01*
X921128D01*
X920837Y443313D01*
X920587Y443438D01*
X920378Y443605D01*
G01X919112Y445313D02*
X918862Y445563D01*
X918570Y445688D01*
X918237Y445730D01*
X917820Y445647D01*
X917528Y445438D01*
X917445Y445188D01*
X917487Y444938D01*
X917653Y444730D01*
X918487Y444313D01*
X918862Y444022D01*
X919112Y443605D01*
X919195Y443230D01*
X917445D01*
G01X916137Y443605D02*
X915887Y443397D01*
X915595Y443272D01*
X915220Y443230D01*
X914845Y443313D01*
X914553Y443480D01*
X914345Y443772D01*
X914303Y444105D01*
X914387Y444438D01*
X914595Y444647D01*
X914887Y444813D01*
X915178Y444855D01*
X915470Y444813D01*
X915845Y444647D01*
X915720Y445730D01*
X914595D01*
G01X913370D02*
X912787Y443230D01*
X912120Y445730D01*
X911453Y443230D01*
X910870Y445730D01*
G01X909728Y443522D02*
X909437Y443313D01*
X909103Y443230D01*
X908770Y443313D01*
X908478Y443563D01*
X908270Y443938D01*
X908187Y444313D01*
Y444772D01*
X908270Y445147D01*
X908478Y445480D01*
X908728Y445647D01*
X909020Y445730D01*
X909353Y445647D01*
X909603Y445480D01*
X909770Y445230D01*
X909853Y444897D01*
X909770Y444605D01*
X909562Y444313D01*
X909312Y444147D01*
X909020Y444105D01*
X908687Y444188D01*
X908437Y444397D01*
X908187Y444772D01*
G01X905920Y443230D02*
Y445730D01*
X906420Y445230D01*
G01Y443230D02*
X905420D01*
G01X875570Y461672D02*
X875820Y461797D01*
X876112Y461880D01*
X876445D01*
X876820Y461755D01*
X877112Y461547D01*
X877320Y461297D01*
X877487Y460880D01*
X877529Y460505D01*
X877445Y460130D01*
X877320Y459880D01*
X877070Y459630D01*
X876779Y459463D01*
X876487Y459380D01*
X876195D01*
X875904Y459463D01*
X875654Y459588D01*
X875445Y459755D01*
G01X874179Y461463D02*
X873929Y461713D01*
X873637Y461838D01*
X873304Y461880D01*
X872887Y461797D01*
X872595Y461588D01*
X872512Y461338D01*
X872554Y461088D01*
X872720Y460880D01*
X873554Y460463D01*
X873929Y460172D01*
X874179Y459755D01*
X874262Y459380D01*
X872512D01*
G01X871204Y459755D02*
X870954Y459547D01*
X870662Y459422D01*
X870287Y459380D01*
X869912Y459463D01*
X869620Y459630D01*
X869412Y459922D01*
X869370Y460255D01*
X869454Y460588D01*
X869662Y460797D01*
X869954Y460963D01*
X870245Y461005D01*
X870537Y460963D01*
X870912Y460797D01*
X870787Y461880D01*
X869662D01*
G01X868437D02*
X867854Y459380D01*
X867187Y461880D01*
X866520Y459380D01*
X865937Y461880D01*
G01X864879Y460422D02*
X864587Y460713D01*
X864337Y460880D01*
X864004Y460963D01*
X863712Y460880D01*
X863504Y460713D01*
X863337Y460463D01*
X863295Y460172D01*
X863337Y459922D01*
X863504Y459672D01*
X863754Y459463D01*
X864045Y459380D01*
X864379Y459463D01*
X864670Y459713D01*
X864837Y460088D01*
X864879Y460505D01*
X864795Y461047D01*
X864670Y461338D01*
X864462Y461630D01*
X864170Y461838D01*
X863879Y461880D01*
X863587Y461797D01*
X863379Y461588D01*
G01X861070Y459380D02*
X860987Y459922D01*
X860862Y460380D01*
X860695Y460797D01*
X860487Y461255D01*
X860154Y461880D01*
X861820D01*
G01X865910Y432192D02*
X868410D01*
Y433776D01*
G01X867202Y433192D02*
Y432192D01*
G01X867243Y436417D02*
X867368Y436584D01*
X867577Y436709D01*
X867868Y436792D01*
X868118Y436709D01*
X868285Y436542D01*
X868410Y436251D01*
Y435126D01*
X865910D01*
Y436501D01*
X866077Y436792D01*
X866327Y436959D01*
X866618Y437042D01*
X866910Y436959D01*
X867160Y436709D01*
X867243Y436417D01*
Y435126D01*
G01X867993Y438392D02*
X868243Y438642D01*
X868368Y438934D01*
X868410Y439267D01*
X868327Y439684D01*
X868118Y439976D01*
X867868Y440059D01*
X867618Y440017D01*
X867410Y439851D01*
X866993Y439017D01*
X866702Y438642D01*
X866285Y438392D01*
X865910Y438309D01*
Y440059D01*
G01X868410Y442284D02*
X865910D01*
G01X868410Y441326D02*
Y443242D01*
G01X865910Y445384D02*
X868410D01*
X867910Y444884D01*
G01X865910D02*
Y445884D01*
G01X867822Y427031D02*
Y429531D01*
X866238D01*
G01X866822Y428323D02*
X867822D01*
G01X863597Y428364D02*
X863430Y428489D01*
X863305Y428698D01*
X863222Y428989D01*
X863305Y429239D01*
X863472Y429406D01*
X863763Y429531D01*
X864888D01*
Y427031D01*
X863513D01*
X863222Y427198D01*
X863055Y427448D01*
X862972Y427739D01*
X863055Y428031D01*
X863305Y428281D01*
X863597Y428364D01*
X864888D01*
G01X861622Y429114D02*
X861372Y429364D01*
X861080Y429489D01*
X860747Y429531D01*
X860330Y429448D01*
X860038Y429239D01*
X859955Y428989D01*
X859997Y428739D01*
X860163Y428531D01*
X860997Y428114D01*
X861372Y427823D01*
X861622Y427406D01*
X861705Y427031D01*
X859955D01*
G01X857730Y429531D02*
Y427031D01*
G01X858688Y429531D02*
X856772D01*
G01X855547Y427531D02*
X855297Y427239D01*
X854963Y427073D01*
X854588Y427031D01*
X854255Y427073D01*
X853922Y427281D01*
X853713Y427531D01*
X853672Y427781D01*
X853755Y428073D01*
X854047Y428281D01*
X854338Y428364D01*
X854713D01*
G01X854338D02*
X854088Y428489D01*
X853880Y428698D01*
X853797Y428948D01*
X853880Y429198D01*
X854088Y429406D01*
X854463Y429531D01*
X854838Y429489D01*
X855213Y429323D01*
G01X913097Y462670D02*
Y460878D01*
X912930Y460503D01*
X912597Y460253D01*
X912180Y460170D01*
X911763Y460253D01*
X911430Y460503D01*
X911263Y460878D01*
Y462670D01*
G01X909872Y462253D02*
X909622Y462503D01*
X909330Y462628D01*
X908997Y462670D01*
X908580Y462587D01*
X908288Y462378D01*
X908205Y462128D01*
X908247Y461878D01*
X908413Y461670D01*
X909247Y461253D01*
X909622Y460962D01*
X909872Y460545D01*
X909955Y460170D01*
X908205D01*
G01X906897Y460545D02*
X906647Y460337D01*
X906355Y460212D01*
X905980Y460170D01*
X905605Y460253D01*
X905313Y460420D01*
X905105Y460712D01*
X905063Y461045D01*
X905147Y461378D01*
X905355Y461587D01*
X905647Y461753D01*
X905938Y461795D01*
X906230Y461753D01*
X906605Y461587D01*
X906480Y462670D01*
X905355D01*
G01X904130D02*
X903547Y460170D01*
X902880Y462670D01*
X902213Y460170D01*
X901630Y462670D01*
G01X899780Y460170D02*
Y462670D01*
X900280Y462170D01*
G01Y460170D02*
X899280D01*
G01X897597Y460670D02*
X897347Y460378D01*
X897013Y460212D01*
X896638Y460170D01*
X896305Y460212D01*
X895972Y460420D01*
X895763Y460670D01*
X895722Y460920D01*
X895805Y461212D01*
X896097Y461420D01*
X896388Y461503D01*
X896763D01*
G01X896388D02*
X896138Y461628D01*
X895930Y461837D01*
X895847Y462087D01*
X895930Y462337D01*
X896138Y462545D01*
X896513Y462670D01*
X896888Y462628D01*
X897263Y462462D01*
G01X854100Y473417D02*
X856600D01*
Y474458D01*
X856475Y474792D01*
X856308Y475000D01*
X855975Y475083D01*
X855642Y475000D01*
X855433Y474750D01*
X855308Y474458D01*
Y473417D01*
G01Y474458D02*
X854100Y475083D01*
G01X856183Y476558D02*
X856433Y476808D01*
X856558Y477100D01*
X856600Y477433D01*
X856517Y477850D01*
X856308Y478142D01*
X856058Y478225D01*
X855808Y478183D01*
X855600Y478017D01*
X855183Y477183D01*
X854892Y476808D01*
X854475Y476558D01*
X854100Y476475D01*
Y478225D01*
G01X854475Y479533D02*
X854267Y479783D01*
X854142Y480075D01*
X854100Y480450D01*
X854183Y480825D01*
X854350Y481117D01*
X854642Y481325D01*
X854975Y481367D01*
X855308Y481283D01*
X855517Y481075D01*
X855683Y480783D01*
X855725Y480492D01*
X855683Y480200D01*
X855517Y479825D01*
X856600Y479950D01*
Y481075D01*
G01Y482300D02*
X854100Y482883D01*
X856600Y483550D01*
X854100Y484217D01*
X856600Y484800D01*
G01X854100Y486650D02*
X854142Y486942D01*
X854267Y487275D01*
X854475Y487483D01*
X854767Y487567D01*
X855058Y487483D01*
X855308Y487233D01*
X855433Y486858D01*
Y486442D01*
X855517Y486192D01*
X855725Y485983D01*
X856017Y485900D01*
X856308Y486025D01*
X856517Y486317D01*
X856600Y486650D01*
X856517Y486983D01*
X856308Y487275D01*
X856017Y487400D01*
X855725Y487317D01*
X855517Y487108D01*
X855433Y486858D01*
Y486442D01*
X855308Y486067D01*
X855058Y485817D01*
X854767Y485733D01*
X854475Y485817D01*
X854267Y486025D01*
X854142Y486358D01*
X854100Y486650D01*
G01X854475Y488833D02*
X854267Y489083D01*
X854142Y489375D01*
X854100Y489750D01*
X854183Y490125D01*
X854350Y490417D01*
X854642Y490625D01*
X854975Y490667D01*
X855308Y490583D01*
X855517Y490375D01*
X855683Y490083D01*
X855725Y489792D01*
X855683Y489500D01*
X855517Y489125D01*
X856600Y489250D01*
Y490375D01*
G01X876099Y473481D02*
X876349Y473606D01*
X876641Y473689D01*
X876974D01*
X877349Y473564D01*
X877641Y473356D01*
X877849Y473106D01*
X878016Y472689D01*
X878058Y472314D01*
X877974Y471939D01*
X877849Y471689D01*
X877599Y471439D01*
X877308Y471272D01*
X877016Y471189D01*
X876724D01*
X876433Y471272D01*
X876183Y471397D01*
X875974Y471564D01*
G01X874708Y473272D02*
X874458Y473522D01*
X874166Y473647D01*
X873833Y473689D01*
X873416Y473606D01*
X873124Y473397D01*
X873041Y473147D01*
X873083Y472897D01*
X873249Y472689D01*
X874083Y472272D01*
X874458Y471981D01*
X874708Y471564D01*
X874791Y471189D01*
X873041D01*
G01X871733Y471564D02*
X871483Y471356D01*
X871191Y471231D01*
X870816Y471189D01*
X870441Y471272D01*
X870149Y471439D01*
X869941Y471731D01*
X869899Y472064D01*
X869983Y472397D01*
X870191Y472606D01*
X870483Y472772D01*
X870774Y472814D01*
X871066Y472772D01*
X871441Y472606D01*
X871316Y473689D01*
X870191D01*
G01X868966D02*
X868383Y471189D01*
X867716Y473689D01*
X867049Y471189D01*
X866466Y473689D01*
G01X864116Y471189D02*
Y473689D01*
X865658Y471897D01*
X863574D01*
G01X861516Y471189D02*
X861224Y471231D01*
X860891Y471356D01*
X860683Y471564D01*
X860599Y471856D01*
X860683Y472147D01*
X860933Y472397D01*
X861308Y472522D01*
X861724D01*
X861974Y472606D01*
X862183Y472814D01*
X862266Y473106D01*
X862141Y473397D01*
X861849Y473606D01*
X861516Y473689D01*
X861183Y473606D01*
X860891Y473397D01*
X860766Y473106D01*
X860849Y472814D01*
X861058Y472606D01*
X861308Y472522D01*
X861724D01*
X862099Y472397D01*
X862349Y472147D01*
X862433Y471856D01*
X862349Y471564D01*
X862141Y471356D01*
X861808Y471231D01*
X861516Y471189D01*
G01X875599Y477482D02*
X875849Y477607D01*
X876141Y477690D01*
X876474D01*
X876849Y477565D01*
X877141Y477357D01*
X877349Y477107D01*
X877516Y476690D01*
X877558Y476315D01*
X877474Y475940D01*
X877349Y475690D01*
X877099Y475440D01*
X876808Y475273D01*
X876516Y475190D01*
X876224D01*
X875933Y475273D01*
X875683Y475398D01*
X875474Y475565D01*
G01X874208Y477273D02*
X873958Y477523D01*
X873666Y477648D01*
X873333Y477690D01*
X872916Y477607D01*
X872624Y477398D01*
X872541Y477148D01*
X872583Y476898D01*
X872749Y476690D01*
X873583Y476273D01*
X873958Y475982D01*
X874208Y475565D01*
X874291Y475190D01*
X872541D01*
G01X871233Y475565D02*
X870983Y475357D01*
X870691Y475232D01*
X870316Y475190D01*
X869941Y475273D01*
X869649Y475440D01*
X869441Y475732D01*
X869399Y476065D01*
X869483Y476398D01*
X869691Y476607D01*
X869983Y476773D01*
X870274Y476815D01*
X870566Y476773D01*
X870941Y476607D01*
X870816Y477690D01*
X869691D01*
G01X868466D02*
X867883Y475190D01*
X867216Y477690D01*
X866549Y475190D01*
X865966Y477690D01*
G01X863616Y475190D02*
Y477690D01*
X865158Y475898D01*
X863074D01*
G01X861724Y475482D02*
X861433Y475273D01*
X861099Y475190D01*
X860766Y475273D01*
X860474Y475523D01*
X860266Y475898D01*
X860183Y476273D01*
Y476732D01*
X860266Y477107D01*
X860474Y477440D01*
X860724Y477607D01*
X861016Y477690D01*
X861349Y477607D01*
X861599Y477440D01*
X861766Y477190D01*
X861849Y476857D01*
X861766Y476565D01*
X861558Y476273D01*
X861308Y476107D01*
X861016Y476065D01*
X860683Y476148D01*
X860433Y476357D01*
X860183Y476732D01*
G01X916453Y470022D02*
X916703Y470147D01*
X916995Y470230D01*
X917328D01*
X917703Y470105D01*
X917995Y469897D01*
X918203Y469647D01*
X918370Y469230D01*
X918412Y468855D01*
X918328Y468480D01*
X918203Y468230D01*
X917953Y467980D01*
X917662Y467813D01*
X917370Y467730D01*
X917078D01*
X916787Y467813D01*
X916537Y467938D01*
X916328Y468105D01*
G01X915062Y469813D02*
X914812Y470063D01*
X914520Y470188D01*
X914187Y470230D01*
X913770Y470147D01*
X913478Y469938D01*
X913395Y469688D01*
X913437Y469438D01*
X913603Y469230D01*
X914437Y468813D01*
X914812Y468522D01*
X915062Y468105D01*
X915145Y467730D01*
X913395D01*
G01X912087Y468105D02*
X911837Y467897D01*
X911545Y467772D01*
X911170Y467730D01*
X910795Y467813D01*
X910503Y467980D01*
X910295Y468272D01*
X910253Y468605D01*
X910337Y468938D01*
X910545Y469147D01*
X910837Y469313D01*
X911128Y469355D01*
X911420Y469313D01*
X911795Y469147D01*
X911670Y470230D01*
X910545D01*
G01X909320D02*
X908737Y467730D01*
X908070Y470230D01*
X907403Y467730D01*
X906820Y470230D01*
G01X905678Y468022D02*
X905387Y467813D01*
X905053Y467730D01*
X904720Y467813D01*
X904428Y468063D01*
X904220Y468438D01*
X904137Y468813D01*
Y469272D01*
X904220Y469647D01*
X904428Y469980D01*
X904678Y470147D01*
X904970Y470230D01*
X905303Y470147D01*
X905553Y469980D01*
X905720Y469730D01*
X905803Y469397D01*
X905720Y469105D01*
X905512Y468813D01*
X905262Y468647D01*
X904970Y468605D01*
X904637Y468688D01*
X904387Y468897D01*
X904137Y469272D01*
G01X901953Y467730D02*
X901870Y468272D01*
X901745Y468730D01*
X901578Y469147D01*
X901370Y469605D01*
X901037Y470230D01*
X902703D01*
G01X875740Y469792D02*
X875990Y469917D01*
X876282Y470000D01*
X876615D01*
X876990Y469875D01*
X877282Y469667D01*
X877490Y469417D01*
X877657Y469000D01*
X877699Y468625D01*
X877615Y468250D01*
X877490Y468000D01*
X877240Y467750D01*
X876949Y467583D01*
X876657Y467500D01*
X876365D01*
X876074Y467583D01*
X875824Y467708D01*
X875615Y467875D01*
G01X874349Y469583D02*
X874099Y469833D01*
X873807Y469958D01*
X873474Y470000D01*
X873057Y469917D01*
X872765Y469708D01*
X872682Y469458D01*
X872724Y469208D01*
X872890Y469000D01*
X873724Y468583D01*
X874099Y468292D01*
X874349Y467875D01*
X874432Y467500D01*
X872682D01*
G01X871374Y467875D02*
X871124Y467667D01*
X870832Y467542D01*
X870457Y467500D01*
X870082Y467583D01*
X869790Y467750D01*
X869582Y468042D01*
X869540Y468375D01*
X869624Y468708D01*
X869832Y468917D01*
X870124Y469083D01*
X870415Y469125D01*
X870707Y469083D01*
X871082Y468917D01*
X870957Y470000D01*
X869832D01*
G01X868607D02*
X868024Y467500D01*
X867357Y470000D01*
X866690Y467500D01*
X866107Y470000D01*
G01X865049Y468542D02*
X864757Y468833D01*
X864507Y469000D01*
X864174Y469083D01*
X863882Y469000D01*
X863674Y468833D01*
X863507Y468583D01*
X863465Y468292D01*
X863507Y468042D01*
X863674Y467792D01*
X863924Y467583D01*
X864215Y467500D01*
X864549Y467583D01*
X864840Y467833D01*
X865007Y468208D01*
X865049Y468625D01*
X864965Y469167D01*
X864840Y469458D01*
X864632Y469750D01*
X864340Y469958D01*
X864049Y470000D01*
X863757Y469917D01*
X863549Y469708D01*
G01X861157Y467500D02*
Y470000D01*
X861657Y469500D01*
G01Y467500D02*
X860657D01*
G01X916215Y658659D02*
X883515D01*
Y639959D01*
X916215D01*
Y658659D01*
G01X1059200Y-54200D02*
Y-57200D01*
X1057200D01*
G01X1054600D02*
Y-54200D01*
X1055200Y-54800D01*
G01Y-57200D02*
X1054000D01*
G01X1050400D02*
Y-54200D01*
X1052250Y-56350D01*
X1049750D01*
G01X1044800Y-54200D02*
Y-57200D01*
X1042800D01*
G01X1040200D02*
Y-54200D01*
X1040800Y-54800D01*
G01Y-57200D02*
X1039600D01*
G01X1037550Y-54700D02*
X1037250Y-54400D01*
X1036900Y-54250D01*
X1036500Y-54200D01*
X1036000Y-54300D01*
X1035650Y-54550D01*
X1035550Y-54850D01*
X1035600Y-55150D01*
X1035800Y-55400D01*
X1036800Y-55900D01*
X1037250Y-56250D01*
X1037550Y-56750D01*
X1037650Y-57200D01*
X1035550D01*
G01X1030400Y-54200D02*
Y-57200D01*
X1028400D01*
G01X1025800D02*
Y-54200D01*
X1026400Y-54800D01*
G01Y-57200D02*
X1025200D01*
G01X1022200Y-54200D02*
X1022600Y-54300D01*
X1022900Y-54550D01*
X1023100Y-54850D01*
X1023250Y-55250D01*
X1023300Y-55700D01*
X1023250Y-56150D01*
X1023100Y-56550D01*
X1022900Y-56850D01*
X1022600Y-57100D01*
X1022200Y-57200D01*
X1021800Y-57100D01*
X1021500Y-56850D01*
X1021300Y-56550D01*
X1021150Y-56150D01*
X1021100Y-55700D01*
X1021150Y-55250D01*
X1021300Y-54850D01*
X1021500Y-54550D01*
X1021800Y-54300D01*
X1022200Y-54200D01*
G01X1016000D02*
Y-57200D01*
X1014000D01*
G01X1012500Y-56750D02*
X1012200Y-57000D01*
X1011850Y-57150D01*
X1011400Y-57200D01*
X1010950Y-57100D01*
X1010600Y-56900D01*
X1010350Y-56550D01*
X1010300Y-56150D01*
X1010400Y-55750D01*
X1010650Y-55500D01*
X1011000Y-55300D01*
X1011350Y-55250D01*
X1011700Y-55300D01*
X1012150Y-55500D01*
X1012000Y-54200D01*
X1010650D01*
G01X1005200D02*
Y-57200D01*
X1003200D01*
G01X1001700Y-56600D02*
X1001400Y-56950D01*
X1001000Y-57150D01*
X1000550Y-57200D01*
X1000150Y-57150D01*
X999750Y-56900D01*
X999500Y-56600D01*
X999450Y-56300D01*
X999550Y-55950D01*
X999900Y-55700D01*
X1000250Y-55600D01*
X1000700D01*
G01X1000250D02*
X999950Y-55450D01*
X999700Y-55200D01*
X999600Y-54900D01*
X999700Y-54600D01*
X999950Y-54350D01*
X1000400Y-54200D01*
X1000850Y-54250D01*
X1001300Y-54450D01*
G01X994400Y-54200D02*
Y-57200D01*
X992400D01*
G01X989800D02*
Y-54200D01*
X990400Y-54800D01*
G01Y-57200D02*
X989200D01*
G01X987700Y-58200D02*
X984700D01*
G01X982600Y-57200D02*
X982250Y-57150D01*
X981850Y-57000D01*
X981600Y-56750D01*
X981500Y-56400D01*
X981600Y-56050D01*
X981900Y-55750D01*
X982350Y-55600D01*
X982850D01*
X983150Y-55500D01*
X983400Y-55250D01*
X983500Y-54900D01*
X983350Y-54550D01*
X983000Y-54300D01*
X982600Y-54200D01*
X982200Y-54300D01*
X981850Y-54550D01*
X981700Y-54900D01*
X981800Y-55250D01*
X982050Y-55500D01*
X982350Y-55600D01*
X982850D01*
X983300Y-55750D01*
X983600Y-56050D01*
X983700Y-56400D01*
X983600Y-56750D01*
X983350Y-57000D01*
X982950Y-57150D01*
X982600Y-57200D01*
G01X980100Y-56750D02*
X979800Y-57000D01*
X979450Y-57150D01*
X979000Y-57200D01*
X978550Y-57100D01*
X978200Y-56900D01*
X977950Y-56550D01*
X977900Y-56150D01*
X978000Y-55750D01*
X978250Y-55500D01*
X978600Y-55300D01*
X978950Y-55250D01*
X979300Y-55300D01*
X979750Y-55500D01*
X979600Y-54200D01*
X978250D01*
G01X975400Y-57200D02*
X975800Y-57150D01*
X976150Y-56950D01*
X976450Y-56650D01*
X976650Y-56300D01*
X976750Y-55900D01*
Y-55500D01*
X976650Y-55100D01*
X976450Y-54750D01*
X976150Y-54450D01*
X975800Y-54250D01*
X975400Y-54200D01*
X975000Y-54250D01*
X974650Y-54450D01*
X974350Y-54750D01*
X974150Y-55100D01*
X974050Y-55500D01*
Y-55900D01*
X974150Y-56300D01*
X974350Y-56650D01*
X974650Y-56950D01*
X975000Y-57150D01*
X975400Y-57200D01*
G01X972650D02*
Y-54200D01*
G01Y-55650D02*
X972400Y-55400D01*
X972150Y-55250D01*
X971750Y-55200D01*
X971450Y-55250D01*
X971100Y-55450D01*
X970950Y-55750D01*
Y-57200D01*
G01X969700D02*
Y-55200D01*
G01Y-55750D02*
X969550Y-55500D01*
X969300Y-55300D01*
X968950Y-55200D01*
X968600Y-55300D01*
X968350Y-55500D01*
X968200Y-55750D01*
Y-57200D01*
G01Y-55750D02*
X968050Y-55500D01*
X967800Y-55300D01*
X967450Y-55200D01*
X967100Y-55300D01*
X966850Y-55500D01*
X966700Y-55800D01*
Y-57200D01*
G01X966100Y-58200D02*
X963100D01*
G01X962100Y-57200D02*
Y-54200D01*
X961100D01*
X960700Y-54350D01*
X960400Y-54550D01*
X960150Y-54850D01*
X959950Y-55200D01*
X959900Y-55700D01*
X959950Y-56200D01*
X960150Y-56550D01*
X960400Y-56850D01*
X960700Y-57050D01*
X961100Y-57200D01*
X962100D01*
G01X1010800Y122000D02*
X925140D01*
G01X964697Y137191D02*
X964947Y137316D01*
X965239Y137399D01*
X965572D01*
X965947Y137274D01*
X966239Y137066D01*
X966447Y136816D01*
X966614Y136399D01*
X966656Y136024D01*
X966572Y135649D01*
X966447Y135399D01*
X966197Y135149D01*
X965906Y134982D01*
X965614Y134899D01*
X965322D01*
X965031Y134982D01*
X964781Y135107D01*
X964572Y135274D01*
G01X963431D02*
X963181Y135066D01*
X962889Y134941D01*
X962514Y134899D01*
X962139Y134982D01*
X961847Y135149D01*
X961639Y135441D01*
X961597Y135774D01*
X961681Y136107D01*
X961889Y136316D01*
X962181Y136482D01*
X962472Y136524D01*
X962764Y136482D01*
X963139Y136316D01*
X963014Y137399D01*
X961889D01*
G01X959164Y136149D02*
X958331D01*
Y135399D01*
X958581Y135149D01*
X958872Y134982D01*
X959289Y134899D01*
X959706Y134982D01*
X959997Y135149D01*
X960247Y135399D01*
X960414Y135691D01*
X960497Y136024D01*
Y136316D01*
X960414Y136566D01*
X960247Y136857D01*
X959997Y137107D01*
X959747Y137274D01*
X959414Y137399D01*
X959122D01*
X958789Y137316D01*
X958539Y137149D01*
G01X957106Y136982D02*
X956856Y137232D01*
X956564Y137357D01*
X956231Y137399D01*
X955814Y137316D01*
X955522Y137107D01*
X955439Y136857D01*
X955481Y136607D01*
X955647Y136399D01*
X956481Y135982D01*
X956856Y135691D01*
X957106Y135274D01*
X957189Y134899D01*
X955439D01*
G01X954006Y136982D02*
X953756Y137232D01*
X953464Y137357D01*
X953131Y137399D01*
X952714Y137316D01*
X952422Y137107D01*
X952339Y136857D01*
X952381Y136607D01*
X952547Y136399D01*
X953381Y135982D01*
X953756Y135691D01*
X954006Y135274D01*
X954089Y134899D01*
X952339D01*
G01X964697Y141191D02*
X964947Y141316D01*
X965239Y141399D01*
X965572D01*
X965947Y141274D01*
X966239Y141066D01*
X966447Y140816D01*
X966614Y140399D01*
X966656Y140024D01*
X966572Y139649D01*
X966447Y139399D01*
X966197Y139149D01*
X965906Y138982D01*
X965614Y138899D01*
X965322D01*
X965031Y138982D01*
X964781Y139107D01*
X964572Y139274D01*
G01X963431D02*
X963181Y139066D01*
X962889Y138941D01*
X962514Y138899D01*
X962139Y138982D01*
X961847Y139149D01*
X961639Y139441D01*
X961597Y139774D01*
X961681Y140107D01*
X961889Y140316D01*
X962181Y140482D01*
X962472Y140524D01*
X962764Y140482D01*
X963139Y140316D01*
X963014Y141399D01*
X961889D01*
G01X960331D02*
Y139607D01*
X960164Y139232D01*
X959831Y138982D01*
X959414Y138899D01*
X958997Y138982D01*
X958664Y139232D01*
X958497Y139607D01*
Y141399D01*
G01X956314Y138899D02*
Y141399D01*
X956814Y140899D01*
G01Y138899D02*
X955814D01*
G01X964697Y133191D02*
X964947Y133316D01*
X965239Y133399D01*
X965572D01*
X965947Y133274D01*
X966239Y133066D01*
X966447Y132816D01*
X966614Y132399D01*
X966656Y132024D01*
X966572Y131649D01*
X966447Y131399D01*
X966197Y131149D01*
X965906Y130982D01*
X965614Y130899D01*
X965322D01*
X965031Y130982D01*
X964781Y131107D01*
X964572Y131274D01*
G01X963431D02*
X963181Y131066D01*
X962889Y130941D01*
X962514Y130899D01*
X962139Y130982D01*
X961847Y131149D01*
X961639Y131441D01*
X961597Y131774D01*
X961681Y132107D01*
X961889Y132316D01*
X962181Y132482D01*
X962472Y132524D01*
X962764Y132482D01*
X963139Y132316D01*
X963014Y133399D01*
X961889D01*
G01X960331D02*
Y131607D01*
X960164Y131232D01*
X959831Y130982D01*
X959414Y130899D01*
X958997Y130982D01*
X958664Y131232D01*
X958497Y131607D01*
Y133399D01*
G01X956314Y130899D02*
Y133399D01*
X956814Y132899D01*
G01Y130899D02*
X955814D01*
G01X953214Y133399D02*
X953547Y133316D01*
X953797Y133107D01*
X953964Y132857D01*
X954089Y132524D01*
X954131Y132149D01*
X954089Y131774D01*
X953964Y131441D01*
X953797Y131191D01*
X953547Y130982D01*
X953214Y130899D01*
X952881Y130982D01*
X952631Y131191D01*
X952464Y131441D01*
X952339Y131774D01*
X952297Y132149D01*
X952339Y132524D01*
X952464Y132857D01*
X952631Y133107D01*
X952881Y133316D01*
X953214Y133399D01*
G01X964697Y129191D02*
X964947Y129316D01*
X965239Y129399D01*
X965572D01*
X965947Y129274D01*
X966239Y129066D01*
X966447Y128816D01*
X966614Y128399D01*
X966656Y128024D01*
X966572Y127649D01*
X966447Y127399D01*
X966197Y127149D01*
X965906Y126982D01*
X965614Y126899D01*
X965322D01*
X965031Y126982D01*
X964781Y127107D01*
X964572Y127274D01*
G01X963431D02*
X963181Y127066D01*
X962889Y126941D01*
X962514Y126899D01*
X962139Y126982D01*
X961847Y127149D01*
X961639Y127441D01*
X961597Y127774D01*
X961681Y128107D01*
X961889Y128316D01*
X962181Y128482D01*
X962472Y128524D01*
X962764Y128482D01*
X963139Y128316D01*
X963014Y129399D01*
X961889D01*
G01X959164Y128149D02*
X958331D01*
Y127399D01*
X958581Y127149D01*
X958872Y126982D01*
X959289Y126899D01*
X959706Y126982D01*
X959997Y127149D01*
X960247Y127399D01*
X960414Y127691D01*
X960497Y128024D01*
Y128316D01*
X960414Y128566D01*
X960247Y128857D01*
X959997Y129107D01*
X959747Y129274D01*
X959414Y129399D01*
X959122D01*
X958789Y129316D01*
X958539Y129149D01*
G01X957106Y128982D02*
X956856Y129232D01*
X956564Y129357D01*
X956231Y129399D01*
X955814Y129316D01*
X955522Y129107D01*
X955439Y128857D01*
X955481Y128607D01*
X955647Y128399D01*
X956481Y127982D01*
X956856Y127691D01*
X957106Y127274D01*
X957189Y126899D01*
X955439D01*
G01X953214D02*
Y129399D01*
X953714Y128899D01*
G01Y126899D02*
X952714D01*
G01X949185Y128718D02*
X949435Y128843D01*
X949727Y128926D01*
X950060D01*
X950435Y128801D01*
X950727Y128593D01*
X950935Y128343D01*
X951102Y127926D01*
X951144Y127551D01*
X951060Y127176D01*
X950935Y126926D01*
X950685Y126676D01*
X950394Y126509D01*
X950102Y126426D01*
X949810D01*
X949519Y126509D01*
X949269Y126634D01*
X949060Y126801D01*
G01X947919D02*
X947669Y126593D01*
X947377Y126468D01*
X947002Y126426D01*
X946627Y126509D01*
X946335Y126676D01*
X946127Y126968D01*
X946085Y127301D01*
X946169Y127634D01*
X946377Y127843D01*
X946669Y128009D01*
X946960Y128051D01*
X947252Y128009D01*
X947627Y127843D01*
X947502Y128926D01*
X946377D01*
G01X943652Y127676D02*
X942819D01*
Y126926D01*
X943069Y126676D01*
X943360Y126509D01*
X943777Y126426D01*
X944194Y126509D01*
X944485Y126676D01*
X944735Y126926D01*
X944902Y127218D01*
X944985Y127551D01*
Y127843D01*
X944902Y128093D01*
X944735Y128384D01*
X944485Y128634D01*
X944235Y128801D01*
X943902Y128926D01*
X943610D01*
X943277Y128843D01*
X943027Y128676D01*
G01X941719Y126801D02*
X941469Y126593D01*
X941177Y126468D01*
X940802Y126426D01*
X940427Y126509D01*
X940135Y126676D01*
X939927Y126968D01*
X939885Y127301D01*
X939969Y127634D01*
X940177Y127843D01*
X940469Y128009D01*
X940760Y128051D01*
X941052Y128009D01*
X941427Y127843D01*
X941302Y128926D01*
X940177D01*
G01X937202Y126426D02*
Y128926D01*
X938744Y127134D01*
X936660D01*
G01X981048Y137192D02*
X981298Y137317D01*
X981590Y137400D01*
X981923D01*
X982298Y137275D01*
X982590Y137067D01*
X982798Y136817D01*
X982965Y136400D01*
X983007Y136025D01*
X982923Y135650D01*
X982798Y135400D01*
X982548Y135150D01*
X982257Y134983D01*
X981965Y134900D01*
X981673D01*
X981382Y134983D01*
X981132Y135108D01*
X980923Y135275D01*
G01X979782D02*
X979532Y135067D01*
X979240Y134942D01*
X978865Y134900D01*
X978490Y134983D01*
X978198Y135150D01*
X977990Y135442D01*
X977948Y135775D01*
X978032Y136108D01*
X978240Y136317D01*
X978532Y136483D01*
X978823Y136525D01*
X979115Y136483D01*
X979490Y136317D01*
X979365Y137400D01*
X978240D01*
G01X975515Y136150D02*
X974682D01*
Y135400D01*
X974932Y135150D01*
X975223Y134983D01*
X975640Y134900D01*
X976057Y134983D01*
X976348Y135150D01*
X976598Y135400D01*
X976765Y135692D01*
X976848Y136025D01*
Y136317D01*
X976765Y136567D01*
X976598Y136858D01*
X976348Y137108D01*
X976098Y137275D01*
X975765Y137400D01*
X975473D01*
X975140Y137317D01*
X974890Y137150D01*
G01X972165Y134900D02*
Y137400D01*
X973707Y135608D01*
X971623D01*
G01X970357Y135942D02*
X970065Y136233D01*
X969815Y136400D01*
X969482Y136483D01*
X969190Y136400D01*
X968982Y136233D01*
X968815Y135983D01*
X968773Y135692D01*
X968815Y135442D01*
X968982Y135192D01*
X969232Y134983D01*
X969523Y134900D01*
X969857Y134983D01*
X970148Y135233D01*
X970315Y135608D01*
X970357Y136025D01*
X970273Y136567D01*
X970148Y136858D01*
X969940Y137150D01*
X969648Y137358D01*
X969357Y137400D01*
X969065Y137317D01*
X968857Y137108D01*
G01X981048Y129192D02*
X981298Y129317D01*
X981590Y129400D01*
X981923D01*
X982298Y129275D01*
X982590Y129067D01*
X982798Y128817D01*
X982965Y128400D01*
X983007Y128025D01*
X982923Y127650D01*
X982798Y127400D01*
X982548Y127150D01*
X982257Y126983D01*
X981965Y126900D01*
X981673D01*
X981382Y126983D01*
X981132Y127108D01*
X980923Y127275D01*
G01X979782D02*
X979532Y127067D01*
X979240Y126942D01*
X978865Y126900D01*
X978490Y126983D01*
X978198Y127150D01*
X977990Y127442D01*
X977948Y127775D01*
X978032Y128108D01*
X978240Y128317D01*
X978532Y128483D01*
X978823Y128525D01*
X979115Y128483D01*
X979490Y128317D01*
X979365Y129400D01*
X978240D01*
G01X975515Y128150D02*
X974682D01*
Y127400D01*
X974932Y127150D01*
X975223Y126983D01*
X975640Y126900D01*
X976057Y126983D01*
X976348Y127150D01*
X976598Y127400D01*
X976765Y127692D01*
X976848Y128025D01*
Y128317D01*
X976765Y128567D01*
X976598Y128858D01*
X976348Y129108D01*
X976098Y129275D01*
X975765Y129400D01*
X975473D01*
X975140Y129317D01*
X974890Y129150D01*
G01X973582Y127275D02*
X973332Y127067D01*
X973040Y126942D01*
X972665Y126900D01*
X972290Y126983D01*
X971998Y127150D01*
X971790Y127442D01*
X971748Y127775D01*
X971832Y128108D01*
X972040Y128317D01*
X972332Y128483D01*
X972623Y128525D01*
X972915Y128483D01*
X973290Y128317D01*
X973165Y129400D01*
X972040D01*
G01X970482Y127275D02*
X970232Y127067D01*
X969940Y126942D01*
X969565Y126900D01*
X969190Y126983D01*
X968898Y127150D01*
X968690Y127442D01*
X968648Y127775D01*
X968732Y128108D01*
X968940Y128317D01*
X969232Y128483D01*
X969523Y128525D01*
X969815Y128483D01*
X970190Y128317D01*
X970065Y129400D01*
X968940D01*
G01X933296Y136928D02*
X933546Y137053D01*
X933838Y137136D01*
X934171D01*
X934546Y137011D01*
X934838Y136803D01*
X935046Y136553D01*
X935213Y136136D01*
X935255Y135761D01*
X935171Y135386D01*
X935046Y135136D01*
X934796Y134886D01*
X934505Y134719D01*
X934213Y134636D01*
X933921D01*
X933630Y134719D01*
X933380Y134844D01*
X933171Y135011D01*
G01X932030D02*
X931780Y134803D01*
X931488Y134678D01*
X931113Y134636D01*
X930738Y134719D01*
X930446Y134886D01*
X930238Y135178D01*
X930196Y135511D01*
X930280Y135844D01*
X930488Y136053D01*
X930780Y136219D01*
X931071Y136261D01*
X931363Y136219D01*
X931738Y136053D01*
X931613Y137136D01*
X930488D01*
G01X927763Y135886D02*
X926930D01*
Y135136D01*
X927180Y134886D01*
X927471Y134719D01*
X927888Y134636D01*
X928305Y134719D01*
X928596Y134886D01*
X928846Y135136D01*
X929013Y135428D01*
X929096Y135761D01*
Y136053D01*
X929013Y136303D01*
X928846Y136594D01*
X928596Y136844D01*
X928346Y137011D01*
X928013Y137136D01*
X927721D01*
X927388Y137053D01*
X927138Y136886D01*
G01X925830Y135011D02*
X925580Y134803D01*
X925288Y134678D01*
X924913Y134636D01*
X924538Y134719D01*
X924246Y134886D01*
X924038Y135178D01*
X923996Y135511D01*
X924080Y135844D01*
X924288Y136053D01*
X924580Y136219D01*
X924871Y136261D01*
X925163Y136219D01*
X925538Y136053D01*
X925413Y137136D01*
X924288D01*
G01X922730Y135136D02*
X922480Y134844D01*
X922146Y134678D01*
X921771Y134636D01*
X921438Y134678D01*
X921105Y134886D01*
X920896Y135136D01*
X920855Y135386D01*
X920938Y135678D01*
X921230Y135886D01*
X921521Y135969D01*
X921896D01*
G01X921521D02*
X921271Y136094D01*
X921063Y136303D01*
X920980Y136553D01*
X921063Y136803D01*
X921271Y137011D01*
X921646Y137136D01*
X922021Y137094D01*
X922396Y136928D01*
G01X933296Y144928D02*
X933546Y145053D01*
X933838Y145136D01*
X934171D01*
X934546Y145011D01*
X934838Y144803D01*
X935046Y144553D01*
X935213Y144136D01*
X935255Y143761D01*
X935171Y143386D01*
X935046Y143136D01*
X934796Y142886D01*
X934505Y142719D01*
X934213Y142636D01*
X933921D01*
X933630Y142719D01*
X933380Y142844D01*
X933171Y143011D01*
G01X932030D02*
X931780Y142803D01*
X931488Y142678D01*
X931113Y142636D01*
X930738Y142719D01*
X930446Y142886D01*
X930238Y143178D01*
X930196Y143511D01*
X930280Y143844D01*
X930488Y144053D01*
X930780Y144219D01*
X931071Y144261D01*
X931363Y144219D01*
X931738Y144053D01*
X931613Y145136D01*
X930488D01*
G01X927763Y143886D02*
X926930D01*
Y143136D01*
X927180Y142886D01*
X927471Y142719D01*
X927888Y142636D01*
X928305Y142719D01*
X928596Y142886D01*
X928846Y143136D01*
X929013Y143428D01*
X929096Y143761D01*
Y144053D01*
X929013Y144303D01*
X928846Y144594D01*
X928596Y144844D01*
X928346Y145011D01*
X928013Y145136D01*
X927721D01*
X927388Y145053D01*
X927138Y144886D01*
G01X924413Y142636D02*
Y145136D01*
X925955Y143344D01*
X923871D01*
G01X921313Y142636D02*
Y145136D01*
X922855Y143344D01*
X920771D01*
G01X949185Y136718D02*
X949435Y136843D01*
X949727Y136926D01*
X950060D01*
X950435Y136801D01*
X950727Y136593D01*
X950935Y136343D01*
X951102Y135926D01*
X951144Y135551D01*
X951060Y135176D01*
X950935Y134926D01*
X950685Y134676D01*
X950394Y134509D01*
X950102Y134426D01*
X949810D01*
X949519Y134509D01*
X949269Y134634D01*
X949060Y134801D01*
G01X947919D02*
X947669Y134593D01*
X947377Y134468D01*
X947002Y134426D01*
X946627Y134509D01*
X946335Y134676D01*
X946127Y134968D01*
X946085Y135301D01*
X946169Y135634D01*
X946377Y135843D01*
X946669Y136009D01*
X946960Y136051D01*
X947252Y136009D01*
X947627Y135843D01*
X947502Y136926D01*
X946377D01*
G01X943652Y135676D02*
X942819D01*
Y134926D01*
X943069Y134676D01*
X943360Y134509D01*
X943777Y134426D01*
X944194Y134509D01*
X944485Y134676D01*
X944735Y134926D01*
X944902Y135218D01*
X944985Y135551D01*
Y135843D01*
X944902Y136093D01*
X944735Y136384D01*
X944485Y136634D01*
X944235Y136801D01*
X943902Y136926D01*
X943610D01*
X943277Y136843D01*
X943027Y136676D01*
G01X940302Y134426D02*
Y136926D01*
X941844Y135134D01*
X939760D01*
G01X938619Y134801D02*
X938369Y134593D01*
X938077Y134468D01*
X937702Y134426D01*
X937327Y134509D01*
X937035Y134676D01*
X936827Y134968D01*
X936785Y135301D01*
X936869Y135634D01*
X937077Y135843D01*
X937369Y136009D01*
X937660Y136051D01*
X937952Y136009D01*
X938327Y135843D01*
X938202Y136926D01*
X937077D01*
G01X949185Y132718D02*
X949435Y132843D01*
X949727Y132926D01*
X950060D01*
X950435Y132801D01*
X950727Y132593D01*
X950935Y132343D01*
X951102Y131926D01*
X951144Y131551D01*
X951060Y131176D01*
X950935Y130926D01*
X950685Y130676D01*
X950394Y130509D01*
X950102Y130426D01*
X949810D01*
X949519Y130509D01*
X949269Y130634D01*
X949060Y130801D01*
G01X947919D02*
X947669Y130593D01*
X947377Y130468D01*
X947002Y130426D01*
X946627Y130509D01*
X946335Y130676D01*
X946127Y130968D01*
X946085Y131301D01*
X946169Y131634D01*
X946377Y131843D01*
X946669Y132009D01*
X946960Y132051D01*
X947252Y132009D01*
X947627Y131843D01*
X947502Y132926D01*
X946377D01*
G01X944819D02*
Y131134D01*
X944652Y130759D01*
X944319Y130509D01*
X943902Y130426D01*
X943485Y130509D01*
X943152Y130759D01*
X942985Y131134D01*
Y132926D01*
G01X940802Y130426D02*
Y132926D01*
X941302Y132426D01*
G01Y130426D02*
X940302D01*
G01X937702D02*
Y132926D01*
X938202Y132426D01*
G01Y130426D02*
X937202D01*
G01X949185Y140718D02*
X949435Y140843D01*
X949727Y140926D01*
X950060D01*
X950435Y140801D01*
X950727Y140593D01*
X950935Y140343D01*
X951102Y139926D01*
X951144Y139551D01*
X951060Y139176D01*
X950935Y138926D01*
X950685Y138676D01*
X950394Y138509D01*
X950102Y138426D01*
X949810D01*
X949519Y138509D01*
X949269Y138634D01*
X949060Y138801D01*
G01X947919D02*
X947669Y138593D01*
X947377Y138468D01*
X947002Y138426D01*
X946627Y138509D01*
X946335Y138676D01*
X946127Y138968D01*
X946085Y139301D01*
X946169Y139634D01*
X946377Y139843D01*
X946669Y140009D01*
X946960Y140051D01*
X947252Y140009D01*
X947627Y139843D01*
X947502Y140926D01*
X946377D01*
G01X943902D02*
Y138426D01*
G01X944860Y140926D02*
X942944D01*
G01X940802Y138426D02*
Y140926D01*
X941302Y140426D01*
G01Y138426D02*
X940302D01*
G01X938619Y138926D02*
X938369Y138634D01*
X938035Y138468D01*
X937660Y138426D01*
X937327Y138468D01*
X936994Y138676D01*
X936785Y138926D01*
X936744Y139176D01*
X936827Y139468D01*
X937119Y139676D01*
X937410Y139759D01*
X937785D01*
G01X937410D02*
X937160Y139884D01*
X936952Y140093D01*
X936869Y140343D01*
X936952Y140593D01*
X937160Y140801D01*
X937535Y140926D01*
X937910Y140884D01*
X938285Y140718D01*
G01X977733Y113859D02*
X977983Y113984D01*
X978275Y114067D01*
X978608D01*
X978983Y113942D01*
X979275Y113734D01*
X979483Y113484D01*
X979650Y113067D01*
X979692Y112692D01*
X979608Y112317D01*
X979483Y112067D01*
X979233Y111817D01*
X978942Y111650D01*
X978650Y111567D01*
X978358D01*
X978067Y111650D01*
X977817Y111775D01*
X977608Y111942D01*
G01X976467D02*
X976217Y111734D01*
X975925Y111609D01*
X975550Y111567D01*
X975175Y111650D01*
X974883Y111817D01*
X974675Y112109D01*
X974633Y112442D01*
X974717Y112775D01*
X974925Y112984D01*
X975217Y113150D01*
X975508Y113192D01*
X975800Y113150D01*
X976175Y112984D01*
X976050Y114067D01*
X974925D01*
G01X972450D02*
Y111567D01*
G01X973408Y114067D02*
X971492D01*
G01X970142Y113650D02*
X969892Y113900D01*
X969600Y114025D01*
X969267Y114067D01*
X968850Y113984D01*
X968558Y113775D01*
X968475Y113525D01*
X968517Y113275D01*
X968683Y113067D01*
X969517Y112650D01*
X969892Y112359D01*
X970142Y111942D01*
X970225Y111567D01*
X968475D01*
G01X962933Y116059D02*
X963183Y116184D01*
X963475Y116267D01*
X963808D01*
X964183Y116142D01*
X964475Y115934D01*
X964683Y115684D01*
X964850Y115267D01*
X964892Y114892D01*
X964808Y114517D01*
X964683Y114267D01*
X964433Y114017D01*
X964142Y113850D01*
X963850Y113767D01*
X963558D01*
X963267Y113850D01*
X963017Y113975D01*
X962808Y114142D01*
G01X961667D02*
X961417Y113934D01*
X961125Y113809D01*
X960750Y113767D01*
X960375Y113850D01*
X960083Y114017D01*
X959875Y114309D01*
X959833Y114642D01*
X959917Y114975D01*
X960125Y115184D01*
X960417Y115350D01*
X960708Y115392D01*
X961000Y115350D01*
X961375Y115184D01*
X961250Y116267D01*
X960125D01*
G01X957650D02*
Y113767D01*
G01X958608Y116267D02*
X956692D01*
G01X954550Y113767D02*
Y116267D01*
X955050Y115767D01*
G01Y113767D02*
X954050D01*
G01X933296Y140928D02*
X933546Y141053D01*
X933838Y141136D01*
X934171D01*
X934546Y141011D01*
X934838Y140803D01*
X935046Y140553D01*
X935213Y140136D01*
X935255Y139761D01*
X935171Y139386D01*
X935046Y139136D01*
X934796Y138886D01*
X934505Y138719D01*
X934213Y138636D01*
X933921D01*
X933630Y138719D01*
X933380Y138844D01*
X933171Y139011D01*
G01X932030D02*
X931780Y138803D01*
X931488Y138678D01*
X931113Y138636D01*
X930738Y138719D01*
X930446Y138886D01*
X930238Y139178D01*
X930196Y139511D01*
X930280Y139844D01*
X930488Y140053D01*
X930780Y140219D01*
X931071Y140261D01*
X931363Y140219D01*
X931738Y140053D01*
X931613Y141136D01*
X930488D01*
G01X928930D02*
Y139344D01*
X928763Y138969D01*
X928430Y138719D01*
X928013Y138636D01*
X927596Y138719D01*
X927263Y138969D01*
X927096Y139344D01*
Y141136D01*
G01X925705Y139678D02*
X925413Y139969D01*
X925163Y140136D01*
X924830Y140219D01*
X924538Y140136D01*
X924330Y139969D01*
X924163Y139719D01*
X924121Y139428D01*
X924163Y139178D01*
X924330Y138928D01*
X924580Y138719D01*
X924871Y138636D01*
X925205Y138719D01*
X925496Y138969D01*
X925663Y139344D01*
X925705Y139761D01*
X925621Y140303D01*
X925496Y140594D01*
X925288Y140886D01*
X924996Y141094D01*
X924705Y141136D01*
X924413Y141053D01*
X924205Y140844D01*
G01X981048Y133192D02*
X981298Y133317D01*
X981590Y133400D01*
X981923D01*
X982298Y133275D01*
X982590Y133067D01*
X982798Y132817D01*
X982965Y132400D01*
X983007Y132025D01*
X982923Y131650D01*
X982798Y131400D01*
X982548Y131150D01*
X982257Y130983D01*
X981965Y130900D01*
X981673D01*
X981382Y130983D01*
X981132Y131108D01*
X980923Y131275D01*
G01X979782D02*
X979532Y131067D01*
X979240Y130942D01*
X978865Y130900D01*
X978490Y130983D01*
X978198Y131150D01*
X977990Y131442D01*
X977948Y131775D01*
X978032Y132108D01*
X978240Y132317D01*
X978532Y132483D01*
X978823Y132525D01*
X979115Y132483D01*
X979490Y132317D01*
X979365Y133400D01*
X978240D01*
G01X976682D02*
Y131608D01*
X976515Y131233D01*
X976182Y130983D01*
X975765Y130900D01*
X975348Y130983D01*
X975015Y131233D01*
X974848Y131608D01*
Y133400D01*
G01X973582Y131275D02*
X973332Y131067D01*
X973040Y130942D01*
X972665Y130900D01*
X972290Y130983D01*
X971998Y131150D01*
X971790Y131442D01*
X971748Y131775D01*
X971832Y132108D01*
X972040Y132317D01*
X972332Y132483D01*
X972623Y132525D01*
X972915Y132483D01*
X973290Y132317D01*
X973165Y133400D01*
X972040D01*
G01X933296Y148928D02*
X933546Y149053D01*
X933838Y149136D01*
X934171D01*
X934546Y149011D01*
X934838Y148803D01*
X935046Y148553D01*
X935213Y148136D01*
X935255Y147761D01*
X935171Y147386D01*
X935046Y147136D01*
X934796Y146886D01*
X934505Y146719D01*
X934213Y146636D01*
X933921D01*
X933630Y146719D01*
X933380Y146844D01*
X933171Y147011D01*
G01X932030D02*
X931780Y146803D01*
X931488Y146678D01*
X931113Y146636D01*
X930738Y146719D01*
X930446Y146886D01*
X930238Y147178D01*
X930196Y147511D01*
X930280Y147844D01*
X930488Y148053D01*
X930780Y148219D01*
X931071Y148261D01*
X931363Y148219D01*
X931738Y148053D01*
X931613Y149136D01*
X930488D01*
G01X928013D02*
Y146636D01*
G01X928971Y149136D02*
X927055D01*
G01X925621Y146928D02*
X925330Y146719D01*
X924996Y146636D01*
X924663Y146719D01*
X924371Y146969D01*
X924163Y147344D01*
X924080Y147719D01*
Y148178D01*
X924163Y148553D01*
X924371Y148886D01*
X924621Y149053D01*
X924913Y149136D01*
X925246Y149053D01*
X925496Y148886D01*
X925663Y148636D01*
X925746Y148303D01*
X925663Y148011D01*
X925455Y147719D01*
X925205Y147553D01*
X924913Y147511D01*
X924580Y147594D01*
X924330Y147803D01*
X924080Y148178D01*
G01X981048Y141192D02*
X981298Y141317D01*
X981590Y141400D01*
X981923D01*
X982298Y141275D01*
X982590Y141067D01*
X982798Y140817D01*
X982965Y140400D01*
X983007Y140025D01*
X982923Y139650D01*
X982798Y139400D01*
X982548Y139150D01*
X982257Y138983D01*
X981965Y138900D01*
X981673D01*
X981382Y138983D01*
X981132Y139108D01*
X980923Y139275D01*
G01X979782D02*
X979532Y139067D01*
X979240Y138942D01*
X978865Y138900D01*
X978490Y138983D01*
X978198Y139150D01*
X977990Y139442D01*
X977948Y139775D01*
X978032Y140108D01*
X978240Y140317D01*
X978532Y140483D01*
X978823Y140525D01*
X979115Y140483D01*
X979490Y140317D01*
X979365Y141400D01*
X978240D01*
G01X975765D02*
Y138900D01*
G01X976723Y141400D02*
X974807D01*
G01X972665Y138900D02*
X972373Y138942D01*
X972040Y139067D01*
X971832Y139275D01*
X971748Y139567D01*
X971832Y139858D01*
X972082Y140108D01*
X972457Y140233D01*
X972873D01*
X973123Y140317D01*
X973332Y140525D01*
X973415Y140817D01*
X973290Y141108D01*
X972998Y141317D01*
X972665Y141400D01*
X972332Y141317D01*
X972040Y141108D01*
X971915Y140817D01*
X971998Y140525D01*
X972207Y140317D01*
X972457Y140233D01*
X972873D01*
X973248Y140108D01*
X973498Y139858D01*
X973582Y139567D01*
X973498Y139275D01*
X973290Y139067D01*
X972957Y138942D01*
X972665Y138900D01*
G01X954633Y441000D02*
Y443500D01*
X953592D01*
X953258Y443375D01*
X953050Y443208D01*
X952967Y442875D01*
X953050Y442542D01*
X953300Y442333D01*
X953592Y442208D01*
X954633D01*
G01X953592D02*
X952967Y441000D01*
G01X951492Y443083D02*
X951242Y443333D01*
X950950Y443458D01*
X950617Y443500D01*
X950200Y443417D01*
X949908Y443208D01*
X949825Y442958D01*
X949867Y442708D01*
X950033Y442500D01*
X950867Y442083D01*
X951242Y441792D01*
X951492Y441375D01*
X951575Y441000D01*
X949825D01*
G01X948517Y441375D02*
X948267Y441167D01*
X947975Y441042D01*
X947600Y441000D01*
X947225Y441083D01*
X946933Y441250D01*
X946725Y441542D01*
X946683Y441875D01*
X946767Y442208D01*
X946975Y442417D01*
X947267Y442583D01*
X947558Y442625D01*
X947850Y442583D01*
X948225Y442417D01*
X948100Y443500D01*
X946975D01*
G01X945750D02*
X945167Y441000D01*
X944500Y443500D01*
X943833Y441000D01*
X943250Y443500D01*
G01X941400Y441000D02*
Y443500D01*
X941900Y443000D01*
G01Y441000D02*
X940900D01*
G01X939217Y441375D02*
X938967Y441167D01*
X938675Y441042D01*
X938300Y441000D01*
X937925Y441083D01*
X937633Y441250D01*
X937425Y441542D01*
X937383Y441875D01*
X937467Y442208D01*
X937675Y442417D01*
X937967Y442583D01*
X938258Y442625D01*
X938550Y442583D01*
X938925Y442417D01*
X938800Y443500D01*
X937675D01*
G01X935200Y441000D02*
X934908Y441042D01*
X934575Y441167D01*
X934367Y441375D01*
X934283Y441667D01*
X934367Y441958D01*
X934617Y442208D01*
X934992Y442333D01*
X935408D01*
X935658Y442417D01*
X935867Y442625D01*
X935950Y442917D01*
X935825Y443208D01*
X935533Y443417D01*
X935200Y443500D01*
X934867Y443417D01*
X934575Y443208D01*
X934450Y442917D01*
X934533Y442625D01*
X934742Y442417D01*
X934992Y442333D01*
X935408D01*
X935783Y442208D01*
X936033Y441958D01*
X936117Y441667D01*
X936033Y441375D01*
X935825Y441167D01*
X935492Y441042D01*
X935200Y441000D01*
G01X954633Y445000D02*
Y447500D01*
X953592D01*
X953258Y447375D01*
X953050Y447208D01*
X952967Y446875D01*
X953050Y446542D01*
X953300Y446333D01*
X953592Y446208D01*
X954633D01*
G01X953592D02*
X952967Y445000D01*
G01X951492Y447083D02*
X951242Y447333D01*
X950950Y447458D01*
X950617Y447500D01*
X950200Y447417D01*
X949908Y447208D01*
X949825Y446958D01*
X949867Y446708D01*
X950033Y446500D01*
X950867Y446083D01*
X951242Y445792D01*
X951492Y445375D01*
X951575Y445000D01*
X949825D01*
G01X948517Y445375D02*
X948267Y445167D01*
X947975Y445042D01*
X947600Y445000D01*
X947225Y445083D01*
X946933Y445250D01*
X946725Y445542D01*
X946683Y445875D01*
X946767Y446208D01*
X946975Y446417D01*
X947267Y446583D01*
X947558Y446625D01*
X947850Y446583D01*
X948225Y446417D01*
X948100Y447500D01*
X946975D01*
G01X945750D02*
X945167Y445000D01*
X944500Y447500D01*
X943833Y445000D01*
X943250Y447500D01*
G01X941400Y445000D02*
Y447500D01*
X941900Y447000D01*
G01Y445000D02*
X940900D01*
G01X939217Y445375D02*
X938967Y445167D01*
X938675Y445042D01*
X938300Y445000D01*
X937925Y445083D01*
X937633Y445250D01*
X937425Y445542D01*
X937383Y445875D01*
X937467Y446208D01*
X937675Y446417D01*
X937967Y446583D01*
X938258Y446625D01*
X938550Y446583D01*
X938925Y446417D01*
X938800Y447500D01*
X937675D01*
G01X935908Y445292D02*
X935617Y445083D01*
X935283Y445000D01*
X934950Y445083D01*
X934658Y445333D01*
X934450Y445708D01*
X934367Y446083D01*
Y446542D01*
X934450Y446917D01*
X934658Y447250D01*
X934908Y447417D01*
X935200Y447500D01*
X935533Y447417D01*
X935783Y447250D01*
X935950Y447000D01*
X936033Y446667D01*
X935950Y446375D01*
X935742Y446083D01*
X935492Y445917D01*
X935200Y445875D01*
X934867Y445958D01*
X934617Y446167D01*
X934367Y446542D01*
G01X967623Y464350D02*
Y466850D01*
X966582D01*
X966248Y466725D01*
X966040Y466558D01*
X965957Y466225D01*
X966040Y465892D01*
X966290Y465683D01*
X966582Y465558D01*
X967623D01*
G01X966582D02*
X965957Y464350D01*
G01X964482Y466433D02*
X964232Y466683D01*
X963940Y466808D01*
X963607Y466850D01*
X963190Y466767D01*
X962898Y466558D01*
X962815Y466308D01*
X962857Y466058D01*
X963023Y465850D01*
X963857Y465433D01*
X964232Y465142D01*
X964482Y464725D01*
X964565Y464350D01*
X962815D01*
G01X961507Y464725D02*
X961257Y464517D01*
X960965Y464392D01*
X960590Y464350D01*
X960215Y464433D01*
X959923Y464600D01*
X959715Y464892D01*
X959673Y465225D01*
X959757Y465558D01*
X959965Y465767D01*
X960257Y465933D01*
X960548Y465975D01*
X960840Y465933D01*
X961215Y465767D01*
X961090Y466850D01*
X959965D01*
G01X958740D02*
X958157Y464350D01*
X957490Y466850D01*
X956823Y464350D01*
X956240Y466850D01*
G01X954390Y464350D02*
Y466850D01*
X954890Y466350D01*
G01Y464350D02*
X953890D01*
G01X951373D02*
X951290Y464892D01*
X951165Y465350D01*
X950998Y465767D01*
X950790Y466225D01*
X950457Y466850D01*
X952123D01*
G01X949107Y464725D02*
X948857Y464517D01*
X948565Y464392D01*
X948190Y464350D01*
X947815Y464433D01*
X947523Y464600D01*
X947315Y464892D01*
X947273Y465225D01*
X947357Y465558D01*
X947565Y465767D01*
X947857Y465933D01*
X948148Y465975D01*
X948440Y465933D01*
X948815Y465767D01*
X948690Y466850D01*
X947565D01*
G01X967623Y460350D02*
Y462850D01*
X966582D01*
X966248Y462725D01*
X966040Y462558D01*
X965957Y462225D01*
X966040Y461892D01*
X966290Y461683D01*
X966582Y461558D01*
X967623D01*
G01X966582D02*
X965957Y460350D01*
G01X964482Y462433D02*
X964232Y462683D01*
X963940Y462808D01*
X963607Y462850D01*
X963190Y462767D01*
X962898Y462558D01*
X962815Y462308D01*
X962857Y462058D01*
X963023Y461850D01*
X963857Y461433D01*
X964232Y461142D01*
X964482Y460725D01*
X964565Y460350D01*
X962815D01*
G01X961507Y460725D02*
X961257Y460517D01*
X960965Y460392D01*
X960590Y460350D01*
X960215Y460433D01*
X959923Y460600D01*
X959715Y460892D01*
X959673Y461225D01*
X959757Y461558D01*
X959965Y461767D01*
X960257Y461933D01*
X960548Y461975D01*
X960840Y461933D01*
X961215Y461767D01*
X961090Y462850D01*
X959965D01*
G01X958740D02*
X958157Y460350D01*
X957490Y462850D01*
X956823Y460350D01*
X956240Y462850D01*
G01X954390Y460350D02*
Y462850D01*
X954890Y462350D01*
G01Y460350D02*
X953890D01*
G01X952082Y461392D02*
X951790Y461683D01*
X951540Y461850D01*
X951207Y461933D01*
X950915Y461850D01*
X950707Y461683D01*
X950540Y461433D01*
X950498Y461142D01*
X950540Y460892D01*
X950707Y460642D01*
X950957Y460433D01*
X951248Y460350D01*
X951582Y460433D01*
X951873Y460683D01*
X952040Y461058D01*
X952082Y461475D01*
X951998Y462017D01*
X951873Y462308D01*
X951665Y462600D01*
X951373Y462808D01*
X951082Y462850D01*
X950790Y462767D01*
X950582Y462558D01*
G01X948982Y461392D02*
X948690Y461683D01*
X948440Y461850D01*
X948107Y461933D01*
X947815Y461850D01*
X947607Y461683D01*
X947440Y461433D01*
X947398Y461142D01*
X947440Y460892D01*
X947607Y460642D01*
X947857Y460433D01*
X948148Y460350D01*
X948482Y460433D01*
X948773Y460683D01*
X948940Y461058D01*
X948982Y461475D01*
X948898Y462017D01*
X948773Y462308D01*
X948565Y462600D01*
X948273Y462808D01*
X947982Y462850D01*
X947690Y462767D01*
X947482Y462558D01*
G01X963069Y437442D02*
X963319Y437567D01*
X963611Y437650D01*
X963944D01*
X964319Y437525D01*
X964611Y437317D01*
X964819Y437067D01*
X964986Y436650D01*
X965028Y436275D01*
X964944Y435900D01*
X964819Y435650D01*
X964569Y435400D01*
X964278Y435233D01*
X963986Y435150D01*
X963694D01*
X963403Y435233D01*
X963153Y435358D01*
X962944Y435525D01*
G01X961678Y437233D02*
X961428Y437483D01*
X961136Y437608D01*
X960803Y437650D01*
X960386Y437567D01*
X960094Y437358D01*
X960011Y437108D01*
X960053Y436858D01*
X960219Y436650D01*
X961053Y436233D01*
X961428Y435942D01*
X961678Y435525D01*
X961761Y435150D01*
X960011D01*
G01X958703Y435525D02*
X958453Y435317D01*
X958161Y435192D01*
X957786Y435150D01*
X957411Y435233D01*
X957119Y435400D01*
X956911Y435692D01*
X956869Y436025D01*
X956953Y436358D01*
X957161Y436567D01*
X957453Y436733D01*
X957744Y436775D01*
X958036Y436733D01*
X958411Y436567D01*
X958286Y437650D01*
X957161D01*
G01X955936D02*
X955353Y435150D01*
X954686Y437650D01*
X954019Y435150D01*
X953436Y437650D01*
G01X951669Y435150D02*
X951586Y435692D01*
X951461Y436150D01*
X951294Y436567D01*
X951086Y437025D01*
X950753Y437650D01*
X952419D01*
G01X948569Y435150D02*
X948486Y435692D01*
X948361Y436150D01*
X948194Y436567D01*
X947986Y437025D01*
X947653Y437650D01*
X949319D01*
G01X963069Y433442D02*
X963319Y433567D01*
X963611Y433650D01*
X963944D01*
X964319Y433525D01*
X964611Y433317D01*
X964819Y433067D01*
X964986Y432650D01*
X965028Y432275D01*
X964944Y431900D01*
X964819Y431650D01*
X964569Y431400D01*
X964278Y431233D01*
X963986Y431150D01*
X963694D01*
X963403Y431233D01*
X963153Y431358D01*
X962944Y431525D01*
G01X961678Y433233D02*
X961428Y433483D01*
X961136Y433608D01*
X960803Y433650D01*
X960386Y433567D01*
X960094Y433358D01*
X960011Y433108D01*
X960053Y432858D01*
X960219Y432650D01*
X961053Y432233D01*
X961428Y431942D01*
X961678Y431525D01*
X961761Y431150D01*
X960011D01*
G01X958703Y431525D02*
X958453Y431317D01*
X958161Y431192D01*
X957786Y431150D01*
X957411Y431233D01*
X957119Y431400D01*
X956911Y431692D01*
X956869Y432025D01*
X956953Y432358D01*
X957161Y432567D01*
X957453Y432733D01*
X957744Y432775D01*
X958036Y432733D01*
X958411Y432567D01*
X958286Y433650D01*
X957161D01*
G01X955936D02*
X955353Y431150D01*
X954686Y433650D01*
X954019Y431150D01*
X953436Y433650D01*
G01X951669Y431150D02*
X951586Y431692D01*
X951461Y432150D01*
X951294Y432567D01*
X951086Y433025D01*
X950753Y433650D01*
X952419D01*
G01X949278Y432192D02*
X948986Y432483D01*
X948736Y432650D01*
X948403Y432733D01*
X948111Y432650D01*
X947903Y432483D01*
X947736Y432233D01*
X947694Y431942D01*
X947736Y431692D01*
X947903Y431442D01*
X948153Y431233D01*
X948444Y431150D01*
X948778Y431233D01*
X949069Y431483D01*
X949236Y431858D01*
X949278Y432275D01*
X949194Y432817D01*
X949069Y433108D01*
X948861Y433400D01*
X948569Y433608D01*
X948278Y433650D01*
X947986Y433567D01*
X947778Y433358D01*
G01X963069Y429442D02*
X963319Y429567D01*
X963611Y429650D01*
X963944D01*
X964319Y429525D01*
X964611Y429317D01*
X964819Y429067D01*
X964986Y428650D01*
X965028Y428275D01*
X964944Y427900D01*
X964819Y427650D01*
X964569Y427400D01*
X964278Y427233D01*
X963986Y427150D01*
X963694D01*
X963403Y427233D01*
X963153Y427358D01*
X962944Y427525D01*
G01X961678Y429233D02*
X961428Y429483D01*
X961136Y429608D01*
X960803Y429650D01*
X960386Y429567D01*
X960094Y429358D01*
X960011Y429108D01*
X960053Y428858D01*
X960219Y428650D01*
X961053Y428233D01*
X961428Y427942D01*
X961678Y427525D01*
X961761Y427150D01*
X960011D01*
G01X958703Y427525D02*
X958453Y427317D01*
X958161Y427192D01*
X957786Y427150D01*
X957411Y427233D01*
X957119Y427400D01*
X956911Y427692D01*
X956869Y428025D01*
X956953Y428358D01*
X957161Y428567D01*
X957453Y428733D01*
X957744Y428775D01*
X958036Y428733D01*
X958411Y428567D01*
X958286Y429650D01*
X957161D01*
G01X955936D02*
X955353Y427150D01*
X954686Y429650D01*
X954019Y427150D01*
X953436Y429650D01*
G01X951669Y427150D02*
X951586Y427692D01*
X951461Y428150D01*
X951294Y428567D01*
X951086Y429025D01*
X950753Y429650D01*
X952419D01*
G01X949403Y427525D02*
X949153Y427317D01*
X948861Y427192D01*
X948486Y427150D01*
X948111Y427233D01*
X947819Y427400D01*
X947611Y427692D01*
X947569Y428025D01*
X947653Y428358D01*
X947861Y428567D01*
X948153Y428733D01*
X948444Y428775D01*
X948736Y428733D01*
X949111Y428567D01*
X948986Y429650D01*
X947861D01*
G01X945782Y460517D02*
X945907Y460267D01*
X945990Y459975D01*
Y459642D01*
X945865Y459267D01*
X945657Y458975D01*
X945407Y458767D01*
X944990Y458600D01*
X944615Y458558D01*
X944240Y458642D01*
X943990Y458767D01*
X943740Y459017D01*
X943573Y459308D01*
X943490Y459600D01*
Y459892D01*
X943573Y460183D01*
X943698Y460433D01*
X943865Y460642D01*
G01X945573Y461908D02*
X945823Y462158D01*
X945948Y462450D01*
X945990Y462783D01*
X945907Y463200D01*
X945698Y463492D01*
X945448Y463575D01*
X945198Y463533D01*
X944990Y463367D01*
X944573Y462533D01*
X944282Y462158D01*
X943865Y461908D01*
X943490Y461825D01*
Y463575D01*
G01X943865Y464883D02*
X943657Y465133D01*
X943532Y465425D01*
X943490Y465800D01*
X943573Y466175D01*
X943740Y466467D01*
X944032Y466675D01*
X944365Y466717D01*
X944698Y466633D01*
X944907Y466425D01*
X945073Y466133D01*
X945115Y465842D01*
X945073Y465550D01*
X944907Y465175D01*
X945990Y465300D01*
Y466425D01*
G01Y467650D02*
X943490Y468233D01*
X945990Y468900D01*
X943490Y469567D01*
X945990Y470150D01*
G01X943782Y471292D02*
X943573Y471583D01*
X943490Y471917D01*
X943573Y472250D01*
X943823Y472542D01*
X944198Y472750D01*
X944573Y472833D01*
X945032D01*
X945407Y472750D01*
X945740Y472542D01*
X945907Y472292D01*
X945990Y472000D01*
X945907Y471667D01*
X945740Y471417D01*
X945490Y471250D01*
X945157Y471167D01*
X944865Y471250D01*
X944573Y471458D01*
X944407Y471708D01*
X944365Y472000D01*
X944448Y472333D01*
X944657Y472583D01*
X945032Y472833D01*
G01X943490Y475100D02*
X943532Y475392D01*
X943657Y475725D01*
X943865Y475933D01*
X944157Y476017D01*
X944448Y475933D01*
X944698Y475683D01*
X944823Y475308D01*
Y474892D01*
X944907Y474642D01*
X945115Y474433D01*
X945407Y474350D01*
X945698Y474475D01*
X945907Y474767D01*
X945990Y475100D01*
X945907Y475433D01*
X945698Y475725D01*
X945407Y475850D01*
X945115Y475767D01*
X944907Y475558D01*
X944823Y475308D01*
Y474892D01*
X944698Y474517D01*
X944448Y474267D01*
X944157Y474183D01*
X943865Y474267D01*
X943657Y474475D01*
X943532Y474808D01*
X943490Y475100D01*
G01X941657Y466850D02*
Y465058D01*
X941490Y464683D01*
X941157Y464433D01*
X940740Y464350D01*
X940323Y464433D01*
X939990Y464683D01*
X939823Y465058D01*
Y466850D01*
G01X938432Y466433D02*
X938182Y466683D01*
X937890Y466808D01*
X937557Y466850D01*
X937140Y466767D01*
X936848Y466558D01*
X936765Y466308D01*
X936807Y466058D01*
X936973Y465850D01*
X937807Y465433D01*
X938182Y465142D01*
X938432Y464725D01*
X938515Y464350D01*
X936765D01*
G01X935457Y464725D02*
X935207Y464517D01*
X934915Y464392D01*
X934540Y464350D01*
X934165Y464433D01*
X933873Y464600D01*
X933665Y464892D01*
X933623Y465225D01*
X933707Y465558D01*
X933915Y465767D01*
X934207Y465933D01*
X934498Y465975D01*
X934790Y465933D01*
X935165Y465767D01*
X935040Y466850D01*
X933915D01*
G01X932690D02*
X932107Y464350D01*
X931440Y466850D01*
X930773Y464350D01*
X930190Y466850D01*
G01X928340Y464350D02*
Y466850D01*
X928840Y466350D01*
G01Y464350D02*
X927840D01*
G01X926032Y465392D02*
X925740Y465683D01*
X925490Y465850D01*
X925157Y465933D01*
X924865Y465850D01*
X924657Y465683D01*
X924490Y465433D01*
X924448Y465142D01*
X924490Y464892D01*
X924657Y464642D01*
X924907Y464433D01*
X925198Y464350D01*
X925532Y464433D01*
X925823Y464683D01*
X925990Y465058D01*
X926032Y465475D01*
X925948Y466017D01*
X925823Y466308D01*
X925615Y466600D01*
X925323Y466808D01*
X925032Y466850D01*
X924740Y466767D01*
X924532Y466558D01*
G01X944069Y437900D02*
Y435400D01*
X942403D01*
G01X940928Y437483D02*
X940678Y437733D01*
X940386Y437858D01*
X940053Y437900D01*
X939636Y437817D01*
X939344Y437608D01*
X939261Y437358D01*
X939303Y437108D01*
X939469Y436900D01*
X940303Y436483D01*
X940678Y436192D01*
X940928Y435775D01*
X941011Y435400D01*
X939261D01*
G01X937953Y435775D02*
X937703Y435567D01*
X937411Y435442D01*
X937036Y435400D01*
X936661Y435483D01*
X936369Y435650D01*
X936161Y435942D01*
X936119Y436275D01*
X936203Y436608D01*
X936411Y436817D01*
X936703Y436983D01*
X936994Y437025D01*
X937286Y436983D01*
X937661Y436817D01*
X937536Y437900D01*
X936411D01*
G01X935186D02*
X934603Y435400D01*
X933936Y437900D01*
X933269Y435400D01*
X932686Y437900D01*
G01X931753Y435900D02*
X931503Y435608D01*
X931169Y435442D01*
X930794Y435400D01*
X930461Y435442D01*
X930128Y435650D01*
X929919Y435900D01*
X929878Y436150D01*
X929961Y436442D01*
X930253Y436650D01*
X930544Y436733D01*
X930919D01*
G01X930544D02*
X930294Y436858D01*
X930086Y437067D01*
X930003Y437317D01*
X930086Y437567D01*
X930294Y437775D01*
X930669Y437900D01*
X931044Y437858D01*
X931419Y437692D01*
G01X944069Y433900D02*
Y431400D01*
X942403D01*
G01X940928Y433483D02*
X940678Y433733D01*
X940386Y433858D01*
X940053Y433900D01*
X939636Y433817D01*
X939344Y433608D01*
X939261Y433358D01*
X939303Y433108D01*
X939469Y432900D01*
X940303Y432483D01*
X940678Y432192D01*
X940928Y431775D01*
X941011Y431400D01*
X939261D01*
G01X937953Y431775D02*
X937703Y431567D01*
X937411Y431442D01*
X937036Y431400D01*
X936661Y431483D01*
X936369Y431650D01*
X936161Y431942D01*
X936119Y432275D01*
X936203Y432608D01*
X936411Y432817D01*
X936703Y432983D01*
X936994Y433025D01*
X937286Y432983D01*
X937661Y432817D01*
X937536Y433900D01*
X936411D01*
G01X935186D02*
X934603Y431400D01*
X933936Y433900D01*
X933269Y431400D01*
X932686Y433900D01*
G01X931628Y433483D02*
X931378Y433733D01*
X931086Y433858D01*
X930753Y433900D01*
X930336Y433817D01*
X930044Y433608D01*
X929961Y433358D01*
X930003Y433108D01*
X930169Y432900D01*
X931003Y432483D01*
X931378Y432192D01*
X931628Y431775D01*
X931711Y431400D01*
X929961D01*
G01X944069Y429900D02*
Y427400D01*
X942403D01*
G01X940928Y429483D02*
X940678Y429733D01*
X940386Y429858D01*
X940053Y429900D01*
X939636Y429817D01*
X939344Y429608D01*
X939261Y429358D01*
X939303Y429108D01*
X939469Y428900D01*
X940303Y428483D01*
X940678Y428192D01*
X940928Y427775D01*
X941011Y427400D01*
X939261D01*
G01X937953Y427775D02*
X937703Y427567D01*
X937411Y427442D01*
X937036Y427400D01*
X936661Y427483D01*
X936369Y427650D01*
X936161Y427942D01*
X936119Y428275D01*
X936203Y428608D01*
X936411Y428817D01*
X936703Y428983D01*
X936994Y429025D01*
X937286Y428983D01*
X937661Y428817D01*
X937536Y429900D01*
X936411D01*
G01X935186D02*
X934603Y427400D01*
X933936Y429900D01*
X933269Y427400D01*
X932686Y429900D01*
G01X930836Y427400D02*
Y429900D01*
X931336Y429400D01*
G01Y427400D02*
X930336D01*
G01X957702Y449760D02*
Y452260D01*
X956118D01*
G01X956702Y451052D02*
X957702D01*
G01X953477Y451093D02*
X953310Y451218D01*
X953185Y451427D01*
X953102Y451718D01*
X953185Y451968D01*
X953352Y452135D01*
X953643Y452260D01*
X954768D01*
Y449760D01*
X953393D01*
X953102Y449927D01*
X952935Y450177D01*
X952852Y450468D01*
X952935Y450760D01*
X953185Y451010D01*
X953477Y451093D01*
X954768D01*
G01X951502Y451843D02*
X951252Y452093D01*
X950960Y452218D01*
X950627Y452260D01*
X950210Y452177D01*
X949918Y451968D01*
X949835Y451718D01*
X949877Y451468D01*
X950043Y451260D01*
X950877Y450843D01*
X951252Y450552D01*
X951502Y450135D01*
X951585Y449760D01*
X949835D01*
G01X948527Y450135D02*
X948277Y449927D01*
X947985Y449802D01*
X947610Y449760D01*
X947235Y449843D01*
X946943Y450010D01*
X946735Y450302D01*
X946693Y450635D01*
X946777Y450968D01*
X946985Y451177D01*
X947277Y451343D01*
X947568Y451385D01*
X947860Y451343D01*
X948235Y451177D01*
X948110Y452260D01*
X946985D01*
G01X945760D02*
X945177Y449760D01*
X944510Y452260D01*
X943843Y449760D01*
X943260Y452260D01*
G01X940910Y449760D02*
Y452260D01*
X942452Y450468D01*
X940368D01*
G01X957492Y454040D02*
Y456540D01*
X955908D01*
G01X956492Y455332D02*
X957492D01*
G01X953267Y455373D02*
X953100Y455498D01*
X952975Y455707D01*
X952892Y455998D01*
X952975Y456248D01*
X953142Y456415D01*
X953433Y456540D01*
X954558D01*
Y454040D01*
X953183D01*
X952892Y454207D01*
X952725Y454457D01*
X952642Y454748D01*
X952725Y455040D01*
X952975Y455290D01*
X953267Y455373D01*
X954558D01*
G01X951292Y456123D02*
X951042Y456373D01*
X950750Y456498D01*
X950417Y456540D01*
X950000Y456457D01*
X949708Y456248D01*
X949625Y455998D01*
X949667Y455748D01*
X949833Y455540D01*
X950667Y455123D01*
X951042Y454832D01*
X951292Y454415D01*
X951375Y454040D01*
X949625D01*
G01X948317Y454415D02*
X948067Y454207D01*
X947775Y454082D01*
X947400Y454040D01*
X947025Y454123D01*
X946733Y454290D01*
X946525Y454582D01*
X946483Y454915D01*
X946567Y455248D01*
X946775Y455457D01*
X947067Y455623D01*
X947358Y455665D01*
X947650Y455623D01*
X948025Y455457D01*
X947900Y456540D01*
X946775D01*
G01X945550D02*
X944967Y454040D01*
X944300Y456540D01*
X943633Y454040D01*
X943050Y456540D01*
G01X942117Y454415D02*
X941867Y454207D01*
X941575Y454082D01*
X941200Y454040D01*
X940825Y454123D01*
X940533Y454290D01*
X940325Y454582D01*
X940283Y454915D01*
X940367Y455248D01*
X940575Y455457D01*
X940867Y455623D01*
X941158Y455665D01*
X941450Y455623D01*
X941825Y455457D01*
X941700Y456540D01*
X940575D01*
G01X967623Y476350D02*
Y478850D01*
X966582D01*
X966248Y478725D01*
X966040Y478558D01*
X965957Y478225D01*
X966040Y477892D01*
X966290Y477683D01*
X966582Y477558D01*
X967623D01*
G01X966582D02*
X965957Y476350D01*
G01X964482Y478433D02*
X964232Y478683D01*
X963940Y478808D01*
X963607Y478850D01*
X963190Y478767D01*
X962898Y478558D01*
X962815Y478308D01*
X962857Y478058D01*
X963023Y477850D01*
X963857Y477433D01*
X964232Y477142D01*
X964482Y476725D01*
X964565Y476350D01*
X962815D01*
G01X961507Y476725D02*
X961257Y476517D01*
X960965Y476392D01*
X960590Y476350D01*
X960215Y476433D01*
X959923Y476600D01*
X959715Y476892D01*
X959673Y477225D01*
X959757Y477558D01*
X959965Y477767D01*
X960257Y477933D01*
X960548Y477975D01*
X960840Y477933D01*
X961215Y477767D01*
X961090Y478850D01*
X959965D01*
G01X958740D02*
X958157Y476350D01*
X957490Y478850D01*
X956823Y476350D01*
X956240Y478850D01*
G01X954390Y476350D02*
Y478850D01*
X954890Y478350D01*
G01Y476350D02*
X953890D01*
G01X951373D02*
X951290Y476892D01*
X951165Y477350D01*
X950998Y477767D01*
X950790Y478225D01*
X950457Y478850D01*
X952123D01*
G01X948982Y477392D02*
X948690Y477683D01*
X948440Y477850D01*
X948107Y477933D01*
X947815Y477850D01*
X947607Y477683D01*
X947440Y477433D01*
X947398Y477142D01*
X947440Y476892D01*
X947607Y476642D01*
X947857Y476433D01*
X948148Y476350D01*
X948482Y476433D01*
X948773Y476683D01*
X948940Y477058D01*
X948982Y477475D01*
X948898Y478017D01*
X948773Y478308D01*
X948565Y478600D01*
X948273Y478808D01*
X947982Y478850D01*
X947690Y478767D01*
X947482Y478558D01*
G01X967623Y472350D02*
Y474850D01*
X966582D01*
X966248Y474725D01*
X966040Y474558D01*
X965957Y474225D01*
X966040Y473892D01*
X966290Y473683D01*
X966582Y473558D01*
X967623D01*
G01X966582D02*
X965957Y472350D01*
G01X964482Y474433D02*
X964232Y474683D01*
X963940Y474808D01*
X963607Y474850D01*
X963190Y474767D01*
X962898Y474558D01*
X962815Y474308D01*
X962857Y474058D01*
X963023Y473850D01*
X963857Y473433D01*
X964232Y473142D01*
X964482Y472725D01*
X964565Y472350D01*
X962815D01*
G01X961507Y472725D02*
X961257Y472517D01*
X960965Y472392D01*
X960590Y472350D01*
X960215Y472433D01*
X959923Y472600D01*
X959715Y472892D01*
X959673Y473225D01*
X959757Y473558D01*
X959965Y473767D01*
X960257Y473933D01*
X960548Y473975D01*
X960840Y473933D01*
X961215Y473767D01*
X961090Y474850D01*
X959965D01*
G01X958740D02*
X958157Y472350D01*
X957490Y474850D01*
X956823Y472350D01*
X956240Y474850D01*
G01X954390Y472350D02*
Y474850D01*
X954890Y474350D01*
G01Y472350D02*
X953890D01*
G01X952082Y473392D02*
X951790Y473683D01*
X951540Y473850D01*
X951207Y473933D01*
X950915Y473850D01*
X950707Y473683D01*
X950540Y473433D01*
X950498Y473142D01*
X950540Y472892D01*
X950707Y472642D01*
X950957Y472433D01*
X951248Y472350D01*
X951582Y472433D01*
X951873Y472683D01*
X952040Y473058D01*
X952082Y473475D01*
X951998Y474017D01*
X951873Y474308D01*
X951665Y474600D01*
X951373Y474808D01*
X951082Y474850D01*
X950790Y474767D01*
X950582Y474558D01*
G01X949107Y472725D02*
X948857Y472517D01*
X948565Y472392D01*
X948190Y472350D01*
X947815Y472433D01*
X947523Y472600D01*
X947315Y472892D01*
X947273Y473225D01*
X947357Y473558D01*
X947565Y473767D01*
X947857Y473933D01*
X948148Y473975D01*
X948440Y473933D01*
X948815Y473767D01*
X948690Y474850D01*
X947565D01*
G01X948123Y480850D02*
Y483350D01*
X947082D01*
X946748Y483225D01*
X946540Y483058D01*
X946457Y482725D01*
X946540Y482392D01*
X946790Y482183D01*
X947082Y482058D01*
X948123D01*
G01X947082D02*
X946457Y480850D01*
G01X944982Y482933D02*
X944732Y483183D01*
X944440Y483308D01*
X944107Y483350D01*
X943690Y483267D01*
X943398Y483058D01*
X943315Y482808D01*
X943357Y482558D01*
X943523Y482350D01*
X944357Y481933D01*
X944732Y481642D01*
X944982Y481225D01*
X945065Y480850D01*
X943315D01*
G01X942007Y481225D02*
X941757Y481017D01*
X941465Y480892D01*
X941090Y480850D01*
X940715Y480933D01*
X940423Y481100D01*
X940215Y481392D01*
X940173Y481725D01*
X940257Y482058D01*
X940465Y482267D01*
X940757Y482433D01*
X941048Y482475D01*
X941340Y482433D01*
X941715Y482267D01*
X941590Y483350D01*
X940465D01*
G01X939240D02*
X938657Y480850D01*
X937990Y483350D01*
X937323Y480850D01*
X936740Y483350D01*
G01X934890Y480850D02*
Y483350D01*
X935390Y482850D01*
G01Y480850D02*
X934390D01*
G01X931873D02*
X931790Y481392D01*
X931665Y481850D01*
X931498Y482267D01*
X931290Y482725D01*
X930957Y483350D01*
X932623D01*
G01X929398Y481142D02*
X929107Y480933D01*
X928773Y480850D01*
X928440Y480933D01*
X928148Y481183D01*
X927940Y481558D01*
X927857Y481933D01*
Y482392D01*
X927940Y482767D01*
X928148Y483100D01*
X928398Y483267D01*
X928690Y483350D01*
X929023Y483267D01*
X929273Y483100D01*
X929440Y482850D01*
X929523Y482517D01*
X929440Y482225D01*
X929232Y481933D01*
X928982Y481767D01*
X928690Y481725D01*
X928357Y481808D01*
X928107Y482017D01*
X927857Y482392D01*
G01X941657Y475350D02*
Y473558D01*
X941490Y473183D01*
X941157Y472933D01*
X940740Y472850D01*
X940323Y472933D01*
X939990Y473183D01*
X939823Y473558D01*
Y475350D01*
G01X938432Y474933D02*
X938182Y475183D01*
X937890Y475308D01*
X937557Y475350D01*
X937140Y475267D01*
X936848Y475058D01*
X936765Y474808D01*
X936807Y474558D01*
X936973Y474350D01*
X937807Y473933D01*
X938182Y473642D01*
X938432Y473225D01*
X938515Y472850D01*
X936765D01*
G01X935457Y473225D02*
X935207Y473017D01*
X934915Y472892D01*
X934540Y472850D01*
X934165Y472933D01*
X933873Y473100D01*
X933665Y473392D01*
X933623Y473725D01*
X933707Y474058D01*
X933915Y474267D01*
X934207Y474433D01*
X934498Y474475D01*
X934790Y474433D01*
X935165Y474267D01*
X935040Y475350D01*
X933915D01*
G01X932690D02*
X932107Y472850D01*
X931440Y475350D01*
X930773Y472850D01*
X930190Y475350D01*
G01X928340Y472850D02*
Y475350D01*
X928840Y474850D01*
G01Y472850D02*
X927840D01*
G01X926157Y473225D02*
X925907Y473017D01*
X925615Y472892D01*
X925240Y472850D01*
X924865Y472933D01*
X924573Y473100D01*
X924365Y473392D01*
X924323Y473725D01*
X924407Y474058D01*
X924615Y474267D01*
X924907Y474433D01*
X925198Y474475D01*
X925490Y474433D01*
X925865Y474267D01*
X925740Y475350D01*
X924615D01*
G01X941657Y478850D02*
Y477058D01*
X941490Y476683D01*
X941157Y476433D01*
X940740Y476350D01*
X940323Y476433D01*
X939990Y476683D01*
X939823Y477058D01*
Y478850D01*
G01X938432Y478433D02*
X938182Y478683D01*
X937890Y478808D01*
X937557Y478850D01*
X937140Y478767D01*
X936848Y478558D01*
X936765Y478308D01*
X936807Y478058D01*
X936973Y477850D01*
X937807Y477433D01*
X938182Y477142D01*
X938432Y476725D01*
X938515Y476350D01*
X936765D01*
G01X935457Y476725D02*
X935207Y476517D01*
X934915Y476392D01*
X934540Y476350D01*
X934165Y476433D01*
X933873Y476600D01*
X933665Y476892D01*
X933623Y477225D01*
X933707Y477558D01*
X933915Y477767D01*
X934207Y477933D01*
X934498Y477975D01*
X934790Y477933D01*
X935165Y477767D01*
X935040Y478850D01*
X933915D01*
G01X932690D02*
X932107Y476350D01*
X931440Y478850D01*
X930773Y476350D01*
X930190Y478850D01*
G01X928340Y476350D02*
Y478850D01*
X928840Y478350D01*
G01Y476350D02*
X927840D01*
G01X924740D02*
Y478850D01*
X926282Y477058D01*
X924198D01*
G01X965873Y470642D02*
X966123Y470767D01*
X966415Y470850D01*
X966748D01*
X967123Y470725D01*
X967415Y470517D01*
X967623Y470267D01*
X967790Y469850D01*
X967832Y469475D01*
X967748Y469100D01*
X967623Y468850D01*
X967373Y468600D01*
X967082Y468433D01*
X966790Y468350D01*
X966498D01*
X966207Y468433D01*
X965957Y468558D01*
X965748Y468725D01*
G01X964482Y470433D02*
X964232Y470683D01*
X963940Y470808D01*
X963607Y470850D01*
X963190Y470767D01*
X962898Y470558D01*
X962815Y470308D01*
X962857Y470058D01*
X963023Y469850D01*
X963857Y469433D01*
X964232Y469142D01*
X964482Y468725D01*
X964565Y468350D01*
X962815D01*
G01X961507Y468725D02*
X961257Y468517D01*
X960965Y468392D01*
X960590Y468350D01*
X960215Y468433D01*
X959923Y468600D01*
X959715Y468892D01*
X959673Y469225D01*
X959757Y469558D01*
X959965Y469767D01*
X960257Y469933D01*
X960548Y469975D01*
X960840Y469933D01*
X961215Y469767D01*
X961090Y470850D01*
X959965D01*
G01X958740D02*
X958157Y468350D01*
X957490Y470850D01*
X956823Y468350D01*
X956240Y470850D01*
G01X955098Y468642D02*
X954807Y468433D01*
X954473Y468350D01*
X954140Y468433D01*
X953848Y468683D01*
X953640Y469058D01*
X953557Y469433D01*
Y469892D01*
X953640Y470267D01*
X953848Y470600D01*
X954098Y470767D01*
X954390Y470850D01*
X954723Y470767D01*
X954973Y470600D01*
X955140Y470350D01*
X955223Y470017D01*
X955140Y469725D01*
X954932Y469433D01*
X954682Y469267D01*
X954390Y469225D01*
X954057Y469308D01*
X953807Y469517D01*
X953557Y469892D01*
G01X952207Y468850D02*
X951957Y468558D01*
X951623Y468392D01*
X951248Y468350D01*
X950915Y468392D01*
X950582Y468600D01*
X950373Y468850D01*
X950332Y469100D01*
X950415Y469392D01*
X950707Y469600D01*
X950998Y469683D01*
X951373D01*
G01X950998D02*
X950748Y469808D01*
X950540Y470017D01*
X950457Y470267D01*
X950540Y470517D01*
X950748Y470725D01*
X951123Y470850D01*
X951498Y470808D01*
X951873Y470642D01*
G01X946373Y487142D02*
X946623Y487267D01*
X946915Y487350D01*
X947248D01*
X947623Y487225D01*
X947915Y487017D01*
X948123Y486767D01*
X948290Y486350D01*
X948332Y485975D01*
X948248Y485600D01*
X948123Y485350D01*
X947873Y485100D01*
X947582Y484933D01*
X947290Y484850D01*
X946998D01*
X946707Y484933D01*
X946457Y485058D01*
X946248Y485225D01*
G01X944982Y486933D02*
X944732Y487183D01*
X944440Y487308D01*
X944107Y487350D01*
X943690Y487267D01*
X943398Y487058D01*
X943315Y486808D01*
X943357Y486558D01*
X943523Y486350D01*
X944357Y485933D01*
X944732Y485642D01*
X944982Y485225D01*
X945065Y484850D01*
X943315D01*
G01X942007Y485225D02*
X941757Y485017D01*
X941465Y484892D01*
X941090Y484850D01*
X940715Y484933D01*
X940423Y485100D01*
X940215Y485392D01*
X940173Y485725D01*
X940257Y486058D01*
X940465Y486267D01*
X940757Y486433D01*
X941048Y486475D01*
X941340Y486433D01*
X941715Y486267D01*
X941590Y487350D01*
X940465D01*
G01X939240D02*
X938657Y484850D01*
X937990Y487350D01*
X937323Y484850D01*
X936740Y487350D01*
G01X935598Y485142D02*
X935307Y484933D01*
X934973Y484850D01*
X934640Y484933D01*
X934348Y485183D01*
X934140Y485558D01*
X934057Y485933D01*
Y486392D01*
X934140Y486767D01*
X934348Y487100D01*
X934598Y487267D01*
X934890Y487350D01*
X935223Y487267D01*
X935473Y487100D01*
X935640Y486850D01*
X935723Y486517D01*
X935640Y486225D01*
X935432Y485933D01*
X935182Y485767D01*
X934890Y485725D01*
X934557Y485808D01*
X934307Y486017D01*
X934057Y486392D01*
G01X932582Y485892D02*
X932290Y486183D01*
X932040Y486350D01*
X931707Y486433D01*
X931415Y486350D01*
X931207Y486183D01*
X931040Y485933D01*
X930998Y485642D01*
X931040Y485392D01*
X931207Y485142D01*
X931457Y484933D01*
X931748Y484850D01*
X932082Y484933D01*
X932373Y485183D01*
X932540Y485558D01*
X932582Y485975D01*
X932498Y486517D01*
X932373Y486808D01*
X932165Y487100D01*
X931873Y487308D01*
X931582Y487350D01*
X931290Y487267D01*
X931082Y487058D01*
G01X964870Y490944D02*
X965120Y491069D01*
X965412Y491152D01*
X965745D01*
X966120Y491027D01*
X966412Y490819D01*
X966620Y490569D01*
X966787Y490152D01*
X966829Y489777D01*
X966745Y489402D01*
X966620Y489152D01*
X966370Y488902D01*
X966079Y488735D01*
X965787Y488652D01*
X965495D01*
X965204Y488735D01*
X964954Y488860D01*
X964745Y489027D01*
G01X963604D02*
X963354Y488819D01*
X963062Y488694D01*
X962687Y488652D01*
X962312Y488735D01*
X962020Y488902D01*
X961812Y489194D01*
X961770Y489527D01*
X961854Y489860D01*
X962062Y490069D01*
X962354Y490235D01*
X962645Y490277D01*
X962937Y490235D01*
X963312Y490069D01*
X963187Y491152D01*
X962062D01*
G01X960670Y488652D02*
Y491152D01*
X959587Y489069D01*
X958504Y491152D01*
Y488652D01*
G01X956487D02*
Y491152D01*
X956987Y490652D01*
G01Y488652D02*
X955987D01*
G01X953387Y491152D02*
X953720Y491069D01*
X953970Y490860D01*
X954137Y490610D01*
X954262Y490277D01*
X954304Y489902D01*
X954262Y489527D01*
X954137Y489194D01*
X953970Y488944D01*
X953720Y488735D01*
X953387Y488652D01*
X953054Y488735D01*
X952804Y488944D01*
X952637Y489194D01*
X952512Y489527D01*
X952470Y489902D01*
X952512Y490277D01*
X952637Y490610D01*
X952804Y490860D01*
X953054Y491069D01*
X953387Y491152D01*
G01X981443Y491244D02*
X981693Y491369D01*
X981985Y491452D01*
X982318D01*
X982693Y491327D01*
X982985Y491119D01*
X983193Y490869D01*
X983360Y490452D01*
X983402Y490077D01*
X983318Y489702D01*
X983193Y489452D01*
X982943Y489202D01*
X982652Y489035D01*
X982360Y488952D01*
X982068D01*
X981777Y489035D01*
X981527Y489160D01*
X981318Y489327D01*
G01X980177D02*
X979927Y489119D01*
X979635Y488994D01*
X979260Y488952D01*
X978885Y489035D01*
X978593Y489202D01*
X978385Y489494D01*
X978343Y489827D01*
X978427Y490160D01*
X978635Y490369D01*
X978927Y490535D01*
X979218Y490577D01*
X979510Y490535D01*
X979885Y490369D01*
X979760Y491452D01*
X978635D01*
G01X977243Y488952D02*
Y491452D01*
X976160Y489369D01*
X975077Y491452D01*
Y488952D01*
G01X973060D02*
Y491452D01*
X973560Y490952D01*
G01Y488952D02*
X972560D01*
G01X969960D02*
Y491452D01*
X970460Y490952D01*
G01Y488952D02*
X969460D01*
G01X963690Y480350D02*
X964023Y480392D01*
X964315Y480558D01*
X964565Y480808D01*
X964732Y481100D01*
X964815Y481433D01*
Y481767D01*
X964732Y482100D01*
X964565Y482392D01*
X964315Y482642D01*
X964023Y482808D01*
X963690Y482850D01*
X963357Y482808D01*
X963065Y482642D01*
X962815Y482392D01*
X962648Y482100D01*
X962565Y481767D01*
Y481433D01*
X962648Y481100D01*
X962815Y480808D01*
X963065Y480558D01*
X963357Y480392D01*
X963690Y480350D01*
G01X963357Y481017D02*
X962857Y480350D01*
G01X961382Y482433D02*
X961132Y482683D01*
X960840Y482808D01*
X960507Y482850D01*
X960090Y482767D01*
X959798Y482558D01*
X959715Y482308D01*
X959757Y482058D01*
X959923Y481850D01*
X960757Y481433D01*
X961132Y481142D01*
X961382Y480725D01*
X961465Y480350D01*
X959715D01*
G01X958407Y480725D02*
X958157Y480517D01*
X957865Y480392D01*
X957490Y480350D01*
X957115Y480433D01*
X956823Y480600D01*
X956615Y480892D01*
X956573Y481225D01*
X956657Y481558D01*
X956865Y481767D01*
X957157Y481933D01*
X957448Y481975D01*
X957740Y481933D01*
X958115Y481767D01*
X957990Y482850D01*
X956865D01*
G01X955640D02*
X955057Y480350D01*
X954390Y482850D01*
X953723Y480350D01*
X953140Y482850D01*
G01X952207Y480725D02*
X951957Y480517D01*
X951665Y480392D01*
X951290Y480350D01*
X950915Y480433D01*
X950623Y480600D01*
X950415Y480892D01*
X950373Y481225D01*
X950457Y481558D01*
X950665Y481767D01*
X950957Y481933D01*
X951248Y481975D01*
X951540Y481933D01*
X951915Y481767D01*
X951790Y482850D01*
X950665D01*
G01X918252Y639820D02*
X950952D01*
Y658520D01*
X918252D01*
Y639820D01*
G01X1017512Y-13396D02*
X1017762Y-13271D01*
X1018054Y-13188D01*
X1018387D01*
X1018762Y-13313D01*
X1019054Y-13521D01*
X1019262Y-13771D01*
X1019429Y-14188D01*
X1019471Y-14563D01*
X1019387Y-14938D01*
X1019262Y-15188D01*
X1019012Y-15438D01*
X1018721Y-15605D01*
X1018429Y-15688D01*
X1018137D01*
X1017846Y-15605D01*
X1017596Y-15480D01*
X1017387Y-15313D01*
G01X1016246D02*
X1015996Y-15521D01*
X1015704Y-15646D01*
X1015329Y-15688D01*
X1014954Y-15605D01*
X1014662Y-15438D01*
X1014454Y-15146D01*
X1014412Y-14813D01*
X1014496Y-14480D01*
X1014704Y-14271D01*
X1014996Y-14105D01*
X1015287Y-14063D01*
X1015579Y-14105D01*
X1015954Y-14271D01*
X1015829Y-13188D01*
X1014704D01*
G01X1013146D02*
Y-14980D01*
X1012979Y-15355D01*
X1012646Y-15605D01*
X1012229Y-15688D01*
X1011812Y-15605D01*
X1011479Y-15355D01*
X1011312Y-14980D01*
Y-13188D01*
G01X1009129Y-15688D02*
Y-13188D01*
X1009629Y-13688D01*
G01Y-15688D02*
X1008629D01*
G01X1006821Y-14646D02*
X1006529Y-14355D01*
X1006279Y-14188D01*
X1005946Y-14105D01*
X1005654Y-14188D01*
X1005446Y-14355D01*
X1005279Y-14605D01*
X1005237Y-14896D01*
X1005279Y-15146D01*
X1005446Y-15396D01*
X1005696Y-15605D01*
X1005987Y-15688D01*
X1006321Y-15605D01*
X1006612Y-15355D01*
X1006779Y-14980D01*
X1006821Y-14563D01*
X1006737Y-14021D01*
X1006612Y-13730D01*
X1006404Y-13438D01*
X1006112Y-13230D01*
X1005821Y-13188D01*
X1005529Y-13271D01*
X1005321Y-13480D01*
G01X1026929Y24500D02*
X1026852Y25172D01*
X1026737Y25740D01*
X1026584Y26257D01*
X1026392Y26825D01*
X1026085Y27600D01*
X1027619D01*
G01X1023829Y24500D02*
X1023752Y25172D01*
X1023637Y25740D01*
X1023484Y26257D01*
X1023292Y26825D01*
X1022985Y27600D01*
X1024519D01*
G01X1029580Y-417D02*
X1029350Y-107D01*
X1029082Y48D01*
X1028775Y100D01*
X1028392Y-3D01*
X1028124Y-262D01*
X1028047Y-572D01*
X1028085Y-882D01*
X1028239Y-1140D01*
X1029005Y-1657D01*
X1029350Y-2018D01*
X1029580Y-2535D01*
X1029657Y-3000D01*
X1028047D01*
G01X1026480Y-417D02*
X1026250Y-107D01*
X1025982Y48D01*
X1025675Y100D01*
X1025292Y-3D01*
X1025024Y-262D01*
X1024947Y-572D01*
X1024985Y-882D01*
X1025139Y-1140D01*
X1025905Y-1657D01*
X1026250Y-2018D01*
X1026480Y-2535D01*
X1026557Y-3000D01*
X1024947D01*
G01X1022652D02*
Y100D01*
X1023112Y-520D01*
G01Y-3000D02*
X1022192D01*
G01X1023214Y-8100D02*
X1022881Y-8308D01*
X1022506Y-8433D01*
X1022172D01*
X1021839Y-8308D01*
X1021589Y-8100D01*
X1021464Y-7808D01*
X1021547Y-7516D01*
X1021756Y-7266D01*
X1022131Y-7100D01*
X1022631Y-7016D01*
X1022922Y-6850D01*
X1023047Y-6558D01*
X1022964Y-6266D01*
X1022756Y-6058D01*
X1022464Y-5933D01*
X1022172D01*
X1021881Y-6016D01*
X1021631Y-6225D01*
G01X1020114Y-8433D02*
Y-5933D01*
G01X1018364D02*
Y-8433D01*
G01Y-7183D02*
X1020114D01*
G01X1017056Y-8058D02*
X1016806Y-8266D01*
X1016514Y-8391D01*
X1016139Y-8433D01*
X1015764Y-8350D01*
X1015472Y-8183D01*
X1015264Y-7891D01*
X1015222Y-7558D01*
X1015306Y-7225D01*
X1015514Y-7016D01*
X1015806Y-6850D01*
X1016097Y-6808D01*
X1016389Y-6850D01*
X1016764Y-7016D01*
X1016639Y-5933D01*
X1015514D01*
G01X1013956D02*
Y-7725D01*
X1013789Y-8100D01*
X1013456Y-8350D01*
X1013039Y-8433D01*
X1012622Y-8350D01*
X1012289Y-8100D01*
X1012122Y-7725D01*
Y-5933D01*
G01X1009939Y-8433D02*
Y-5933D01*
X1010439Y-6433D01*
G01Y-8433D02*
X1009439D01*
G01X1032580Y77083D02*
X1032350Y77393D01*
X1032082Y77548D01*
X1031775Y77600D01*
X1031392Y77497D01*
X1031124Y77238D01*
X1031047Y76928D01*
X1031085Y76618D01*
X1031239Y76360D01*
X1032005Y75843D01*
X1032350Y75482D01*
X1032580Y74965D01*
X1032657Y74500D01*
X1031047D01*
G01X1029480Y77083D02*
X1029250Y77393D01*
X1028982Y77548D01*
X1028675Y77600D01*
X1028292Y77497D01*
X1028024Y77238D01*
X1027947Y76928D01*
X1027985Y76618D01*
X1028139Y76360D01*
X1028905Y75843D01*
X1029250Y75482D01*
X1029480Y74965D01*
X1029557Y74500D01*
X1027947D01*
G01X1025652D02*
Y77600D01*
X1026112Y76980D01*
G01Y74500D02*
X1025192D01*
G01X1026929Y62000D02*
X1026852Y62672D01*
X1026737Y63240D01*
X1026584Y63757D01*
X1026392Y64325D01*
X1026085Y65100D01*
X1027619D01*
G01X1023829Y62000D02*
X1023752Y62672D01*
X1023637Y63240D01*
X1023484Y63757D01*
X1023292Y64325D01*
X1022985Y65100D01*
X1024519D01*
G01X1030580Y38583D02*
X1030350Y38893D01*
X1030082Y39048D01*
X1029775Y39100D01*
X1029392Y38997D01*
X1029124Y38738D01*
X1029047Y38428D01*
X1029085Y38118D01*
X1029239Y37860D01*
X1030005Y37343D01*
X1030350Y36982D01*
X1030580Y36465D01*
X1030657Y36000D01*
X1029047D01*
G01X1027480Y38583D02*
X1027250Y38893D01*
X1026982Y39048D01*
X1026675Y39100D01*
X1026292Y38997D01*
X1026024Y38738D01*
X1025947Y38428D01*
X1025985Y38118D01*
X1026139Y37860D01*
X1026905Y37343D01*
X1027250Y36982D01*
X1027480Y36465D01*
X1027557Y36000D01*
X1025947D01*
G01X1023652D02*
Y39100D01*
X1024112Y38480D01*
G01Y36000D02*
X1023192D01*
G01X1043558Y112184D02*
X1043808Y112309D01*
X1044100Y112392D01*
X1044433D01*
X1044808Y112267D01*
X1045100Y112059D01*
X1045308Y111809D01*
X1045475Y111392D01*
X1045517Y111017D01*
X1045433Y110642D01*
X1045308Y110392D01*
X1045058Y110142D01*
X1044767Y109975D01*
X1044475Y109892D01*
X1044183D01*
X1043892Y109975D01*
X1043642Y110100D01*
X1043433Y110267D01*
G01X1042292D02*
X1042042Y110059D01*
X1041750Y109934D01*
X1041375Y109892D01*
X1041000Y109975D01*
X1040708Y110142D01*
X1040500Y110434D01*
X1040458Y110767D01*
X1040542Y111100D01*
X1040750Y111309D01*
X1041042Y111475D01*
X1041333Y111517D01*
X1041625Y111475D01*
X1042000Y111309D01*
X1041875Y112392D01*
X1040750D01*
G01X1039192D02*
Y110600D01*
X1039025Y110225D01*
X1038692Y109975D01*
X1038275Y109892D01*
X1037858Y109975D01*
X1037525Y110225D01*
X1037358Y110600D01*
Y112392D01*
G01X1035175Y109892D02*
Y112392D01*
X1035675Y111892D01*
G01Y109892D02*
X1034675D01*
G01X1032867Y111975D02*
X1032617Y112225D01*
X1032325Y112350D01*
X1031992Y112392D01*
X1031575Y112309D01*
X1031283Y112100D01*
X1031200Y111850D01*
X1031242Y111600D01*
X1031408Y111392D01*
X1032242Y110975D01*
X1032617Y110684D01*
X1032867Y110267D01*
X1032950Y109892D01*
X1031200D01*
G01X1030694Y129784D02*
X1030944Y129909D01*
X1031236Y129992D01*
X1031569D01*
X1031944Y129867D01*
X1032236Y129659D01*
X1032444Y129409D01*
X1032611Y128992D01*
X1032653Y128617D01*
X1032569Y128242D01*
X1032444Y127992D01*
X1032194Y127742D01*
X1031903Y127575D01*
X1031611Y127492D01*
X1031319D01*
X1031028Y127575D01*
X1030778Y127700D01*
X1030569Y127867D01*
G01X1029428D02*
X1029178Y127659D01*
X1028886Y127534D01*
X1028511Y127492D01*
X1028136Y127575D01*
X1027844Y127742D01*
X1027636Y128034D01*
X1027594Y128367D01*
X1027678Y128700D01*
X1027886Y128909D01*
X1028178Y129075D01*
X1028469Y129117D01*
X1028761Y129075D01*
X1029136Y128909D01*
X1029011Y129992D01*
X1027886D01*
G01X1025161Y128742D02*
X1024328D01*
Y127992D01*
X1024578Y127742D01*
X1024869Y127575D01*
X1025286Y127492D01*
X1025703Y127575D01*
X1025994Y127742D01*
X1026244Y127992D01*
X1026411Y128284D01*
X1026494Y128617D01*
Y128909D01*
X1026411Y129159D01*
X1026244Y129450D01*
X1025994Y129700D01*
X1025744Y129867D01*
X1025411Y129992D01*
X1025119D01*
X1024786Y129909D01*
X1024536Y129742D01*
G01X1023228Y127867D02*
X1022978Y127659D01*
X1022686Y127534D01*
X1022311Y127492D01*
X1021936Y127575D01*
X1021644Y127742D01*
X1021436Y128034D01*
X1021394Y128367D01*
X1021478Y128700D01*
X1021686Y128909D01*
X1021978Y129075D01*
X1022269Y129117D01*
X1022561Y129075D01*
X1022936Y128909D01*
X1022811Y129992D01*
X1021686D01*
G01X1020003Y128534D02*
X1019711Y128825D01*
X1019461Y128992D01*
X1019128Y129075D01*
X1018836Y128992D01*
X1018628Y128825D01*
X1018461Y128575D01*
X1018419Y128284D01*
X1018461Y128034D01*
X1018628Y127784D01*
X1018878Y127575D01*
X1019169Y127492D01*
X1019503Y127575D01*
X1019794Y127825D01*
X1019961Y128200D01*
X1020003Y128617D01*
X1019919Y129159D01*
X1019794Y129450D01*
X1019586Y129742D01*
X1019294Y129950D01*
X1019003Y129992D01*
X1018711Y129909D01*
X1018503Y129700D01*
G01X1030694Y137784D02*
X1030944Y137909D01*
X1031236Y137992D01*
X1031569D01*
X1031944Y137867D01*
X1032236Y137659D01*
X1032444Y137409D01*
X1032611Y136992D01*
X1032653Y136617D01*
X1032569Y136242D01*
X1032444Y135992D01*
X1032194Y135742D01*
X1031903Y135575D01*
X1031611Y135492D01*
X1031319D01*
X1031028Y135575D01*
X1030778Y135700D01*
X1030569Y135867D01*
G01X1029428D02*
X1029178Y135659D01*
X1028886Y135534D01*
X1028511Y135492D01*
X1028136Y135575D01*
X1027844Y135742D01*
X1027636Y136034D01*
X1027594Y136367D01*
X1027678Y136700D01*
X1027886Y136909D01*
X1028178Y137075D01*
X1028469Y137117D01*
X1028761Y137075D01*
X1029136Y136909D01*
X1029011Y137992D01*
X1027886D01*
G01X1025161Y136742D02*
X1024328D01*
Y135992D01*
X1024578Y135742D01*
X1024869Y135575D01*
X1025286Y135492D01*
X1025703Y135575D01*
X1025994Y135742D01*
X1026244Y135992D01*
X1026411Y136284D01*
X1026494Y136617D01*
Y136909D01*
X1026411Y137159D01*
X1026244Y137450D01*
X1025994Y137700D01*
X1025744Y137867D01*
X1025411Y137992D01*
X1025119D01*
X1024786Y137909D01*
X1024536Y137742D01*
G01X1021811Y135492D02*
Y137992D01*
X1023353Y136200D01*
X1021269D01*
G01X1019919Y135784D02*
X1019628Y135575D01*
X1019294Y135492D01*
X1018961Y135575D01*
X1018669Y135825D01*
X1018461Y136200D01*
X1018378Y136575D01*
Y137034D01*
X1018461Y137409D01*
X1018669Y137742D01*
X1018919Y137909D01*
X1019211Y137992D01*
X1019544Y137909D01*
X1019794Y137742D01*
X1019961Y137492D01*
X1020044Y137159D01*
X1019961Y136867D01*
X1019753Y136575D01*
X1019503Y136409D01*
X1019211Y136367D01*
X1018878Y136450D01*
X1018628Y136659D01*
X1018378Y137034D01*
G01X1013514Y137548D02*
X1013764Y137673D01*
X1014056Y137756D01*
X1014389D01*
X1014764Y137631D01*
X1015056Y137423D01*
X1015264Y137173D01*
X1015431Y136756D01*
X1015473Y136381D01*
X1015389Y136006D01*
X1015264Y135756D01*
X1015014Y135506D01*
X1014723Y135339D01*
X1014431Y135256D01*
X1014139D01*
X1013848Y135339D01*
X1013598Y135464D01*
X1013389Y135631D01*
G01X1012248D02*
X1011998Y135423D01*
X1011706Y135298D01*
X1011331Y135256D01*
X1010956Y135339D01*
X1010664Y135506D01*
X1010456Y135798D01*
X1010414Y136131D01*
X1010498Y136464D01*
X1010706Y136673D01*
X1010998Y136839D01*
X1011289Y136881D01*
X1011581Y136839D01*
X1011956Y136673D01*
X1011831Y137756D01*
X1010706D01*
G01X1007981Y136506D02*
X1007148D01*
Y135756D01*
X1007398Y135506D01*
X1007689Y135339D01*
X1008106Y135256D01*
X1008523Y135339D01*
X1008814Y135506D01*
X1009064Y135756D01*
X1009231Y136048D01*
X1009314Y136381D01*
Y136673D01*
X1009231Y136923D01*
X1009064Y137214D01*
X1008814Y137464D01*
X1008564Y137631D01*
X1008231Y137756D01*
X1007939D01*
X1007606Y137673D01*
X1007356Y137506D01*
G01X1004631Y135256D02*
Y137756D01*
X1006173Y135964D01*
X1004089D01*
G01X1002031Y135256D02*
X1001739Y135298D01*
X1001406Y135423D01*
X1001198Y135631D01*
X1001114Y135923D01*
X1001198Y136214D01*
X1001448Y136464D01*
X1001823Y136589D01*
X1002239D01*
X1002489Y136673D01*
X1002698Y136881D01*
X1002781Y137173D01*
X1002656Y137464D01*
X1002364Y137673D01*
X1002031Y137756D01*
X1001698Y137673D01*
X1001406Y137464D01*
X1001281Y137173D01*
X1001364Y136881D01*
X1001573Y136673D01*
X1001823Y136589D01*
X1002239D01*
X1002614Y136464D01*
X1002864Y136214D01*
X1002948Y135923D01*
X1002864Y135631D01*
X1002656Y135423D01*
X1002323Y135298D01*
X1002031Y135256D01*
G01X1013514Y129548D02*
X1013764Y129673D01*
X1014056Y129756D01*
X1014389D01*
X1014764Y129631D01*
X1015056Y129423D01*
X1015264Y129173D01*
X1015431Y128756D01*
X1015473Y128381D01*
X1015389Y128006D01*
X1015264Y127756D01*
X1015014Y127506D01*
X1014723Y127339D01*
X1014431Y127256D01*
X1014139D01*
X1013848Y127339D01*
X1013598Y127464D01*
X1013389Y127631D01*
G01X1012248D02*
X1011998Y127423D01*
X1011706Y127298D01*
X1011331Y127256D01*
X1010956Y127339D01*
X1010664Y127506D01*
X1010456Y127798D01*
X1010414Y128131D01*
X1010498Y128464D01*
X1010706Y128673D01*
X1010998Y128839D01*
X1011289Y128881D01*
X1011581Y128839D01*
X1011956Y128673D01*
X1011831Y129756D01*
X1010706D01*
G01X1007981Y128506D02*
X1007148D01*
Y127756D01*
X1007398Y127506D01*
X1007689Y127339D01*
X1008106Y127256D01*
X1008523Y127339D01*
X1008814Y127506D01*
X1009064Y127756D01*
X1009231Y128048D01*
X1009314Y128381D01*
Y128673D01*
X1009231Y128923D01*
X1009064Y129214D01*
X1008814Y129464D01*
X1008564Y129631D01*
X1008231Y129756D01*
X1007939D01*
X1007606Y129673D01*
X1007356Y129506D01*
G01X1006048Y127631D02*
X1005798Y127423D01*
X1005506Y127298D01*
X1005131Y127256D01*
X1004756Y127339D01*
X1004464Y127506D01*
X1004256Y127798D01*
X1004214Y128131D01*
X1004298Y128464D01*
X1004506Y128673D01*
X1004798Y128839D01*
X1005089Y128881D01*
X1005381Y128839D01*
X1005756Y128673D01*
X1005631Y129756D01*
X1004506D01*
G01X1002031Y127256D02*
X1001739Y127298D01*
X1001406Y127423D01*
X1001198Y127631D01*
X1001114Y127923D01*
X1001198Y128214D01*
X1001448Y128464D01*
X1001823Y128589D01*
X1002239D01*
X1002489Y128673D01*
X1002698Y128881D01*
X1002781Y129173D01*
X1002656Y129464D01*
X1002364Y129673D01*
X1002031Y129756D01*
X1001698Y129673D01*
X1001406Y129464D01*
X1001281Y129173D01*
X1001364Y128881D01*
X1001573Y128673D01*
X1001823Y128589D01*
X1002239D01*
X1002614Y128464D01*
X1002864Y128214D01*
X1002948Y127923D01*
X1002864Y127631D01*
X1002656Y127423D01*
X1002323Y127298D01*
X1002031Y127256D01*
G01X997162Y137665D02*
X997412Y137790D01*
X997704Y137873D01*
X998037D01*
X998412Y137748D01*
X998704Y137540D01*
X998912Y137290D01*
X999079Y136873D01*
X999121Y136498D01*
X999037Y136123D01*
X998912Y135873D01*
X998662Y135623D01*
X998371Y135456D01*
X998079Y135373D01*
X997787D01*
X997496Y135456D01*
X997246Y135581D01*
X997037Y135748D01*
G01X995896D02*
X995646Y135540D01*
X995354Y135415D01*
X994979Y135373D01*
X994604Y135456D01*
X994312Y135623D01*
X994104Y135915D01*
X994062Y136248D01*
X994146Y136581D01*
X994354Y136790D01*
X994646Y136956D01*
X994937Y136998D01*
X995229Y136956D01*
X995604Y136790D01*
X995479Y137873D01*
X994354D01*
G01X991629Y136623D02*
X990796D01*
Y135873D01*
X991046Y135623D01*
X991337Y135456D01*
X991754Y135373D01*
X992171Y135456D01*
X992462Y135623D01*
X992712Y135873D01*
X992879Y136165D01*
X992962Y136498D01*
Y136790D01*
X992879Y137040D01*
X992712Y137331D01*
X992462Y137581D01*
X992212Y137748D01*
X991879Y137873D01*
X991587D01*
X991254Y137790D01*
X991004Y137623D01*
G01X988279Y135373D02*
Y137873D01*
X989821Y136081D01*
X987737D01*
G01X985762Y135373D02*
X985679Y135915D01*
X985554Y136373D01*
X985387Y136790D01*
X985179Y137248D01*
X984846Y137873D01*
X986512D01*
G01X997162Y129665D02*
X997412Y129790D01*
X997704Y129873D01*
X998037D01*
X998412Y129748D01*
X998704Y129540D01*
X998912Y129290D01*
X999079Y128873D01*
X999121Y128498D01*
X999037Y128123D01*
X998912Y127873D01*
X998662Y127623D01*
X998371Y127456D01*
X998079Y127373D01*
X997787D01*
X997496Y127456D01*
X997246Y127581D01*
X997037Y127748D01*
G01X995896D02*
X995646Y127540D01*
X995354Y127415D01*
X994979Y127373D01*
X994604Y127456D01*
X994312Y127623D01*
X994104Y127915D01*
X994062Y128248D01*
X994146Y128581D01*
X994354Y128790D01*
X994646Y128956D01*
X994937Y128998D01*
X995229Y128956D01*
X995604Y128790D01*
X995479Y129873D01*
X994354D01*
G01X991629Y128623D02*
X990796D01*
Y127873D01*
X991046Y127623D01*
X991337Y127456D01*
X991754Y127373D01*
X992171Y127456D01*
X992462Y127623D01*
X992712Y127873D01*
X992879Y128165D01*
X992962Y128498D01*
Y128790D01*
X992879Y129040D01*
X992712Y129331D01*
X992462Y129581D01*
X992212Y129748D01*
X991879Y129873D01*
X991587D01*
X991254Y129790D01*
X991004Y129623D01*
G01X989696Y127748D02*
X989446Y127540D01*
X989154Y127415D01*
X988779Y127373D01*
X988404Y127456D01*
X988112Y127623D01*
X987904Y127915D01*
X987862Y128248D01*
X987946Y128581D01*
X988154Y128790D01*
X988446Y128956D01*
X988737Y128998D01*
X989029Y128956D01*
X989404Y128790D01*
X989279Y129873D01*
X988154D01*
G01X985762Y127373D02*
X985679Y127915D01*
X985554Y128373D01*
X985387Y128790D01*
X985179Y129248D01*
X984846Y129873D01*
X986512D01*
G01X1017601Y102581D02*
X1017524Y103253D01*
X1017409Y103821D01*
X1017256Y104338D01*
X1017064Y104906D01*
X1016757Y105681D01*
X1018291D01*
G01X1014501Y102581D02*
X1014424Y103253D01*
X1014309Y103821D01*
X1014156Y104338D01*
X1013964Y104906D01*
X1013657Y105681D01*
X1015191D01*
G01X1025879Y109877D02*
X1026129Y110002D01*
X1026421Y110085D01*
X1026754D01*
X1027129Y109960D01*
X1027421Y109752D01*
X1027629Y109502D01*
X1027796Y109085D01*
X1027838Y108710D01*
X1027754Y108335D01*
X1027629Y108085D01*
X1027379Y107835D01*
X1027088Y107668D01*
X1026796Y107585D01*
X1026504D01*
X1026213Y107668D01*
X1025963Y107793D01*
X1025754Y107960D01*
G01X1024613D02*
X1024363Y107752D01*
X1024071Y107627D01*
X1023696Y107585D01*
X1023321Y107668D01*
X1023029Y107835D01*
X1022821Y108127D01*
X1022779Y108460D01*
X1022863Y108793D01*
X1023071Y109002D01*
X1023363Y109168D01*
X1023654Y109210D01*
X1023946Y109168D01*
X1024321Y109002D01*
X1024196Y110085D01*
X1023071D01*
G01X1020596D02*
Y107585D01*
G01X1021554Y110085D02*
X1019638D01*
G01X1018413Y108085D02*
X1018163Y107793D01*
X1017829Y107627D01*
X1017454Y107585D01*
X1017121Y107627D01*
X1016788Y107835D01*
X1016579Y108085D01*
X1016538Y108335D01*
X1016621Y108627D01*
X1016913Y108835D01*
X1017204Y108918D01*
X1017579D01*
G01X1017204D02*
X1016954Y109043D01*
X1016746Y109252D01*
X1016663Y109502D01*
X1016746Y109752D01*
X1016954Y109960D01*
X1017329Y110085D01*
X1017704Y110043D01*
X1018079Y109877D01*
G01X997162Y133665D02*
X997412Y133790D01*
X997704Y133873D01*
X998037D01*
X998412Y133748D01*
X998704Y133540D01*
X998912Y133290D01*
X999079Y132873D01*
X999121Y132498D01*
X999037Y132123D01*
X998912Y131873D01*
X998662Y131623D01*
X998371Y131456D01*
X998079Y131373D01*
X997787D01*
X997496Y131456D01*
X997246Y131581D01*
X997037Y131748D01*
G01X995896D02*
X995646Y131540D01*
X995354Y131415D01*
X994979Y131373D01*
X994604Y131456D01*
X994312Y131623D01*
X994104Y131915D01*
X994062Y132248D01*
X994146Y132581D01*
X994354Y132790D01*
X994646Y132956D01*
X994937Y132998D01*
X995229Y132956D01*
X995604Y132790D01*
X995479Y133873D01*
X994354D01*
G01X992796D02*
Y132081D01*
X992629Y131706D01*
X992296Y131456D01*
X991879Y131373D01*
X991462Y131456D01*
X991129Y131706D01*
X990962Y132081D01*
Y133873D01*
G01X988279Y131373D02*
Y133873D01*
X989821Y132081D01*
X987737D01*
G01X1013514Y133548D02*
X1013764Y133673D01*
X1014056Y133756D01*
X1014389D01*
X1014764Y133631D01*
X1015056Y133423D01*
X1015264Y133173D01*
X1015431Y132756D01*
X1015473Y132381D01*
X1015389Y132006D01*
X1015264Y131756D01*
X1015014Y131506D01*
X1014723Y131339D01*
X1014431Y131256D01*
X1014139D01*
X1013848Y131339D01*
X1013598Y131464D01*
X1013389Y131631D01*
G01X1012248D02*
X1011998Y131423D01*
X1011706Y131298D01*
X1011331Y131256D01*
X1010956Y131339D01*
X1010664Y131506D01*
X1010456Y131798D01*
X1010414Y132131D01*
X1010498Y132464D01*
X1010706Y132673D01*
X1010998Y132839D01*
X1011289Y132881D01*
X1011581Y132839D01*
X1011956Y132673D01*
X1011831Y133756D01*
X1010706D01*
G01X1009148D02*
Y131964D01*
X1008981Y131589D01*
X1008648Y131339D01*
X1008231Y131256D01*
X1007814Y131339D01*
X1007481Y131589D01*
X1007314Y131964D01*
Y133756D01*
G01X1006048Y131756D02*
X1005798Y131464D01*
X1005464Y131298D01*
X1005089Y131256D01*
X1004756Y131298D01*
X1004423Y131506D01*
X1004214Y131756D01*
X1004173Y132006D01*
X1004256Y132298D01*
X1004548Y132506D01*
X1004839Y132589D01*
X1005214D01*
G01X1004839D02*
X1004589Y132714D01*
X1004381Y132923D01*
X1004298Y133173D01*
X1004381Y133423D01*
X1004589Y133631D01*
X1004964Y133756D01*
X1005339Y133714D01*
X1005714Y133548D01*
G01X1030694Y133784D02*
X1030944Y133909D01*
X1031236Y133992D01*
X1031569D01*
X1031944Y133867D01*
X1032236Y133659D01*
X1032444Y133409D01*
X1032611Y132992D01*
X1032653Y132617D01*
X1032569Y132242D01*
X1032444Y131992D01*
X1032194Y131742D01*
X1031903Y131575D01*
X1031611Y131492D01*
X1031319D01*
X1031028Y131575D01*
X1030778Y131700D01*
X1030569Y131867D01*
G01X1029428D02*
X1029178Y131659D01*
X1028886Y131534D01*
X1028511Y131492D01*
X1028136Y131575D01*
X1027844Y131742D01*
X1027636Y132034D01*
X1027594Y132367D01*
X1027678Y132700D01*
X1027886Y132909D01*
X1028178Y133075D01*
X1028469Y133117D01*
X1028761Y133075D01*
X1029136Y132909D01*
X1029011Y133992D01*
X1027886D01*
G01X1026328D02*
Y132200D01*
X1026161Y131825D01*
X1025828Y131575D01*
X1025411Y131492D01*
X1024994Y131575D01*
X1024661Y131825D01*
X1024494Y132200D01*
Y133992D01*
G01X1023103Y133575D02*
X1022853Y133825D01*
X1022561Y133950D01*
X1022228Y133992D01*
X1021811Y133909D01*
X1021519Y133700D01*
X1021436Y133450D01*
X1021478Y133200D01*
X1021644Y132992D01*
X1022478Y132575D01*
X1022853Y132284D01*
X1023103Y131867D01*
X1023186Y131492D01*
X1021436D01*
G01X997162Y141665D02*
X997412Y141790D01*
X997704Y141873D01*
X998037D01*
X998412Y141748D01*
X998704Y141540D01*
X998912Y141290D01*
X999079Y140873D01*
X999121Y140498D01*
X999037Y140123D01*
X998912Y139873D01*
X998662Y139623D01*
X998371Y139456D01*
X998079Y139373D01*
X997787D01*
X997496Y139456D01*
X997246Y139581D01*
X997037Y139748D01*
G01X995896D02*
X995646Y139540D01*
X995354Y139415D01*
X994979Y139373D01*
X994604Y139456D01*
X994312Y139623D01*
X994104Y139915D01*
X994062Y140248D01*
X994146Y140581D01*
X994354Y140790D01*
X994646Y140956D01*
X994937Y140998D01*
X995229Y140956D01*
X995604Y140790D01*
X995479Y141873D01*
X994354D01*
G01X991879D02*
Y139373D01*
G01X992837Y141873D02*
X990921D01*
G01X988862Y139373D02*
X988779Y139915D01*
X988654Y140373D01*
X988487Y140790D01*
X988279Y141248D01*
X987946Y141873D01*
X989612D01*
G01X1013514Y141548D02*
X1013764Y141673D01*
X1014056Y141756D01*
X1014389D01*
X1014764Y141631D01*
X1015056Y141423D01*
X1015264Y141173D01*
X1015431Y140756D01*
X1015473Y140381D01*
X1015389Y140006D01*
X1015264Y139756D01*
X1015014Y139506D01*
X1014723Y139339D01*
X1014431Y139256D01*
X1014139D01*
X1013848Y139339D01*
X1013598Y139464D01*
X1013389Y139631D01*
G01X1012248D02*
X1011998Y139423D01*
X1011706Y139298D01*
X1011331Y139256D01*
X1010956Y139339D01*
X1010664Y139506D01*
X1010456Y139798D01*
X1010414Y140131D01*
X1010498Y140464D01*
X1010706Y140673D01*
X1010998Y140839D01*
X1011289Y140881D01*
X1011581Y140839D01*
X1011956Y140673D01*
X1011831Y141756D01*
X1010706D01*
G01X1008231D02*
Y139256D01*
G01X1009189Y141756D02*
X1007273D01*
G01X1005923Y140298D02*
X1005631Y140589D01*
X1005381Y140756D01*
X1005048Y140839D01*
X1004756Y140756D01*
X1004548Y140589D01*
X1004381Y140339D01*
X1004339Y140048D01*
X1004381Y139798D01*
X1004548Y139548D01*
X1004798Y139339D01*
X1005089Y139256D01*
X1005423Y139339D01*
X1005714Y139589D01*
X1005881Y139964D01*
X1005923Y140381D01*
X1005839Y140923D01*
X1005714Y141214D01*
X1005506Y141506D01*
X1005214Y141714D01*
X1004923Y141756D01*
X1004631Y141673D01*
X1004423Y141464D01*
G01X1030694Y141784D02*
X1030944Y141909D01*
X1031236Y141992D01*
X1031569D01*
X1031944Y141867D01*
X1032236Y141659D01*
X1032444Y141409D01*
X1032611Y140992D01*
X1032653Y140617D01*
X1032569Y140242D01*
X1032444Y139992D01*
X1032194Y139742D01*
X1031903Y139575D01*
X1031611Y139492D01*
X1031319D01*
X1031028Y139575D01*
X1030778Y139700D01*
X1030569Y139867D01*
G01X1029428D02*
X1029178Y139659D01*
X1028886Y139534D01*
X1028511Y139492D01*
X1028136Y139575D01*
X1027844Y139742D01*
X1027636Y140034D01*
X1027594Y140367D01*
X1027678Y140700D01*
X1027886Y140909D01*
X1028178Y141075D01*
X1028469Y141117D01*
X1028761Y141075D01*
X1029136Y140909D01*
X1029011Y141992D01*
X1027886D01*
G01X1025411D02*
Y139492D01*
G01X1026369Y141992D02*
X1024453D01*
G01X1023228Y139867D02*
X1022978Y139659D01*
X1022686Y139534D01*
X1022311Y139492D01*
X1021936Y139575D01*
X1021644Y139742D01*
X1021436Y140034D01*
X1021394Y140367D01*
X1021478Y140700D01*
X1021686Y140909D01*
X1021978Y141075D01*
X1022269Y141117D01*
X1022561Y141075D01*
X1022936Y140909D01*
X1022811Y141992D01*
X1021686D01*
G01X1117300Y298400D02*
Y329000D01*
X1094000D01*
Y341200D01*
X1033700D01*
Y336400D01*
X1028100D01*
Y333100D01*
X1021900D01*
Y328800D01*
X1011900D01*
Y274900D01*
X1027600D01*
Y260300D01*
X1088600D01*
Y261200D01*
X1093000D01*
Y259700D01*
X1097200D01*
Y261300D01*
X1099700D01*
Y261200D01*
X1099800D01*
Y269400D01*
X1105100D01*
Y274300D01*
X1111000D01*
G01X1012430Y425082D02*
X1017764D01*
Y432082D01*
X1012430D01*
G01X1014564Y428699D02*
X1017764D01*
G01X987224Y450325D02*
X1138123D01*
Y407025D01*
X987223D01*
Y450324D01*
X987224Y450325D01*
G01X1012500Y484000D02*
X1150640D01*
Y456000D01*
X979500D01*
Y484000D01*
X1012500D01*
G01X1046186Y424455D02*
Y426955D01*
X1045145D01*
X1044811Y426830D01*
X1044603Y426663D01*
X1044520Y426330D01*
X1044603Y425997D01*
X1044853Y425788D01*
X1045145Y425663D01*
X1046186D01*
G01X1045145D02*
X1044520Y424455D01*
G01X1042253D02*
Y426955D01*
X1042753Y426455D01*
G01Y424455D02*
X1041753D01*
G01X1039986D02*
Y426955D01*
X1038945D01*
X1038611Y426830D01*
X1038403Y426663D01*
X1038320Y426330D01*
X1038403Y425997D01*
X1038653Y425788D01*
X1038945Y425663D01*
X1039986D01*
G01X1038945D02*
X1038320Y424455D01*
G01X1036053D02*
Y426955D01*
X1036553Y426455D01*
G01Y424455D02*
X1035553D01*
G01X1033745Y426538D02*
X1033495Y426788D01*
X1033203Y426913D01*
X1032870Y426955D01*
X1032453Y426872D01*
X1032161Y426663D01*
X1032078Y426413D01*
X1032120Y426163D01*
X1032286Y425955D01*
X1033120Y425538D01*
X1033495Y425247D01*
X1033745Y424830D01*
X1033828Y424455D01*
X1032078D01*
G01X1021556Y445515D02*
Y448015D01*
X1020515D01*
X1020181Y447890D01*
X1019973Y447723D01*
X1019890Y447390D01*
X1019973Y447057D01*
X1020223Y446848D01*
X1020515Y446723D01*
X1021556D01*
G01X1020515D02*
X1019890Y445515D01*
G01X1018331Y445807D02*
X1018040Y445598D01*
X1017706Y445515D01*
X1017373Y445598D01*
X1017081Y445848D01*
X1016873Y446223D01*
X1016790Y446598D01*
Y447057D01*
X1016873Y447432D01*
X1017081Y447765D01*
X1017331Y447932D01*
X1017623Y448015D01*
X1017956Y447932D01*
X1018206Y447765D01*
X1018373Y447515D01*
X1018456Y447182D01*
X1018373Y446890D01*
X1018165Y446598D01*
X1017915Y446432D01*
X1017623Y446390D01*
X1017290Y446473D01*
X1017040Y446682D01*
X1016790Y447057D01*
G01X1013690Y445515D02*
X1015356D01*
Y448015D01*
X1013690D01*
G01X1014356Y446807D02*
X1015356D01*
G01X1011423Y445515D02*
Y448015D01*
X1011923Y447515D01*
G01Y445515D02*
X1010923D01*
G01X1005236Y445975D02*
Y448475D01*
X1004195D01*
X1003861Y448350D01*
X1003653Y448183D01*
X1003570Y447850D01*
X1003653Y447517D01*
X1003903Y447308D01*
X1004195Y447183D01*
X1005236D01*
G01X1004195D02*
X1003570Y445975D01*
G01X1001303D02*
Y448475D01*
X1001803Y447975D01*
G01Y445975D02*
X1000803D01*
G01X999036D02*
Y448475D01*
X997995D01*
X997661Y448350D01*
X997453Y448183D01*
X997370Y447850D01*
X997453Y447517D01*
X997703Y447308D01*
X997995Y447183D01*
X999036D01*
G01X997995D02*
X997370Y445975D01*
G01X995103D02*
Y448475D01*
X995603Y447975D01*
G01Y445975D02*
X994603D01*
G01X992920Y446350D02*
X992670Y446142D01*
X992378Y446017D01*
X992003Y445975D01*
X991628Y446058D01*
X991336Y446225D01*
X991128Y446517D01*
X991086Y446850D01*
X991170Y447183D01*
X991378Y447392D01*
X991670Y447558D01*
X991961Y447600D01*
X992253Y447558D01*
X992628Y447392D01*
X992503Y448475D01*
X991378D01*
G01X1044436Y440747D02*
X1044686Y440872D01*
X1044978Y440955D01*
X1045311D01*
X1045686Y440830D01*
X1045978Y440622D01*
X1046186Y440372D01*
X1046353Y439955D01*
X1046395Y439580D01*
X1046311Y439205D01*
X1046186Y438955D01*
X1045936Y438705D01*
X1045645Y438538D01*
X1045353Y438455D01*
X1045061D01*
X1044770Y438538D01*
X1044520Y438663D01*
X1044311Y438830D01*
G01X1042253Y438455D02*
Y440955D01*
X1042753Y440455D01*
G01Y438455D02*
X1041753D01*
G01X1039986D02*
Y440955D01*
X1038945D01*
X1038611Y440830D01*
X1038403Y440663D01*
X1038320Y440330D01*
X1038403Y439997D01*
X1038653Y439788D01*
X1038945Y439663D01*
X1039986D01*
G01X1038945D02*
X1038320Y438455D01*
G01X1036053D02*
Y440955D01*
X1036553Y440455D01*
G01Y438455D02*
X1035553D01*
G01X1033745Y439497D02*
X1033453Y439788D01*
X1033203Y439955D01*
X1032870Y440038D01*
X1032578Y439955D01*
X1032370Y439788D01*
X1032203Y439538D01*
X1032161Y439247D01*
X1032203Y438997D01*
X1032370Y438747D01*
X1032620Y438538D01*
X1032911Y438455D01*
X1033245Y438538D01*
X1033536Y438788D01*
X1033703Y439163D01*
X1033745Y439580D01*
X1033661Y440122D01*
X1033536Y440413D01*
X1033328Y440705D01*
X1033036Y440913D01*
X1032745Y440955D01*
X1032453Y440872D01*
X1032245Y440663D01*
G01X1044436Y447747D02*
X1044686Y447872D01*
X1044978Y447955D01*
X1045311D01*
X1045686Y447830D01*
X1045978Y447622D01*
X1046186Y447372D01*
X1046353Y446955D01*
X1046395Y446580D01*
X1046311Y446205D01*
X1046186Y445955D01*
X1045936Y445705D01*
X1045645Y445538D01*
X1045353Y445455D01*
X1045061D01*
X1044770Y445538D01*
X1044520Y445663D01*
X1044311Y445830D01*
G01X1042961Y445747D02*
X1042670Y445538D01*
X1042336Y445455D01*
X1042003Y445538D01*
X1041711Y445788D01*
X1041503Y446163D01*
X1041420Y446538D01*
Y446997D01*
X1041503Y447372D01*
X1041711Y447705D01*
X1041961Y447872D01*
X1042253Y447955D01*
X1042586Y447872D01*
X1042836Y447705D01*
X1043003Y447455D01*
X1043086Y447122D01*
X1043003Y446830D01*
X1042795Y446538D01*
X1042545Y446372D01*
X1042253Y446330D01*
X1041920Y446413D01*
X1041670Y446622D01*
X1041420Y446997D01*
G01X1038320Y445455D02*
X1039986D01*
Y447955D01*
X1038320D01*
G01X1038986Y446747D02*
X1039986D01*
G01X1036053Y445455D02*
Y447955D01*
X1036553Y447455D01*
G01Y445455D02*
X1035553D01*
G01X1033745Y447538D02*
X1033495Y447788D01*
X1033203Y447913D01*
X1032870Y447955D01*
X1032453Y447872D01*
X1032161Y447663D01*
X1032078Y447413D01*
X1032120Y447163D01*
X1032286Y446955D01*
X1033120Y446538D01*
X1033495Y446247D01*
X1033745Y445830D01*
X1033828Y445455D01*
X1032078D01*
G01X1044436Y430247D02*
X1044686Y430372D01*
X1044978Y430455D01*
X1045311D01*
X1045686Y430330D01*
X1045978Y430122D01*
X1046186Y429872D01*
X1046353Y429455D01*
X1046395Y429080D01*
X1046311Y428705D01*
X1046186Y428455D01*
X1045936Y428205D01*
X1045645Y428038D01*
X1045353Y427955D01*
X1045061D01*
X1044770Y428038D01*
X1044520Y428163D01*
X1044311Y428330D01*
G01X1042253Y427955D02*
Y430455D01*
X1042753Y429955D01*
G01Y427955D02*
X1041753D01*
G01X1039986D02*
Y430455D01*
X1038945D01*
X1038611Y430330D01*
X1038403Y430163D01*
X1038320Y429830D01*
X1038403Y429497D01*
X1038653Y429288D01*
X1038945Y429163D01*
X1039986D01*
G01X1038945D02*
X1038320Y427955D01*
G01X1036845Y430038D02*
X1036595Y430288D01*
X1036303Y430413D01*
X1035970Y430455D01*
X1035553Y430372D01*
X1035261Y430163D01*
X1035178Y429913D01*
X1035220Y429663D01*
X1035386Y429455D01*
X1036220Y429038D01*
X1036595Y428747D01*
X1036845Y428330D01*
X1036928Y427955D01*
X1035178D01*
G01X1033745Y430038D02*
X1033495Y430288D01*
X1033203Y430413D01*
X1032870Y430455D01*
X1032453Y430372D01*
X1032161Y430163D01*
X1032078Y429913D01*
X1032120Y429663D01*
X1032286Y429455D01*
X1033120Y429038D01*
X1033495Y428747D01*
X1033745Y428330D01*
X1033828Y427955D01*
X1032078D01*
G01X1029975Y435642D02*
X1030100Y435392D01*
X1030183Y435100D01*
Y434767D01*
X1030058Y434392D01*
X1029850Y434100D01*
X1029600Y433892D01*
X1029183Y433725D01*
X1028808Y433683D01*
X1028433Y433767D01*
X1028183Y433892D01*
X1027933Y434142D01*
X1027766Y434433D01*
X1027683Y434725D01*
Y435017D01*
X1027766Y435308D01*
X1027891Y435558D01*
X1028058Y435767D01*
G01X1027683Y437825D02*
X1030183D01*
X1029683Y437325D01*
G01X1027683D02*
Y438325D01*
G01Y440092D02*
X1030183D01*
Y441133D01*
X1030058Y441467D01*
X1029891Y441675D01*
X1029558Y441758D01*
X1029225Y441675D01*
X1029016Y441425D01*
X1028891Y441133D01*
Y440092D01*
G01Y441133D02*
X1027683Y441758D01*
G01Y444025D02*
X1030183D01*
X1029683Y443525D01*
G01X1027683D02*
Y444525D01*
G01X1028183Y446208D02*
X1027891Y446458D01*
X1027725Y446792D01*
X1027683Y447167D01*
X1027725Y447500D01*
X1027933Y447833D01*
X1028183Y448042D01*
X1028433Y448083D01*
X1028725Y448000D01*
X1028933Y447708D01*
X1029016Y447417D01*
Y447042D01*
G01Y447417D02*
X1029141Y447667D01*
X1029350Y447875D01*
X1029600Y447958D01*
X1029850Y447875D01*
X1030058Y447667D01*
X1030183Y447292D01*
X1030141Y446917D01*
X1029975Y446542D01*
G01X1003486Y430467D02*
X1003736Y430592D01*
X1004028Y430675D01*
X1004361D01*
X1004736Y430550D01*
X1005028Y430342D01*
X1005236Y430092D01*
X1005403Y429675D01*
X1005445Y429300D01*
X1005361Y428925D01*
X1005236Y428675D01*
X1004986Y428425D01*
X1004695Y428258D01*
X1004403Y428175D01*
X1004111D01*
X1003820Y428258D01*
X1003570Y428383D01*
X1003361Y428550D01*
G01X1001303Y428175D02*
Y430675D01*
X1001803Y430175D01*
G01Y428175D02*
X1000803D01*
G01X999036D02*
Y430675D01*
X997995D01*
X997661Y430550D01*
X997453Y430383D01*
X997370Y430050D01*
X997453Y429717D01*
X997703Y429508D01*
X997995Y429383D01*
X999036D01*
G01X997995D02*
X997370Y428175D01*
G01X996020Y428675D02*
X995770Y428383D01*
X995436Y428217D01*
X995061Y428175D01*
X994728Y428217D01*
X994395Y428425D01*
X994186Y428675D01*
X994145Y428925D01*
X994228Y429217D01*
X994520Y429425D01*
X994811Y429508D01*
X995186D01*
G01X994811D02*
X994561Y429633D01*
X994353Y429842D01*
X994270Y430092D01*
X994353Y430342D01*
X994561Y430550D01*
X994936Y430675D01*
X995311Y430633D01*
X995686Y430467D01*
G01X992003Y430675D02*
X992336Y430592D01*
X992586Y430383D01*
X992753Y430133D01*
X992878Y429800D01*
X992920Y429425D01*
X992878Y429050D01*
X992753Y428717D01*
X992586Y428467D01*
X992336Y428258D01*
X992003Y428175D01*
X991670Y428258D01*
X991420Y428467D01*
X991253Y428717D01*
X991128Y429050D01*
X991086Y429425D01*
X991128Y429800D01*
X991253Y430133D01*
X991420Y430383D01*
X991670Y430592D01*
X992003Y430675D01*
G01X1003486Y444467D02*
X1003736Y444592D01*
X1004028Y444675D01*
X1004361D01*
X1004736Y444550D01*
X1005028Y444342D01*
X1005236Y444092D01*
X1005403Y443675D01*
X1005445Y443300D01*
X1005361Y442925D01*
X1005236Y442675D01*
X1004986Y442425D01*
X1004695Y442258D01*
X1004403Y442175D01*
X1004111D01*
X1003820Y442258D01*
X1003570Y442383D01*
X1003361Y442550D01*
G01X1001303Y442175D02*
Y444675D01*
X1001803Y444175D01*
G01Y442175D02*
X1000803D01*
G01X999036D02*
Y444675D01*
X997995D01*
X997661Y444550D01*
X997453Y444383D01*
X997370Y444050D01*
X997453Y443717D01*
X997703Y443508D01*
X997995Y443383D01*
X999036D01*
G01X997995D02*
X997370Y442175D01*
G01X995103D02*
Y444675D01*
X995603Y444175D01*
G01Y442175D02*
X994603D01*
G01X992086D02*
X992003Y442717D01*
X991878Y443175D01*
X991711Y443592D01*
X991503Y444050D01*
X991170Y444675D01*
X992836D01*
G01X1044436Y433747D02*
X1044686Y433872D01*
X1044978Y433955D01*
X1045311D01*
X1045686Y433830D01*
X1045978Y433622D01*
X1046186Y433372D01*
X1046353Y432955D01*
X1046395Y432580D01*
X1046311Y432205D01*
X1046186Y431955D01*
X1045936Y431705D01*
X1045645Y431538D01*
X1045353Y431455D01*
X1045061D01*
X1044770Y431538D01*
X1044520Y431663D01*
X1044311Y431830D01*
G01X1042253Y431455D02*
Y433955D01*
X1042753Y433455D01*
G01Y431455D02*
X1041753D01*
G01X1039986D02*
Y433955D01*
X1038945D01*
X1038611Y433830D01*
X1038403Y433663D01*
X1038320Y433330D01*
X1038403Y432997D01*
X1038653Y432788D01*
X1038945Y432663D01*
X1039986D01*
G01X1038945D02*
X1038320Y431455D01*
G01X1036845Y433538D02*
X1036595Y433788D01*
X1036303Y433913D01*
X1035970Y433955D01*
X1035553Y433872D01*
X1035261Y433663D01*
X1035178Y433413D01*
X1035220Y433163D01*
X1035386Y432955D01*
X1036220Y432538D01*
X1036595Y432247D01*
X1036845Y431830D01*
X1036928Y431455D01*
X1035178D01*
G01X1032953Y433955D02*
X1033286Y433872D01*
X1033536Y433663D01*
X1033703Y433413D01*
X1033828Y433080D01*
X1033870Y432705D01*
X1033828Y432330D01*
X1033703Y431997D01*
X1033536Y431747D01*
X1033286Y431538D01*
X1032953Y431455D01*
X1032620Y431538D01*
X1032370Y431747D01*
X1032203Y431997D01*
X1032078Y432330D01*
X1032036Y432705D01*
X1032078Y433080D01*
X1032203Y433413D01*
X1032370Y433663D01*
X1032620Y433872D01*
X1032953Y433955D01*
G01X1044436Y437247D02*
X1044686Y437372D01*
X1044978Y437455D01*
X1045311D01*
X1045686Y437330D01*
X1045978Y437122D01*
X1046186Y436872D01*
X1046353Y436455D01*
X1046395Y436080D01*
X1046311Y435705D01*
X1046186Y435455D01*
X1045936Y435205D01*
X1045645Y435038D01*
X1045353Y434955D01*
X1045061D01*
X1044770Y435038D01*
X1044520Y435163D01*
X1044311Y435330D01*
G01X1042253Y434955D02*
Y437455D01*
X1042753Y436955D01*
G01Y434955D02*
X1041753D01*
G01X1039986D02*
Y437455D01*
X1038945D01*
X1038611Y437330D01*
X1038403Y437163D01*
X1038320Y436830D01*
X1038403Y436497D01*
X1038653Y436288D01*
X1038945Y436163D01*
X1039986D01*
G01X1038945D02*
X1038320Y434955D01*
G01X1036053D02*
Y437455D01*
X1036553Y436955D01*
G01Y434955D02*
X1035553D01*
G01X1032953D02*
X1032661Y434997D01*
X1032328Y435122D01*
X1032120Y435330D01*
X1032036Y435622D01*
X1032120Y435913D01*
X1032370Y436163D01*
X1032745Y436288D01*
X1033161D01*
X1033411Y436372D01*
X1033620Y436580D01*
X1033703Y436872D01*
X1033578Y437163D01*
X1033286Y437372D01*
X1032953Y437455D01*
X1032620Y437372D01*
X1032328Y437163D01*
X1032203Y436872D01*
X1032286Y436580D01*
X1032495Y436372D01*
X1032745Y436288D01*
X1033161D01*
X1033536Y436163D01*
X1033786Y435913D01*
X1033870Y435622D01*
X1033786Y435330D01*
X1033578Y435122D01*
X1033245Y434997D01*
X1032953Y434955D01*
G01X1026475Y435642D02*
X1026600Y435392D01*
X1026683Y435100D01*
Y434767D01*
X1026558Y434392D01*
X1026350Y434100D01*
X1026100Y433892D01*
X1025683Y433725D01*
X1025308Y433683D01*
X1024933Y433767D01*
X1024683Y433892D01*
X1024433Y434142D01*
X1024266Y434433D01*
X1024183Y434725D01*
Y435017D01*
X1024266Y435308D01*
X1024391Y435558D01*
X1024558Y435767D01*
G01X1024183Y437825D02*
X1026683D01*
X1026183Y437325D01*
G01X1024183D02*
Y438325D01*
G01Y440092D02*
X1026683D01*
Y441133D01*
X1026558Y441467D01*
X1026391Y441675D01*
X1026058Y441758D01*
X1025725Y441675D01*
X1025516Y441425D01*
X1025391Y441133D01*
Y440092D01*
G01Y441133D02*
X1024183Y441758D01*
G01Y444025D02*
X1026683D01*
X1026183Y443525D01*
G01X1024183D02*
Y444525D01*
G01Y447625D02*
X1026683D01*
X1024891Y446083D01*
Y448167D01*
G01X1003486Y437467D02*
X1003736Y437592D01*
X1004028Y437675D01*
X1004361D01*
X1004736Y437550D01*
X1005028Y437342D01*
X1005236Y437092D01*
X1005403Y436675D01*
X1005445Y436300D01*
X1005361Y435925D01*
X1005236Y435675D01*
X1004986Y435425D01*
X1004695Y435258D01*
X1004403Y435175D01*
X1004111D01*
X1003820Y435258D01*
X1003570Y435383D01*
X1003361Y435550D01*
G01X1001303Y435175D02*
Y437675D01*
X1001803Y437175D01*
G01Y435175D02*
X1000803D01*
G01X999036D02*
Y437675D01*
X997995D01*
X997661Y437550D01*
X997453Y437383D01*
X997370Y437050D01*
X997453Y436717D01*
X997703Y436508D01*
X997995Y436383D01*
X999036D01*
G01X997995D02*
X997370Y435175D01*
G01X995895Y437258D02*
X995645Y437508D01*
X995353Y437633D01*
X995020Y437675D01*
X994603Y437592D01*
X994311Y437383D01*
X994228Y437133D01*
X994270Y436883D01*
X994436Y436675D01*
X995270Y436258D01*
X995645Y435967D01*
X995895Y435550D01*
X995978Y435175D01*
X994228D01*
G01X992003D02*
Y437675D01*
X992503Y437175D01*
G01Y435175D02*
X991503D01*
G01X1003486Y433967D02*
X1003736Y434092D01*
X1004028Y434175D01*
X1004361D01*
X1004736Y434050D01*
X1005028Y433842D01*
X1005236Y433592D01*
X1005403Y433175D01*
X1005445Y432800D01*
X1005361Y432425D01*
X1005236Y432175D01*
X1004986Y431925D01*
X1004695Y431758D01*
X1004403Y431675D01*
X1004111D01*
X1003820Y431758D01*
X1003570Y431883D01*
X1003361Y432050D01*
G01X1001303Y431675D02*
Y434175D01*
X1001803Y433675D01*
G01Y431675D02*
X1000803D01*
G01X999036D02*
Y434175D01*
X997995D01*
X997661Y434050D01*
X997453Y433883D01*
X997370Y433550D01*
X997453Y433217D01*
X997703Y433008D01*
X997995Y432883D01*
X999036D01*
G01X997995D02*
X997370Y431675D01*
G01X995895Y433758D02*
X995645Y434008D01*
X995353Y434133D01*
X995020Y434175D01*
X994603Y434092D01*
X994311Y433883D01*
X994228Y433633D01*
X994270Y433383D01*
X994436Y433175D01*
X995270Y432758D01*
X995645Y432467D01*
X995895Y432050D01*
X995978Y431675D01*
X994228D01*
G01X991503D02*
Y434175D01*
X993045Y432383D01*
X990961D01*
G01X1003486Y440967D02*
X1003736Y441092D01*
X1004028Y441175D01*
X1004361D01*
X1004736Y441050D01*
X1005028Y440842D01*
X1005236Y440592D01*
X1005403Y440175D01*
X1005445Y439800D01*
X1005361Y439425D01*
X1005236Y439175D01*
X1004986Y438925D01*
X1004695Y438758D01*
X1004403Y438675D01*
X1004111D01*
X1003820Y438758D01*
X1003570Y438883D01*
X1003361Y439050D01*
G01X1001303Y438675D02*
Y441175D01*
X1001803Y440675D01*
G01Y438675D02*
X1000803D01*
G01X999036D02*
Y441175D01*
X997995D01*
X997661Y441050D01*
X997453Y440883D01*
X997370Y440550D01*
X997453Y440217D01*
X997703Y440008D01*
X997995Y439883D01*
X999036D01*
G01X997995D02*
X997370Y438675D01*
G01X995895Y440758D02*
X995645Y441008D01*
X995353Y441133D01*
X995020Y441175D01*
X994603Y441092D01*
X994311Y440883D01*
X994228Y440633D01*
X994270Y440383D01*
X994436Y440175D01*
X995270Y439758D01*
X995645Y439467D01*
X995895Y439050D01*
X995978Y438675D01*
X994228D01*
G01X992711Y438967D02*
X992420Y438758D01*
X992086Y438675D01*
X991753Y438758D01*
X991461Y439008D01*
X991253Y439383D01*
X991170Y439758D01*
Y440217D01*
X991253Y440592D01*
X991461Y440925D01*
X991711Y441092D01*
X992003Y441175D01*
X992336Y441092D01*
X992586Y440925D01*
X992753Y440675D01*
X992836Y440342D01*
X992753Y440050D01*
X992545Y439758D01*
X992295Y439592D01*
X992003Y439550D01*
X991670Y439633D01*
X991420Y439842D01*
X991170Y440217D01*
G01X1019806Y444307D02*
X1020056Y444432D01*
X1020348Y444515D01*
X1020681D01*
X1021056Y444390D01*
X1021348Y444182D01*
X1021556Y443932D01*
X1021723Y443515D01*
X1021765Y443140D01*
X1021681Y442765D01*
X1021556Y442515D01*
X1021306Y442265D01*
X1021015Y442098D01*
X1020723Y442015D01*
X1020431D01*
X1020140Y442098D01*
X1019890Y442223D01*
X1019681Y442390D01*
G01X1017623Y442015D02*
Y444515D01*
X1018123Y444015D01*
G01Y442015D02*
X1017123D01*
G01X1015356D02*
Y444515D01*
X1014315D01*
X1013981Y444390D01*
X1013773Y444223D01*
X1013690Y443890D01*
X1013773Y443557D01*
X1014023Y443348D01*
X1014315Y443223D01*
X1015356D01*
G01X1014315D02*
X1013690Y442015D01*
G01X1011423D02*
Y444515D01*
X1011923Y444015D01*
G01Y442015D02*
X1010923D01*
G01X1009240Y442390D02*
X1008990Y442182D01*
X1008698Y442057D01*
X1008323Y442015D01*
X1007948Y442098D01*
X1007656Y442265D01*
X1007448Y442557D01*
X1007406Y442890D01*
X1007490Y443223D01*
X1007698Y443432D01*
X1007990Y443598D01*
X1008281Y443640D01*
X1008573Y443598D01*
X1008948Y443432D01*
X1008823Y444515D01*
X1007698D01*
G01X1003486Y423467D02*
X1003736Y423592D01*
X1004028Y423675D01*
X1004361D01*
X1004736Y423550D01*
X1005028Y423342D01*
X1005236Y423092D01*
X1005403Y422675D01*
X1005445Y422300D01*
X1005361Y421925D01*
X1005236Y421675D01*
X1004986Y421425D01*
X1004695Y421258D01*
X1004403Y421175D01*
X1004111D01*
X1003820Y421258D01*
X1003570Y421383D01*
X1003361Y421550D01*
G01X1001303Y421175D02*
Y423675D01*
X1001803Y423175D01*
G01Y421175D02*
X1000803D01*
G01X999036D02*
Y423675D01*
X997995D01*
X997661Y423550D01*
X997453Y423383D01*
X997370Y423050D01*
X997453Y422717D01*
X997703Y422508D01*
X997995Y422383D01*
X999036D01*
G01X997995D02*
X997370Y421175D01*
G01X995103D02*
Y423675D01*
X995603Y423175D01*
G01Y421175D02*
X994603D01*
G01X992711Y421467D02*
X992420Y421258D01*
X992086Y421175D01*
X991753Y421258D01*
X991461Y421508D01*
X991253Y421883D01*
X991170Y422258D01*
Y422717D01*
X991253Y423092D01*
X991461Y423425D01*
X991711Y423592D01*
X992003Y423675D01*
X992336Y423592D01*
X992586Y423425D01*
X992753Y423175D01*
X992836Y422842D01*
X992753Y422550D01*
X992545Y422258D01*
X992295Y422092D01*
X992003Y422050D01*
X991670Y422133D01*
X991420Y422342D01*
X991170Y422717D01*
G01X1003486Y426967D02*
X1003736Y427092D01*
X1004028Y427175D01*
X1004361D01*
X1004736Y427050D01*
X1005028Y426842D01*
X1005236Y426592D01*
X1005403Y426175D01*
X1005445Y425800D01*
X1005361Y425425D01*
X1005236Y425175D01*
X1004986Y424925D01*
X1004695Y424758D01*
X1004403Y424675D01*
X1004111D01*
X1003820Y424758D01*
X1003570Y424883D01*
X1003361Y425050D01*
G01X1001303Y424675D02*
Y427175D01*
X1001803Y426675D01*
G01Y424675D02*
X1000803D01*
G01X999036D02*
Y427175D01*
X997995D01*
X997661Y427050D01*
X997453Y426883D01*
X997370Y426550D01*
X997453Y426217D01*
X997703Y426008D01*
X997995Y425883D01*
X999036D01*
G01X997995D02*
X997370Y424675D01*
G01X995895Y426758D02*
X995645Y427008D01*
X995353Y427133D01*
X995020Y427175D01*
X994603Y427092D01*
X994311Y426883D01*
X994228Y426633D01*
X994270Y426383D01*
X994436Y426175D01*
X995270Y425758D01*
X995645Y425467D01*
X995895Y425050D01*
X995978Y424675D01*
X994228D01*
G01X992795Y425717D02*
X992503Y426008D01*
X992253Y426175D01*
X991920Y426258D01*
X991628Y426175D01*
X991420Y426008D01*
X991253Y425758D01*
X991211Y425467D01*
X991253Y425217D01*
X991420Y424967D01*
X991670Y424758D01*
X991961Y424675D01*
X992295Y424758D01*
X992586Y425008D01*
X992753Y425383D01*
X992795Y425800D01*
X992711Y426342D01*
X992586Y426633D01*
X992378Y426925D01*
X992086Y427133D01*
X991795Y427175D01*
X991503Y427092D01*
X991295Y426883D01*
G01X1003486Y419967D02*
X1003736Y420092D01*
X1004028Y420175D01*
X1004361D01*
X1004736Y420050D01*
X1005028Y419842D01*
X1005236Y419592D01*
X1005403Y419175D01*
X1005445Y418800D01*
X1005361Y418425D01*
X1005236Y418175D01*
X1004986Y417925D01*
X1004695Y417758D01*
X1004403Y417675D01*
X1004111D01*
X1003820Y417758D01*
X1003570Y417883D01*
X1003361Y418050D01*
G01X1001303Y417675D02*
Y420175D01*
X1001803Y419675D01*
G01Y417675D02*
X1000803D01*
G01X999036D02*
Y420175D01*
X997995D01*
X997661Y420050D01*
X997453Y419883D01*
X997370Y419550D01*
X997453Y419217D01*
X997703Y419008D01*
X997995Y418883D01*
X999036D01*
G01X997995D02*
X997370Y417675D01*
G01X996020Y418175D02*
X995770Y417883D01*
X995436Y417717D01*
X995061Y417675D01*
X994728Y417717D01*
X994395Y417925D01*
X994186Y418175D01*
X994145Y418425D01*
X994228Y418717D01*
X994520Y418925D01*
X994811Y419008D01*
X995186D01*
G01X994811D02*
X994561Y419133D01*
X994353Y419342D01*
X994270Y419592D01*
X994353Y419842D01*
X994561Y420050D01*
X994936Y420175D01*
X995311Y420133D01*
X995686Y419967D01*
G01X992003Y417675D02*
Y420175D01*
X992503Y419675D01*
G01Y417675D02*
X991503D01*
G01X994821Y465694D02*
X995071Y465819D01*
X995363Y465902D01*
X995696D01*
X996071Y465777D01*
X996363Y465569D01*
X996571Y465319D01*
X996738Y464902D01*
X996780Y464527D01*
X996696Y464152D01*
X996571Y463902D01*
X996321Y463652D01*
X996030Y463485D01*
X995738Y463402D01*
X995446D01*
X995155Y463485D01*
X994905Y463610D01*
X994696Y463777D01*
G01X993555D02*
X993305Y463569D01*
X993013Y463444D01*
X992638Y463402D01*
X992263Y463485D01*
X991971Y463652D01*
X991763Y463944D01*
X991721Y464277D01*
X991805Y464610D01*
X992013Y464819D01*
X992305Y464985D01*
X992596Y465027D01*
X992888Y464985D01*
X993263Y464819D01*
X993138Y465902D01*
X992013D01*
G01X990621Y463402D02*
Y465902D01*
X989538Y463819D01*
X988455Y465902D01*
Y463402D01*
G01X986521D02*
X986438Y463944D01*
X986313Y464402D01*
X986146Y464819D01*
X985938Y465277D01*
X985605Y465902D01*
X987271D01*
G01X1012727Y465815D02*
X1012977Y465940D01*
X1013269Y466023D01*
X1013602D01*
X1013977Y465898D01*
X1014269Y465690D01*
X1014477Y465440D01*
X1014644Y465023D01*
X1014686Y464648D01*
X1014602Y464273D01*
X1014477Y464023D01*
X1014227Y463773D01*
X1013936Y463606D01*
X1013644Y463523D01*
X1013352D01*
X1013061Y463606D01*
X1012811Y463731D01*
X1012602Y463898D01*
G01X1011461D02*
X1011211Y463690D01*
X1010919Y463565D01*
X1010544Y463523D01*
X1010169Y463606D01*
X1009877Y463773D01*
X1009669Y464065D01*
X1009627Y464398D01*
X1009711Y464731D01*
X1009919Y464940D01*
X1010211Y465106D01*
X1010502Y465148D01*
X1010794Y465106D01*
X1011169Y464940D01*
X1011044Y466023D01*
X1009919D01*
G01X1008527Y463523D02*
Y466023D01*
X1007444Y463940D01*
X1006361Y466023D01*
Y463523D01*
G01X1005136Y464565D02*
X1004844Y464856D01*
X1004594Y465023D01*
X1004261Y465106D01*
X1003969Y465023D01*
X1003761Y464856D01*
X1003594Y464606D01*
X1003552Y464315D01*
X1003594Y464065D01*
X1003761Y463815D01*
X1004011Y463606D01*
X1004302Y463523D01*
X1004636Y463606D01*
X1004927Y463856D01*
X1005094Y464231D01*
X1005136Y464648D01*
X1005052Y465190D01*
X1004927Y465481D01*
X1004719Y465773D01*
X1004427Y465981D01*
X1004136Y466023D01*
X1003844Y465940D01*
X1003636Y465731D01*
G01X1029908Y465815D02*
X1030158Y465940D01*
X1030450Y466023D01*
X1030783D01*
X1031158Y465898D01*
X1031450Y465690D01*
X1031658Y465440D01*
X1031825Y465023D01*
X1031867Y464648D01*
X1031783Y464273D01*
X1031658Y464023D01*
X1031408Y463773D01*
X1031117Y463606D01*
X1030825Y463523D01*
X1030533D01*
X1030242Y463606D01*
X1029992Y463731D01*
X1029783Y463898D01*
G01X1028642D02*
X1028392Y463690D01*
X1028100Y463565D01*
X1027725Y463523D01*
X1027350Y463606D01*
X1027058Y463773D01*
X1026850Y464065D01*
X1026808Y464398D01*
X1026892Y464731D01*
X1027100Y464940D01*
X1027392Y465106D01*
X1027683Y465148D01*
X1027975Y465106D01*
X1028350Y464940D01*
X1028225Y466023D01*
X1027100D01*
G01X1025708Y463523D02*
Y466023D01*
X1024625Y463940D01*
X1023542Y466023D01*
Y463523D01*
G01X1022442Y463898D02*
X1022192Y463690D01*
X1021900Y463565D01*
X1021525Y463523D01*
X1021150Y463606D01*
X1020858Y463773D01*
X1020650Y464065D01*
X1020608Y464398D01*
X1020692Y464731D01*
X1020900Y464940D01*
X1021192Y465106D01*
X1021483Y465148D01*
X1021775Y465106D01*
X1022150Y464940D01*
X1022025Y466023D01*
X1020900D01*
G01X1016983Y488667D02*
Y491167D01*
X1015942D01*
X1015608Y491042D01*
X1015400Y490875D01*
X1015317Y490542D01*
X1015400Y490209D01*
X1015650Y490000D01*
X1015942Y489875D01*
X1016983D01*
G01X1015942D02*
X1015317Y488667D01*
G01X1012550D02*
Y491167D01*
X1014092Y489375D01*
X1012008D01*
G01X1010783Y491167D02*
Y488667D01*
X1009117D01*
G01X1007642Y490750D02*
X1007392Y491000D01*
X1007100Y491125D01*
X1006767Y491167D01*
X1006350Y491084D01*
X1006058Y490875D01*
X1005975Y490625D01*
X1006017Y490375D01*
X1006183Y490167D01*
X1007017Y489750D01*
X1007392Y489459D01*
X1007642Y489042D01*
X1007725Y488667D01*
X1005975D01*
G01X994821Y477694D02*
X995071Y477819D01*
X995363Y477902D01*
X995696D01*
X996071Y477777D01*
X996363Y477569D01*
X996571Y477319D01*
X996738Y476902D01*
X996780Y476527D01*
X996696Y476152D01*
X996571Y475902D01*
X996321Y475652D01*
X996030Y475485D01*
X995738Y475402D01*
X995446D01*
X995155Y475485D01*
X994905Y475610D01*
X994696Y475777D01*
G01X993555D02*
X993305Y475569D01*
X993013Y475444D01*
X992638Y475402D01*
X992263Y475485D01*
X991971Y475652D01*
X991763Y475944D01*
X991721Y476277D01*
X991805Y476610D01*
X992013Y476819D01*
X992305Y476985D01*
X992596Y477027D01*
X992888Y476985D01*
X993263Y476819D01*
X993138Y477902D01*
X992013D01*
G01X989288Y476652D02*
X988455D01*
Y475902D01*
X988705Y475652D01*
X988996Y475485D01*
X989413Y475402D01*
X989830Y475485D01*
X990121Y475652D01*
X990371Y475902D01*
X990538Y476194D01*
X990621Y476527D01*
Y476819D01*
X990538Y477069D01*
X990371Y477360D01*
X990121Y477610D01*
X989871Y477777D01*
X989538Y477902D01*
X989246D01*
X988913Y477819D01*
X988663Y477652D01*
G01X987355Y475777D02*
X987105Y475569D01*
X986813Y475444D01*
X986438Y475402D01*
X986063Y475485D01*
X985771Y475652D01*
X985563Y475944D01*
X985521Y476277D01*
X985605Y476610D01*
X985813Y476819D01*
X986105Y476985D01*
X986396Y477027D01*
X986688Y476985D01*
X987063Y476819D01*
X986938Y477902D01*
X985813D01*
G01X984046Y475694D02*
X983755Y475485D01*
X983421Y475402D01*
X983088Y475485D01*
X982796Y475735D01*
X982588Y476110D01*
X982505Y476485D01*
Y476944D01*
X982588Y477319D01*
X982796Y477652D01*
X983046Y477819D01*
X983338Y477902D01*
X983671Y477819D01*
X983921Y477652D01*
X984088Y477402D01*
X984171Y477069D01*
X984088Y476777D01*
X983880Y476485D01*
X983630Y476319D01*
X983338Y476277D01*
X983005Y476360D01*
X982755Y476569D01*
X982505Y476944D01*
G01X1012727Y477815D02*
X1012977Y477940D01*
X1013269Y478023D01*
X1013602D01*
X1013977Y477898D01*
X1014269Y477690D01*
X1014477Y477440D01*
X1014644Y477023D01*
X1014686Y476648D01*
X1014602Y476273D01*
X1014477Y476023D01*
X1014227Y475773D01*
X1013936Y475606D01*
X1013644Y475523D01*
X1013352D01*
X1013061Y475606D01*
X1012811Y475731D01*
X1012602Y475898D01*
G01X1011461D02*
X1011211Y475690D01*
X1010919Y475565D01*
X1010544Y475523D01*
X1010169Y475606D01*
X1009877Y475773D01*
X1009669Y476065D01*
X1009627Y476398D01*
X1009711Y476731D01*
X1009919Y476940D01*
X1010211Y477106D01*
X1010502Y477148D01*
X1010794Y477106D01*
X1011169Y476940D01*
X1011044Y478023D01*
X1009919D01*
G01X1007194Y476773D02*
X1006361D01*
Y476023D01*
X1006611Y475773D01*
X1006902Y475606D01*
X1007319Y475523D01*
X1007736Y475606D01*
X1008027Y475773D01*
X1008277Y476023D01*
X1008444Y476315D01*
X1008527Y476648D01*
Y476940D01*
X1008444Y477190D01*
X1008277Y477481D01*
X1008027Y477731D01*
X1007777Y477898D01*
X1007444Y478023D01*
X1007152D01*
X1006819Y477940D01*
X1006569Y477773D01*
G01X1005136Y476565D02*
X1004844Y476856D01*
X1004594Y477023D01*
X1004261Y477106D01*
X1003969Y477023D01*
X1003761Y476856D01*
X1003594Y476606D01*
X1003552Y476315D01*
X1003594Y476065D01*
X1003761Y475815D01*
X1004011Y475606D01*
X1004302Y475523D01*
X1004636Y475606D01*
X1004927Y475856D01*
X1005094Y476231D01*
X1005136Y476648D01*
X1005052Y477190D01*
X1004927Y477481D01*
X1004719Y477773D01*
X1004427Y477981D01*
X1004136Y478023D01*
X1003844Y477940D01*
X1003636Y477731D01*
G01X1001244Y478023D02*
X1001577Y477940D01*
X1001827Y477731D01*
X1001994Y477481D01*
X1002119Y477148D01*
X1002161Y476773D01*
X1002119Y476398D01*
X1001994Y476065D01*
X1001827Y475815D01*
X1001577Y475606D01*
X1001244Y475523D01*
X1000911Y475606D01*
X1000661Y475815D01*
X1000494Y476065D01*
X1000369Y476398D01*
X1000327Y476773D01*
X1000369Y477148D01*
X1000494Y477481D01*
X1000661Y477731D01*
X1000911Y477940D01*
X1001244Y478023D01*
G01X1029908Y477815D02*
X1030158Y477940D01*
X1030450Y478023D01*
X1030783D01*
X1031158Y477898D01*
X1031450Y477690D01*
X1031658Y477440D01*
X1031825Y477023D01*
X1031867Y476648D01*
X1031783Y476273D01*
X1031658Y476023D01*
X1031408Y475773D01*
X1031117Y475606D01*
X1030825Y475523D01*
X1030533D01*
X1030242Y475606D01*
X1029992Y475731D01*
X1029783Y475898D01*
G01X1028642D02*
X1028392Y475690D01*
X1028100Y475565D01*
X1027725Y475523D01*
X1027350Y475606D01*
X1027058Y475773D01*
X1026850Y476065D01*
X1026808Y476398D01*
X1026892Y476731D01*
X1027100Y476940D01*
X1027392Y477106D01*
X1027683Y477148D01*
X1027975Y477106D01*
X1028350Y476940D01*
X1028225Y478023D01*
X1027100D01*
G01X1024375Y476773D02*
X1023542D01*
Y476023D01*
X1023792Y475773D01*
X1024083Y475606D01*
X1024500Y475523D01*
X1024917Y475606D01*
X1025208Y475773D01*
X1025458Y476023D01*
X1025625Y476315D01*
X1025708Y476648D01*
Y476940D01*
X1025625Y477190D01*
X1025458Y477481D01*
X1025208Y477731D01*
X1024958Y477898D01*
X1024625Y478023D01*
X1024333D01*
X1024000Y477940D01*
X1023750Y477773D01*
G01X1022317Y476565D02*
X1022025Y476856D01*
X1021775Y477023D01*
X1021442Y477106D01*
X1021150Y477023D01*
X1020942Y476856D01*
X1020775Y476606D01*
X1020733Y476315D01*
X1020775Y476065D01*
X1020942Y475815D01*
X1021192Y475606D01*
X1021483Y475523D01*
X1021817Y475606D01*
X1022108Y475856D01*
X1022275Y476231D01*
X1022317Y476648D01*
X1022233Y477190D01*
X1022108Y477481D01*
X1021900Y477773D01*
X1021608Y477981D01*
X1021317Y478023D01*
X1021025Y477940D01*
X1020817Y477731D01*
G01X1018425Y475523D02*
Y478023D01*
X1018925Y477523D01*
G01Y475523D02*
X1017925D01*
G01X994821Y469694D02*
X995071Y469819D01*
X995363Y469902D01*
X995696D01*
X996071Y469777D01*
X996363Y469569D01*
X996571Y469319D01*
X996738Y468902D01*
X996780Y468527D01*
X996696Y468152D01*
X996571Y467902D01*
X996321Y467652D01*
X996030Y467485D01*
X995738Y467402D01*
X995446D01*
X995155Y467485D01*
X994905Y467610D01*
X994696Y467777D01*
G01X993555D02*
X993305Y467569D01*
X993013Y467444D01*
X992638Y467402D01*
X992263Y467485D01*
X991971Y467652D01*
X991763Y467944D01*
X991721Y468277D01*
X991805Y468610D01*
X992013Y468819D01*
X992305Y468985D01*
X992596Y469027D01*
X992888Y468985D01*
X993263Y468819D01*
X993138Y469902D01*
X992013D01*
G01X989288Y468652D02*
X988455D01*
Y467902D01*
X988705Y467652D01*
X988996Y467485D01*
X989413Y467402D01*
X989830Y467485D01*
X990121Y467652D01*
X990371Y467902D01*
X990538Y468194D01*
X990621Y468527D01*
Y468819D01*
X990538Y469069D01*
X990371Y469360D01*
X990121Y469610D01*
X989871Y469777D01*
X989538Y469902D01*
X989246D01*
X988913Y469819D01*
X988663Y469652D01*
G01X987230Y468444D02*
X986938Y468735D01*
X986688Y468902D01*
X986355Y468985D01*
X986063Y468902D01*
X985855Y468735D01*
X985688Y468485D01*
X985646Y468194D01*
X985688Y467944D01*
X985855Y467694D01*
X986105Y467485D01*
X986396Y467402D01*
X986730Y467485D01*
X987021Y467735D01*
X987188Y468110D01*
X987230Y468527D01*
X987146Y469069D01*
X987021Y469360D01*
X986813Y469652D01*
X986521Y469860D01*
X986230Y469902D01*
X985938Y469819D01*
X985730Y469610D01*
G01X982838Y467402D02*
Y469902D01*
X984380Y468110D01*
X982296D01*
G01X1012727Y469815D02*
X1012977Y469940D01*
X1013269Y470023D01*
X1013602D01*
X1013977Y469898D01*
X1014269Y469690D01*
X1014477Y469440D01*
X1014644Y469023D01*
X1014686Y468648D01*
X1014602Y468273D01*
X1014477Y468023D01*
X1014227Y467773D01*
X1013936Y467606D01*
X1013644Y467523D01*
X1013352D01*
X1013061Y467606D01*
X1012811Y467731D01*
X1012602Y467898D01*
G01X1011461D02*
X1011211Y467690D01*
X1010919Y467565D01*
X1010544Y467523D01*
X1010169Y467606D01*
X1009877Y467773D01*
X1009669Y468065D01*
X1009627Y468398D01*
X1009711Y468731D01*
X1009919Y468940D01*
X1010211Y469106D01*
X1010502Y469148D01*
X1010794Y469106D01*
X1011169Y468940D01*
X1011044Y470023D01*
X1009919D01*
G01X1007194Y468773D02*
X1006361D01*
Y468023D01*
X1006611Y467773D01*
X1006902Y467606D01*
X1007319Y467523D01*
X1007736Y467606D01*
X1008027Y467773D01*
X1008277Y468023D01*
X1008444Y468315D01*
X1008527Y468648D01*
Y468940D01*
X1008444Y469190D01*
X1008277Y469481D01*
X1008027Y469731D01*
X1007777Y469898D01*
X1007444Y470023D01*
X1007152D01*
X1006819Y469940D01*
X1006569Y469773D01*
G01X1005136Y468565D02*
X1004844Y468856D01*
X1004594Y469023D01*
X1004261Y469106D01*
X1003969Y469023D01*
X1003761Y468856D01*
X1003594Y468606D01*
X1003552Y468315D01*
X1003594Y468065D01*
X1003761Y467815D01*
X1004011Y467606D01*
X1004302Y467523D01*
X1004636Y467606D01*
X1004927Y467856D01*
X1005094Y468231D01*
X1005136Y468648D01*
X1005052Y469190D01*
X1004927Y469481D01*
X1004719Y469773D01*
X1004427Y469981D01*
X1004136Y470023D01*
X1003844Y469940D01*
X1003636Y469731D01*
G01X1002161Y467898D02*
X1001911Y467690D01*
X1001619Y467565D01*
X1001244Y467523D01*
X1000869Y467606D01*
X1000577Y467773D01*
X1000369Y468065D01*
X1000327Y468398D01*
X1000411Y468731D01*
X1000619Y468940D01*
X1000911Y469106D01*
X1001202Y469148D01*
X1001494Y469106D01*
X1001869Y468940D01*
X1001744Y470023D01*
X1000619D01*
G01X1029908Y469815D02*
X1030158Y469940D01*
X1030450Y470023D01*
X1030783D01*
X1031158Y469898D01*
X1031450Y469690D01*
X1031658Y469440D01*
X1031825Y469023D01*
X1031867Y468648D01*
X1031783Y468273D01*
X1031658Y468023D01*
X1031408Y467773D01*
X1031117Y467606D01*
X1030825Y467523D01*
X1030533D01*
X1030242Y467606D01*
X1029992Y467731D01*
X1029783Y467898D01*
G01X1028642D02*
X1028392Y467690D01*
X1028100Y467565D01*
X1027725Y467523D01*
X1027350Y467606D01*
X1027058Y467773D01*
X1026850Y468065D01*
X1026808Y468398D01*
X1026892Y468731D01*
X1027100Y468940D01*
X1027392Y469106D01*
X1027683Y469148D01*
X1027975Y469106D01*
X1028350Y468940D01*
X1028225Y470023D01*
X1027100D01*
G01X1024375Y468773D02*
X1023542D01*
Y468023D01*
X1023792Y467773D01*
X1024083Y467606D01*
X1024500Y467523D01*
X1024917Y467606D01*
X1025208Y467773D01*
X1025458Y468023D01*
X1025625Y468315D01*
X1025708Y468648D01*
Y468940D01*
X1025625Y469190D01*
X1025458Y469481D01*
X1025208Y469731D01*
X1024958Y469898D01*
X1024625Y470023D01*
X1024333D01*
X1024000Y469940D01*
X1023750Y469773D01*
G01X1022317Y468565D02*
X1022025Y468856D01*
X1021775Y469023D01*
X1021442Y469106D01*
X1021150Y469023D01*
X1020942Y468856D01*
X1020775Y468606D01*
X1020733Y468315D01*
X1020775Y468065D01*
X1020942Y467815D01*
X1021192Y467606D01*
X1021483Y467523D01*
X1021817Y467606D01*
X1022108Y467856D01*
X1022275Y468231D01*
X1022317Y468648D01*
X1022233Y469190D01*
X1022108Y469481D01*
X1021900Y469773D01*
X1021608Y469981D01*
X1021317Y470023D01*
X1021025Y469940D01*
X1020817Y469731D01*
G01X1019217Y468565D02*
X1018925Y468856D01*
X1018675Y469023D01*
X1018342Y469106D01*
X1018050Y469023D01*
X1017842Y468856D01*
X1017675Y468606D01*
X1017633Y468315D01*
X1017675Y468065D01*
X1017842Y467815D01*
X1018092Y467606D01*
X1018383Y467523D01*
X1018717Y467606D01*
X1019008Y467856D01*
X1019175Y468231D01*
X1019217Y468648D01*
X1019133Y469190D01*
X1019008Y469481D01*
X1018800Y469773D01*
X1018508Y469981D01*
X1018217Y470023D01*
X1017925Y469940D01*
X1017717Y469731D01*
G01X1027929Y526001D02*
X1027852Y526673D01*
X1027737Y527241D01*
X1027584Y527758D01*
X1027392Y528326D01*
X1027085Y529101D01*
X1028619D01*
G01X1024829Y526001D02*
X1024752Y526673D01*
X1024637Y527241D01*
X1024484Y527758D01*
X1024292Y528326D01*
X1023985Y529101D01*
X1025519D01*
G01X1029828Y514550D02*
X1029598Y514860D01*
X1029330Y515015D01*
X1029023Y515067D01*
X1028640Y514964D01*
X1028372Y514705D01*
X1028295Y514395D01*
X1028333Y514085D01*
X1028487Y513827D01*
X1029253Y513310D01*
X1029598Y512949D01*
X1029828Y512432D01*
X1029905Y511967D01*
X1028295D01*
G01X1026728Y514550D02*
X1026498Y514860D01*
X1026230Y515015D01*
X1025923Y515067D01*
X1025540Y514964D01*
X1025272Y514705D01*
X1025195Y514395D01*
X1025233Y514085D01*
X1025387Y513827D01*
X1026153Y513310D01*
X1026498Y512949D01*
X1026728Y512432D01*
X1026805Y511967D01*
X1025195D01*
G01X1023628Y514550D02*
X1023398Y514860D01*
X1023130Y515015D01*
X1022823Y515067D01*
X1022440Y514964D01*
X1022172Y514705D01*
X1022095Y514395D01*
X1022133Y514085D01*
X1022287Y513827D01*
X1023053Y513310D01*
X1023398Y512949D01*
X1023628Y512432D01*
X1023705Y511967D01*
X1022095D01*
G01X1034328Y499250D02*
X1034098Y499560D01*
X1033830Y499715D01*
X1033523Y499767D01*
X1033140Y499664D01*
X1032872Y499405D01*
X1032795Y499095D01*
X1032833Y498785D01*
X1032987Y498527D01*
X1033753Y498010D01*
X1034098Y497649D01*
X1034328Y497132D01*
X1034405Y496667D01*
X1032795D01*
G01X1031228Y499250D02*
X1030998Y499560D01*
X1030730Y499715D01*
X1030423Y499767D01*
X1030040Y499664D01*
X1029772Y499405D01*
X1029695Y499095D01*
X1029733Y498785D01*
X1029887Y498527D01*
X1030653Y498010D01*
X1030998Y497649D01*
X1031228Y497132D01*
X1031305Y496667D01*
X1029695D01*
G01X1027400D02*
Y499767D01*
X1027860Y499147D01*
G01Y496667D02*
X1026940D01*
G01X1012283Y497958D02*
X1012533Y498083D01*
X1012825Y498166D01*
X1013158D01*
X1013533Y498041D01*
X1013825Y497833D01*
X1014033Y497583D01*
X1014200Y497166D01*
X1014242Y496791D01*
X1014158Y496416D01*
X1014033Y496166D01*
X1013783Y495916D01*
X1013492Y495749D01*
X1013200Y495666D01*
X1012908D01*
X1012617Y495749D01*
X1012367Y495874D01*
X1012158Y496041D01*
G01X1011017D02*
X1010767Y495833D01*
X1010475Y495708D01*
X1010100Y495666D01*
X1009725Y495749D01*
X1009433Y495916D01*
X1009225Y496208D01*
X1009183Y496541D01*
X1009267Y496874D01*
X1009475Y497083D01*
X1009767Y497249D01*
X1010058Y497291D01*
X1010350Y497249D01*
X1010725Y497083D01*
X1010600Y498166D01*
X1009475D01*
G01X1008083Y495666D02*
Y498166D01*
X1007000Y496083D01*
X1005917Y498166D01*
Y495666D01*
G01X1003900D02*
Y498166D01*
X1004400Y497666D01*
G01Y495666D02*
X1003400D01*
G01X1001717Y496166D02*
X1001467Y495874D01*
X1001133Y495708D01*
X1000758Y495666D01*
X1000425Y495708D01*
X1000092Y495916D01*
X999883Y496166D01*
X999842Y496416D01*
X999925Y496708D01*
X1000217Y496916D01*
X1000508Y496999D01*
X1000883D01*
G01X1000508D02*
X1000258Y497124D01*
X1000050Y497333D01*
X999967Y497583D01*
X1000050Y497833D01*
X1000258Y498041D01*
X1000633Y498166D01*
X1001008Y498124D01*
X1001383Y497958D01*
G01X994821Y473694D02*
X995071Y473819D01*
X995363Y473902D01*
X995696D01*
X996071Y473777D01*
X996363Y473569D01*
X996571Y473319D01*
X996738Y472902D01*
X996780Y472527D01*
X996696Y472152D01*
X996571Y471902D01*
X996321Y471652D01*
X996030Y471485D01*
X995738Y471402D01*
X995446D01*
X995155Y471485D01*
X994905Y471610D01*
X994696Y471777D01*
G01X993555D02*
X993305Y471569D01*
X993013Y471444D01*
X992638Y471402D01*
X992263Y471485D01*
X991971Y471652D01*
X991763Y471944D01*
X991721Y472277D01*
X991805Y472610D01*
X992013Y472819D01*
X992305Y472985D01*
X992596Y473027D01*
X992888Y472985D01*
X993263Y472819D01*
X993138Y473902D01*
X992013D01*
G01X990371D02*
Y471402D01*
X988705D01*
G01X986438D02*
Y473902D01*
X986938Y473402D01*
G01Y471402D02*
X985938D01*
G01X984255Y471902D02*
X984005Y471610D01*
X983671Y471444D01*
X983296Y471402D01*
X982963Y471444D01*
X982630Y471652D01*
X982421Y471902D01*
X982380Y472152D01*
X982463Y472444D01*
X982755Y472652D01*
X983046Y472735D01*
X983421D01*
G01X983046D02*
X982796Y472860D01*
X982588Y473069D01*
X982505Y473319D01*
X982588Y473569D01*
X982796Y473777D01*
X983171Y473902D01*
X983546Y473860D01*
X983921Y473694D01*
G01X1012727Y473815D02*
X1012977Y473940D01*
X1013269Y474023D01*
X1013602D01*
X1013977Y473898D01*
X1014269Y473690D01*
X1014477Y473440D01*
X1014644Y473023D01*
X1014686Y472648D01*
X1014602Y472273D01*
X1014477Y472023D01*
X1014227Y471773D01*
X1013936Y471606D01*
X1013644Y471523D01*
X1013352D01*
X1013061Y471606D01*
X1012811Y471731D01*
X1012602Y471898D01*
G01X1011461D02*
X1011211Y471690D01*
X1010919Y471565D01*
X1010544Y471523D01*
X1010169Y471606D01*
X1009877Y471773D01*
X1009669Y472065D01*
X1009627Y472398D01*
X1009711Y472731D01*
X1009919Y472940D01*
X1010211Y473106D01*
X1010502Y473148D01*
X1010794Y473106D01*
X1011169Y472940D01*
X1011044Y474023D01*
X1009919D01*
G01X1008277D02*
Y471523D01*
X1006611D01*
G01X1004344D02*
Y474023D01*
X1004844Y473523D01*
G01Y471523D02*
X1003844D01*
G01X1002036Y473606D02*
X1001786Y473856D01*
X1001494Y473981D01*
X1001161Y474023D01*
X1000744Y473940D01*
X1000452Y473731D01*
X1000369Y473481D01*
X1000411Y473231D01*
X1000577Y473023D01*
X1001411Y472606D01*
X1001786Y472315D01*
X1002036Y471898D01*
X1002119Y471523D01*
X1000369D01*
G01X1029908Y473815D02*
X1030158Y473940D01*
X1030450Y474023D01*
X1030783D01*
X1031158Y473898D01*
X1031450Y473690D01*
X1031658Y473440D01*
X1031825Y473023D01*
X1031867Y472648D01*
X1031783Y472273D01*
X1031658Y472023D01*
X1031408Y471773D01*
X1031117Y471606D01*
X1030825Y471523D01*
X1030533D01*
X1030242Y471606D01*
X1029992Y471731D01*
X1029783Y471898D01*
G01X1028642D02*
X1028392Y471690D01*
X1028100Y471565D01*
X1027725Y471523D01*
X1027350Y471606D01*
X1027058Y471773D01*
X1026850Y472065D01*
X1026808Y472398D01*
X1026892Y472731D01*
X1027100Y472940D01*
X1027392Y473106D01*
X1027683Y473148D01*
X1027975Y473106D01*
X1028350Y472940D01*
X1028225Y474023D01*
X1027100D01*
G01X1025458D02*
Y471523D01*
X1023792D01*
G01X1021525D02*
Y474023D01*
X1022025Y473523D01*
G01Y471523D02*
X1021025D01*
G01X1018425D02*
Y474023D01*
X1018925Y473523D01*
G01Y471523D02*
X1017925D01*
G01X1034575Y489499D02*
X1034242Y489291D01*
X1033867Y489166D01*
X1033533D01*
X1033200Y489291D01*
X1032950Y489499D01*
X1032825Y489791D01*
X1032908Y490083D01*
X1033117Y490333D01*
X1033492Y490499D01*
X1033992Y490583D01*
X1034283Y490749D01*
X1034408Y491041D01*
X1034325Y491333D01*
X1034117Y491541D01*
X1033825Y491666D01*
X1033533D01*
X1033242Y491583D01*
X1032992Y491374D01*
G01X1031475Y489166D02*
Y491666D01*
G01X1029725D02*
Y489166D01*
G01Y490416D02*
X1031475D01*
G01X1027000Y489166D02*
Y491666D01*
X1028542Y489874D01*
X1026458D01*
G01X1025233Y491666D02*
Y489166D01*
X1023567D01*
G01X1022092Y491249D02*
X1021842Y491499D01*
X1021550Y491624D01*
X1021217Y491666D01*
X1020800Y491583D01*
X1020508Y491374D01*
X1020425Y491124D01*
X1020467Y490874D01*
X1020633Y490666D01*
X1021467Y490249D01*
X1021842Y489958D01*
X1022092Y489541D01*
X1022175Y489166D01*
X1020425D01*
G01X1002175Y489100D02*
X1001842Y488892D01*
X1001467Y488767D01*
X1001133D01*
X1000800Y488892D01*
X1000550Y489100D01*
X1000425Y489392D01*
X1000508Y489684D01*
X1000717Y489934D01*
X1001092Y490100D01*
X1001592Y490184D01*
X1001883Y490350D01*
X1002008Y490642D01*
X1001925Y490934D01*
X1001717Y491142D01*
X1001425Y491267D01*
X1001133D01*
X1000842Y491184D01*
X1000592Y490975D01*
G01X999075Y488767D02*
Y491267D01*
G01X997325D02*
Y488767D01*
G01Y490017D02*
X999075D01*
G01X994600Y488767D02*
Y491267D01*
X996142Y489475D01*
X994058D01*
G01X992833Y491267D02*
Y488767D01*
X991167D01*
G01X988900D02*
Y491267D01*
X989400Y490767D01*
G01Y488767D02*
X988400D01*
G01X1023924Y574918D02*
X1024154Y574608D01*
X1024422Y574453D01*
X1024729Y574401D01*
X1025112Y574504D01*
X1025380Y574763D01*
X1025457Y575073D01*
X1025419Y575383D01*
X1025265Y575641D01*
X1024499Y576158D01*
X1024154Y576519D01*
X1023924Y577036D01*
X1023847Y577501D01*
X1025457D01*
G01X1027024Y574918D02*
X1027254Y574608D01*
X1027522Y574453D01*
X1027829Y574401D01*
X1028212Y574504D01*
X1028480Y574763D01*
X1028557Y575073D01*
X1028519Y575383D01*
X1028365Y575641D01*
X1027599Y576158D01*
X1027254Y576519D01*
X1027024Y577036D01*
X1026947Y577501D01*
X1028557D01*
G01X1030852D02*
Y574401D01*
X1030392Y575021D01*
G01Y577501D02*
X1031312D01*
G01X1027929Y562501D02*
X1027852Y563173D01*
X1027737Y563741D01*
X1027584Y564258D01*
X1027392Y564826D01*
X1027085Y565601D01*
X1028619D01*
G01X1024829Y562501D02*
X1024752Y563173D01*
X1024637Y563741D01*
X1024484Y564258D01*
X1024292Y564826D01*
X1023985Y565601D01*
X1025519D01*
G01X1030580Y539084D02*
X1030350Y539394D01*
X1030082Y539549D01*
X1029775Y539601D01*
X1029392Y539498D01*
X1029124Y539239D01*
X1029047Y538929D01*
X1029085Y538619D01*
X1029239Y538361D01*
X1030005Y537844D01*
X1030350Y537483D01*
X1030580Y536966D01*
X1030657Y536501D01*
X1029047D01*
G01X1027480Y539084D02*
X1027250Y539394D01*
X1026982Y539549D01*
X1026675Y539601D01*
X1026292Y539498D01*
X1026024Y539239D01*
X1025947Y538929D01*
X1025985Y538619D01*
X1026139Y538361D01*
X1026905Y537844D01*
X1027250Y537483D01*
X1027480Y536966D01*
X1027557Y536501D01*
X1025947D01*
G01X1023652D02*
Y539601D01*
X1024112Y538981D01*
G01Y536501D02*
X1023192D01*
G01X1005349Y616665D02*
X1005599Y616790D01*
X1005891Y616873D01*
X1006224D01*
X1006599Y616748D01*
X1006891Y616540D01*
X1007099Y616290D01*
X1007266Y615873D01*
X1007308Y615498D01*
X1007224Y615123D01*
X1007099Y614873D01*
X1006849Y614623D01*
X1006558Y614456D01*
X1006266Y614373D01*
X1005974D01*
X1005683Y614456D01*
X1005433Y614581D01*
X1005224Y614748D01*
G01X1004083D02*
X1003833Y614540D01*
X1003541Y614415D01*
X1003166Y614373D01*
X1002791Y614456D01*
X1002499Y614623D01*
X1002291Y614915D01*
X1002249Y615248D01*
X1002333Y615581D01*
X1002541Y615790D01*
X1002833Y615956D01*
X1003124Y615998D01*
X1003416Y615956D01*
X1003791Y615790D01*
X1003666Y616873D01*
X1002541D01*
G01X1000899D02*
Y614373D01*
X999233D01*
G01X996466D02*
Y616873D01*
X998008Y615081D01*
X995924D01*
G01X1025929Y603501D02*
X1025852Y604173D01*
X1025737Y604741D01*
X1025584Y605258D01*
X1025392Y605826D01*
X1025085Y606601D01*
X1026619D01*
G01X1022829Y603501D02*
X1022752Y604173D01*
X1022637Y604741D01*
X1022484Y605258D01*
X1022292Y605826D01*
X1021985Y606601D01*
X1023519D01*
G01X998631Y618252D02*
X998298Y618044D01*
X997923Y617919D01*
X997589D01*
X997256Y618044D01*
X997006Y618252D01*
X996881Y618544D01*
X996964Y618836D01*
X997173Y619086D01*
X997548Y619252D01*
X998048Y619336D01*
X998339Y619502D01*
X998464Y619794D01*
X998381Y620086D01*
X998173Y620294D01*
X997881Y620419D01*
X997589D01*
X997298Y620336D01*
X997048Y620127D01*
G01X995531Y617919D02*
Y620419D01*
G01X993781D02*
Y617919D01*
G01Y619169D02*
X995531D01*
G01X992473Y618294D02*
X992223Y618086D01*
X991931Y617961D01*
X991556Y617919D01*
X991181Y618002D01*
X990889Y618169D01*
X990681Y618461D01*
X990639Y618794D01*
X990723Y619127D01*
X990931Y619336D01*
X991223Y619502D01*
X991514Y619544D01*
X991806Y619502D01*
X992181Y619336D01*
X992056Y620419D01*
X990931D01*
G01X989289D02*
Y617919D01*
X987623D01*
G01X985356D02*
Y620419D01*
X985856Y619919D01*
G01Y617919D02*
X984856D01*
G01X1058383Y-19108D02*
X1058633Y-18983D01*
X1058925Y-18900D01*
X1059258D01*
X1059633Y-19025D01*
X1059925Y-19233D01*
X1060133Y-19483D01*
X1060300Y-19900D01*
X1060342Y-20275D01*
X1060258Y-20650D01*
X1060133Y-20900D01*
X1059883Y-21150D01*
X1059592Y-21317D01*
X1059300Y-21400D01*
X1059008D01*
X1058717Y-21317D01*
X1058467Y-21192D01*
X1058258Y-21025D01*
G01X1057117D02*
X1056867Y-21233D01*
X1056575Y-21358D01*
X1056200Y-21400D01*
X1055825Y-21317D01*
X1055533Y-21150D01*
X1055325Y-20858D01*
X1055283Y-20525D01*
X1055367Y-20192D01*
X1055575Y-19983D01*
X1055867Y-19817D01*
X1056158Y-19775D01*
X1056450Y-19817D01*
X1056825Y-19983D01*
X1056700Y-18900D01*
X1055575D01*
G01X1054017D02*
Y-20692D01*
X1053850Y-21067D01*
X1053517Y-21317D01*
X1053100Y-21400D01*
X1052683Y-21317D01*
X1052350Y-21067D01*
X1052183Y-20692D01*
Y-18900D01*
G01X1050000Y-21400D02*
Y-18900D01*
X1050500Y-19400D01*
G01Y-21400D02*
X1049500D01*
G01X1047817Y-21025D02*
X1047567Y-21233D01*
X1047275Y-21358D01*
X1046900Y-21400D01*
X1046525Y-21317D01*
X1046233Y-21150D01*
X1046025Y-20858D01*
X1045983Y-20525D01*
X1046067Y-20192D01*
X1046275Y-19983D01*
X1046567Y-19817D01*
X1046858Y-19775D01*
X1047150Y-19817D01*
X1047525Y-19983D01*
X1047400Y-18900D01*
X1046275D01*
G01X1074383Y-19108D02*
X1074633Y-18983D01*
X1074925Y-18900D01*
X1075258D01*
X1075633Y-19025D01*
X1075925Y-19233D01*
X1076133Y-19483D01*
X1076300Y-19900D01*
X1076342Y-20275D01*
X1076258Y-20650D01*
X1076133Y-20900D01*
X1075883Y-21150D01*
X1075592Y-21317D01*
X1075300Y-21400D01*
X1075008D01*
X1074717Y-21317D01*
X1074467Y-21192D01*
X1074258Y-21025D01*
G01X1073117D02*
X1072867Y-21233D01*
X1072575Y-21358D01*
X1072200Y-21400D01*
X1071825Y-21317D01*
X1071533Y-21150D01*
X1071325Y-20858D01*
X1071283Y-20525D01*
X1071367Y-20192D01*
X1071575Y-19983D01*
X1071867Y-19817D01*
X1072158Y-19775D01*
X1072450Y-19817D01*
X1072825Y-19983D01*
X1072700Y-18900D01*
X1071575D01*
G01X1070017D02*
Y-20692D01*
X1069850Y-21067D01*
X1069517Y-21317D01*
X1069100Y-21400D01*
X1068683Y-21317D01*
X1068350Y-21067D01*
X1068183Y-20692D01*
Y-18900D01*
G01X1066000Y-21400D02*
Y-18900D01*
X1066500Y-19400D01*
G01Y-21400D02*
X1065500D01*
G01X1062400D02*
Y-18900D01*
X1063942Y-20692D01*
X1061858D01*
G01X1090383Y-19108D02*
X1090633Y-18983D01*
X1090925Y-18900D01*
X1091258D01*
X1091633Y-19025D01*
X1091925Y-19233D01*
X1092133Y-19483D01*
X1092300Y-19900D01*
X1092342Y-20275D01*
X1092258Y-20650D01*
X1092133Y-20900D01*
X1091883Y-21150D01*
X1091592Y-21317D01*
X1091300Y-21400D01*
X1091008D01*
X1090717Y-21317D01*
X1090467Y-21192D01*
X1090258Y-21025D01*
G01X1089117D02*
X1088867Y-21233D01*
X1088575Y-21358D01*
X1088200Y-21400D01*
X1087825Y-21317D01*
X1087533Y-21150D01*
X1087325Y-20858D01*
X1087283Y-20525D01*
X1087367Y-20192D01*
X1087575Y-19983D01*
X1087867Y-19817D01*
X1088158Y-19775D01*
X1088450Y-19817D01*
X1088825Y-19983D01*
X1088700Y-18900D01*
X1087575D01*
G01X1086017D02*
Y-20692D01*
X1085850Y-21067D01*
X1085517Y-21317D01*
X1085100Y-21400D01*
X1084683Y-21317D01*
X1084350Y-21067D01*
X1084183Y-20692D01*
Y-18900D01*
G01X1082000Y-21400D02*
Y-18900D01*
X1082500Y-19400D01*
G01Y-21400D02*
X1081500D01*
G01X1079817Y-20900D02*
X1079567Y-21192D01*
X1079233Y-21358D01*
X1078858Y-21400D01*
X1078525Y-21358D01*
X1078192Y-21150D01*
X1077983Y-20900D01*
X1077942Y-20650D01*
X1078025Y-20358D01*
X1078317Y-20150D01*
X1078608Y-20067D01*
X1078983D01*
G01X1078608D02*
X1078358Y-19942D01*
X1078150Y-19733D01*
X1078067Y-19483D01*
X1078150Y-19233D01*
X1078358Y-19025D01*
X1078733Y-18900D01*
X1079108Y-18942D01*
X1079483Y-19108D01*
G01X1045429Y27000D02*
X1045352Y27672D01*
X1045237Y28240D01*
X1045084Y28757D01*
X1044892Y29325D01*
X1044585Y30100D01*
X1046119D01*
G01X1042252Y27000D02*
X1041984Y27052D01*
X1041677Y27207D01*
X1041485Y27465D01*
X1041409Y27827D01*
X1041485Y28188D01*
X1041715Y28498D01*
X1042060Y28653D01*
X1042444D01*
X1042674Y28757D01*
X1042865Y29015D01*
X1042942Y29377D01*
X1042827Y29738D01*
X1042559Y29997D01*
X1042252Y30100D01*
X1041945Y29997D01*
X1041677Y29738D01*
X1041562Y29377D01*
X1041639Y29015D01*
X1041830Y28757D01*
X1042060Y28653D01*
X1042444D01*
X1042789Y28498D01*
X1043019Y28188D01*
X1043095Y27827D01*
X1043019Y27465D01*
X1042827Y27207D01*
X1042520Y27052D01*
X1042252Y27000D01*
G01X1049580Y-917D02*
X1049350Y-607D01*
X1049082Y-452D01*
X1048775Y-400D01*
X1048392Y-503D01*
X1048124Y-762D01*
X1048047Y-1072D01*
X1048085Y-1382D01*
X1048239Y-1640D01*
X1049005Y-2157D01*
X1049350Y-2518D01*
X1049580Y-3035D01*
X1049657Y-3500D01*
X1048047D01*
G01X1046480Y-917D02*
X1046250Y-607D01*
X1045982Y-452D01*
X1045675Y-400D01*
X1045292Y-503D01*
X1045024Y-762D01*
X1044947Y-1072D01*
X1044985Y-1382D01*
X1045139Y-1640D01*
X1045905Y-2157D01*
X1046250Y-2518D01*
X1046480Y-3035D01*
X1046557Y-3500D01*
X1044947D01*
G01X1043380Y-917D02*
X1043150Y-607D01*
X1042882Y-452D01*
X1042575Y-400D01*
X1042192Y-503D01*
X1041924Y-762D01*
X1041847Y-1072D01*
X1041885Y-1382D01*
X1042039Y-1640D01*
X1042805Y-2157D01*
X1043150Y-2518D01*
X1043380Y-3035D01*
X1043457Y-3500D01*
X1041847D01*
G01X1049080Y75083D02*
X1048850Y75393D01*
X1048582Y75548D01*
X1048275Y75600D01*
X1047892Y75497D01*
X1047624Y75238D01*
X1047547Y74928D01*
X1047585Y74618D01*
X1047739Y74360D01*
X1048505Y73843D01*
X1048850Y73482D01*
X1049080Y72965D01*
X1049157Y72500D01*
X1047547D01*
G01X1045980Y75083D02*
X1045750Y75393D01*
X1045482Y75548D01*
X1045175Y75600D01*
X1044792Y75497D01*
X1044524Y75238D01*
X1044447Y74928D01*
X1044485Y74618D01*
X1044639Y74360D01*
X1045405Y73843D01*
X1045750Y73482D01*
X1045980Y72965D01*
X1046057Y72500D01*
X1044447D01*
G01X1042880Y75083D02*
X1042650Y75393D01*
X1042382Y75548D01*
X1042075Y75600D01*
X1041692Y75497D01*
X1041424Y75238D01*
X1041347Y74928D01*
X1041385Y74618D01*
X1041539Y74360D01*
X1042305Y73843D01*
X1042650Y73482D01*
X1042880Y72965D01*
X1042957Y72500D01*
X1041347D01*
G01X1045929Y64500D02*
X1045852Y65172D01*
X1045737Y65740D01*
X1045584Y66257D01*
X1045392Y66825D01*
X1045085Y67600D01*
X1046619D01*
G01X1042752Y64500D02*
X1042484Y64552D01*
X1042177Y64707D01*
X1041985Y64965D01*
X1041909Y65327D01*
X1041985Y65688D01*
X1042215Y65998D01*
X1042560Y66153D01*
X1042944D01*
X1043174Y66257D01*
X1043365Y66515D01*
X1043442Y66877D01*
X1043327Y67238D01*
X1043059Y67497D01*
X1042752Y67600D01*
X1042445Y67497D01*
X1042177Y67238D01*
X1042062Y66877D01*
X1042139Y66515D01*
X1042330Y66257D01*
X1042560Y66153D01*
X1042944D01*
X1043289Y65998D01*
X1043519Y65688D01*
X1043595Y65327D01*
X1043519Y64965D01*
X1043327Y64707D01*
X1043020Y64552D01*
X1042752Y64500D01*
G01X1049580Y37083D02*
X1049350Y37393D01*
X1049082Y37548D01*
X1048775Y37600D01*
X1048392Y37497D01*
X1048124Y37238D01*
X1048047Y36928D01*
X1048085Y36618D01*
X1048239Y36360D01*
X1049005Y35843D01*
X1049350Y35482D01*
X1049580Y34965D01*
X1049657Y34500D01*
X1048047D01*
G01X1046480Y37083D02*
X1046250Y37393D01*
X1045982Y37548D01*
X1045675Y37600D01*
X1045292Y37497D01*
X1045024Y37238D01*
X1044947Y36928D01*
X1044985Y36618D01*
X1045139Y36360D01*
X1045905Y35843D01*
X1046250Y35482D01*
X1046480Y34965D01*
X1046557Y34500D01*
X1044947D01*
G01X1043380Y37083D02*
X1043150Y37393D01*
X1042882Y37548D01*
X1042575Y37600D01*
X1042192Y37497D01*
X1041924Y37238D01*
X1041847Y36928D01*
X1041885Y36618D01*
X1042039Y36360D01*
X1042805Y35843D01*
X1043150Y35482D01*
X1043380Y34965D01*
X1043457Y34500D01*
X1041847D01*
G01X1040000Y200900D02*
X1037900D01*
Y115400D01*
X1072300D01*
Y116300D01*
X1082300D01*
Y118100D01*
X1100500D01*
Y122400D01*
X1109700D01*
Y169700D01*
G01X1078692Y135617D02*
X1078817Y135367D01*
X1078900Y135075D01*
Y134742D01*
X1078775Y134367D01*
X1078567Y134075D01*
X1078317Y133867D01*
X1077900Y133700D01*
X1077525Y133658D01*
X1077150Y133742D01*
X1076900Y133867D01*
X1076650Y134117D01*
X1076483Y134408D01*
X1076400Y134700D01*
Y134992D01*
X1076483Y135283D01*
X1076608Y135533D01*
X1076775Y135742D01*
G01Y136883D02*
X1076567Y137133D01*
X1076442Y137425D01*
X1076400Y137800D01*
X1076483Y138175D01*
X1076650Y138467D01*
X1076942Y138675D01*
X1077275Y138717D01*
X1077608Y138633D01*
X1077817Y138425D01*
X1077983Y138133D01*
X1078025Y137842D01*
X1077983Y137550D01*
X1077817Y137175D01*
X1078900Y137300D01*
Y138425D01*
G01X1076400Y140067D02*
X1078900D01*
Y141067D01*
X1078775Y141400D01*
X1078483Y141650D01*
X1078150Y141733D01*
X1077817Y141650D01*
X1077567Y141442D01*
X1077442Y141067D01*
Y140067D01*
G01X1078483Y143208D02*
X1078733Y143458D01*
X1078858Y143750D01*
X1078900Y144083D01*
X1078817Y144500D01*
X1078608Y144792D01*
X1078358Y144875D01*
X1078108Y144833D01*
X1077900Y144667D01*
X1077483Y143833D01*
X1077192Y143458D01*
X1076775Y143208D01*
X1076400Y143125D01*
Y144875D01*
G01Y147100D02*
X1076442Y147392D01*
X1076567Y147725D01*
X1076775Y147933D01*
X1077067Y148017D01*
X1077358Y147933D01*
X1077608Y147683D01*
X1077733Y147308D01*
Y146892D01*
X1077817Y146642D01*
X1078025Y146433D01*
X1078317Y146350D01*
X1078608Y146475D01*
X1078817Y146767D01*
X1078900Y147100D01*
X1078817Y147433D01*
X1078608Y147725D01*
X1078317Y147850D01*
X1078025Y147767D01*
X1077817Y147558D01*
X1077733Y147308D01*
Y146892D01*
X1077608Y146517D01*
X1077358Y146267D01*
X1077067Y146183D01*
X1076775Y146267D01*
X1076567Y146475D01*
X1076442Y146808D01*
X1076400Y147100D01*
G01X1096939Y126033D02*
X1097189Y126158D01*
X1097481Y126241D01*
X1097814D01*
X1098189Y126116D01*
X1098481Y125908D01*
X1098689Y125658D01*
X1098856Y125241D01*
X1098898Y124866D01*
X1098814Y124491D01*
X1098689Y124241D01*
X1098439Y123991D01*
X1098148Y123824D01*
X1097856Y123741D01*
X1097564D01*
X1097273Y123824D01*
X1097023Y123949D01*
X1096814Y124116D01*
G01X1094256Y123741D02*
Y126241D01*
X1095798Y124449D01*
X1093714D01*
G01X1092489Y123741D02*
Y126241D01*
X1091489D01*
X1091156Y126116D01*
X1090906Y125824D01*
X1090823Y125491D01*
X1090906Y125158D01*
X1091114Y124908D01*
X1091489Y124783D01*
X1092489D01*
G01X1088556Y123741D02*
Y126241D01*
X1089056Y125741D01*
G01Y123741D02*
X1088056D01*
G01X1085456Y126241D02*
X1085789Y126158D01*
X1086039Y125949D01*
X1086206Y125699D01*
X1086331Y125366D01*
X1086373Y124991D01*
X1086331Y124616D01*
X1086206Y124283D01*
X1086039Y124033D01*
X1085789Y123824D01*
X1085456Y123741D01*
X1085123Y123824D01*
X1084873Y124033D01*
X1084706Y124283D01*
X1084581Y124616D01*
X1084539Y124991D01*
X1084581Y125366D01*
X1084706Y125699D01*
X1084873Y125949D01*
X1085123Y126158D01*
X1085456Y126241D01*
G01X1086692Y152917D02*
X1086817Y152667D01*
X1086900Y152375D01*
Y152042D01*
X1086775Y151667D01*
X1086567Y151375D01*
X1086317Y151167D01*
X1085900Y151000D01*
X1085525Y150958D01*
X1085150Y151042D01*
X1084900Y151167D01*
X1084650Y151417D01*
X1084483Y151708D01*
X1084400Y152000D01*
Y152292D01*
X1084483Y152583D01*
X1084608Y152833D01*
X1084775Y153042D01*
G01X1084400Y155600D02*
X1086900D01*
X1085108Y154058D01*
Y156142D01*
G01X1084400Y157367D02*
X1086900D01*
Y158367D01*
X1086775Y158700D01*
X1086483Y158950D01*
X1086150Y159033D01*
X1085817Y158950D01*
X1085567Y158742D01*
X1085442Y158367D01*
Y157367D01*
G01X1084775Y160383D02*
X1084567Y160633D01*
X1084442Y160925D01*
X1084400Y161300D01*
X1084483Y161675D01*
X1084650Y161967D01*
X1084942Y162175D01*
X1085275Y162217D01*
X1085608Y162133D01*
X1085817Y161925D01*
X1085983Y161633D01*
X1086025Y161342D01*
X1085983Y161050D01*
X1085817Y160675D01*
X1086900Y160800D01*
Y161925D01*
G01X1086692Y135617D02*
X1086817Y135367D01*
X1086900Y135075D01*
Y134742D01*
X1086775Y134367D01*
X1086567Y134075D01*
X1086317Y133867D01*
X1085900Y133700D01*
X1085525Y133658D01*
X1085150Y133742D01*
X1084900Y133867D01*
X1084650Y134117D01*
X1084483Y134408D01*
X1084400Y134700D01*
Y134992D01*
X1084483Y135283D01*
X1084608Y135533D01*
X1084775Y135742D01*
G01X1084400Y138300D02*
X1086900D01*
X1085108Y136758D01*
Y138842D01*
G01X1084400Y140067D02*
X1086900D01*
Y141067D01*
X1086775Y141400D01*
X1086483Y141650D01*
X1086150Y141733D01*
X1085817Y141650D01*
X1085567Y141442D01*
X1085442Y141067D01*
Y140067D01*
G01X1084692Y143292D02*
X1084483Y143583D01*
X1084400Y143917D01*
X1084483Y144250D01*
X1084733Y144542D01*
X1085108Y144750D01*
X1085483Y144833D01*
X1085942D01*
X1086317Y144750D01*
X1086650Y144542D01*
X1086817Y144292D01*
X1086900Y144000D01*
X1086817Y143667D01*
X1086650Y143417D01*
X1086400Y143250D01*
X1086067Y143167D01*
X1085775Y143250D01*
X1085483Y143458D01*
X1085317Y143708D01*
X1085275Y144000D01*
X1085358Y144333D01*
X1085567Y144583D01*
X1085942Y144833D01*
G01X1081092Y119617D02*
X1081217Y119367D01*
X1081300Y119075D01*
Y118742D01*
X1081175Y118367D01*
X1080967Y118075D01*
X1080717Y117867D01*
X1080300Y117700D01*
X1079925Y117658D01*
X1079550Y117742D01*
X1079300Y117867D01*
X1079050Y118117D01*
X1078883Y118408D01*
X1078800Y118700D01*
Y118992D01*
X1078883Y119283D01*
X1079008Y119533D01*
X1079175Y119742D01*
G01Y120883D02*
X1078967Y121133D01*
X1078842Y121425D01*
X1078800Y121800D01*
X1078883Y122175D01*
X1079050Y122467D01*
X1079342Y122675D01*
X1079675Y122717D01*
X1080008Y122633D01*
X1080217Y122425D01*
X1080383Y122133D01*
X1080425Y121842D01*
X1080383Y121550D01*
X1080217Y121175D01*
X1081300Y121300D01*
Y122425D01*
G01X1078800Y124067D02*
X1081300D01*
Y125067D01*
X1081175Y125400D01*
X1080883Y125650D01*
X1080550Y125733D01*
X1080217Y125650D01*
X1079967Y125442D01*
X1079842Y125067D01*
Y124067D01*
G01X1078800Y128500D02*
X1081300D01*
X1079508Y126958D01*
Y129042D01*
G01X1081300Y131100D02*
X1081217Y130767D01*
X1081008Y130517D01*
X1080758Y130350D01*
X1080425Y130225D01*
X1080050Y130183D01*
X1079675Y130225D01*
X1079342Y130350D01*
X1079092Y130517D01*
X1078883Y130767D01*
X1078800Y131100D01*
X1078883Y131433D01*
X1079092Y131683D01*
X1079342Y131850D01*
X1079675Y131975D01*
X1080050Y132017D01*
X1080425Y131975D01*
X1080758Y131850D01*
X1081008Y131683D01*
X1081217Y131433D01*
X1081300Y131100D01*
G01X1078692Y152917D02*
X1078817Y152667D01*
X1078900Y152375D01*
Y152042D01*
X1078775Y151667D01*
X1078567Y151375D01*
X1078317Y151167D01*
X1077900Y151000D01*
X1077525Y150958D01*
X1077150Y151042D01*
X1076900Y151167D01*
X1076650Y151417D01*
X1076483Y151708D01*
X1076400Y152000D01*
Y152292D01*
X1076483Y152583D01*
X1076608Y152833D01*
X1076775Y153042D01*
G01Y154183D02*
X1076567Y154433D01*
X1076442Y154725D01*
X1076400Y155100D01*
X1076483Y155475D01*
X1076650Y155767D01*
X1076942Y155975D01*
X1077275Y156017D01*
X1077608Y155933D01*
X1077817Y155725D01*
X1077983Y155433D01*
X1078025Y155142D01*
X1077983Y154850D01*
X1077817Y154475D01*
X1078900Y154600D01*
Y155725D01*
G01X1076400Y157367D02*
X1078900D01*
Y158367D01*
X1078775Y158700D01*
X1078483Y158950D01*
X1078150Y159033D01*
X1077817Y158950D01*
X1077567Y158742D01*
X1077442Y158367D01*
Y157367D01*
G01X1076400Y161300D02*
X1078900D01*
X1078400Y160800D01*
G01X1076400D02*
Y161800D01*
G01Y164400D02*
X1076442Y164692D01*
X1076567Y165025D01*
X1076775Y165233D01*
X1077067Y165317D01*
X1077358Y165233D01*
X1077608Y164983D01*
X1077733Y164608D01*
Y164192D01*
X1077817Y163942D01*
X1078025Y163733D01*
X1078317Y163650D01*
X1078608Y163775D01*
X1078817Y164067D01*
X1078900Y164400D01*
X1078817Y164733D01*
X1078608Y165025D01*
X1078317Y165150D01*
X1078025Y165067D01*
X1077817Y164858D01*
X1077733Y164608D01*
Y164192D01*
X1077608Y163817D01*
X1077358Y163567D01*
X1077067Y163483D01*
X1076775Y163567D01*
X1076567Y163775D01*
X1076442Y164108D01*
X1076400Y164400D01*
G01X1082692Y152917D02*
X1082817Y152667D01*
X1082900Y152375D01*
Y152042D01*
X1082775Y151667D01*
X1082567Y151375D01*
X1082317Y151167D01*
X1081900Y151000D01*
X1081525Y150958D01*
X1081150Y151042D01*
X1080900Y151167D01*
X1080650Y151417D01*
X1080483Y151708D01*
X1080400Y152000D01*
Y152292D01*
X1080483Y152583D01*
X1080608Y152833D01*
X1080775Y153042D01*
G01X1080400Y155600D02*
X1082900D01*
X1081108Y154058D01*
Y156142D01*
G01X1080400Y157367D02*
X1082900D01*
Y158367D01*
X1082775Y158700D01*
X1082483Y158950D01*
X1082150Y159033D01*
X1081817Y158950D01*
X1081567Y158742D01*
X1081442Y158367D01*
Y157367D01*
G01X1080400Y161800D02*
X1082900D01*
X1081108Y160258D01*
Y162342D01*
G01X1082692Y135617D02*
X1082817Y135367D01*
X1082900Y135075D01*
Y134742D01*
X1082775Y134367D01*
X1082567Y134075D01*
X1082317Y133867D01*
X1081900Y133700D01*
X1081525Y133658D01*
X1081150Y133742D01*
X1080900Y133867D01*
X1080650Y134117D01*
X1080483Y134408D01*
X1080400Y134700D01*
Y134992D01*
X1080483Y135283D01*
X1080608Y135533D01*
X1080775Y135742D01*
G01X1080400Y138300D02*
X1082900D01*
X1081108Y136758D01*
Y138842D01*
G01X1080400Y140067D02*
X1082900D01*
Y141067D01*
X1082775Y141400D01*
X1082483Y141650D01*
X1082150Y141733D01*
X1081817Y141650D01*
X1081567Y141442D01*
X1081442Y141067D01*
Y140067D01*
G01X1080400Y143917D02*
X1080942Y144000D01*
X1081400Y144125D01*
X1081817Y144292D01*
X1082275Y144500D01*
X1082900Y144833D01*
Y143167D01*
G01X1042692Y152917D02*
X1042817Y152667D01*
X1042900Y152375D01*
Y152042D01*
X1042775Y151667D01*
X1042567Y151375D01*
X1042317Y151167D01*
X1041900Y151000D01*
X1041525Y150958D01*
X1041150Y151042D01*
X1040900Y151167D01*
X1040650Y151417D01*
X1040483Y151708D01*
X1040400Y152000D01*
Y152292D01*
X1040483Y152583D01*
X1040608Y152833D01*
X1040775Y153042D01*
G01Y154183D02*
X1040567Y154433D01*
X1040442Y154725D01*
X1040400Y155100D01*
X1040483Y155475D01*
X1040650Y155767D01*
X1040942Y155975D01*
X1041275Y156017D01*
X1041608Y155933D01*
X1041817Y155725D01*
X1041983Y155433D01*
X1042025Y155142D01*
X1041983Y154850D01*
X1041817Y154475D01*
X1042900Y154600D01*
Y155725D01*
G01X1040400Y157367D02*
X1042900D01*
Y158367D01*
X1042775Y158700D01*
X1042483Y158950D01*
X1042150Y159033D01*
X1041817Y158950D01*
X1041567Y158742D01*
X1041442Y158367D01*
Y157367D01*
G01X1042483Y160508D02*
X1042733Y160758D01*
X1042858Y161050D01*
X1042900Y161383D01*
X1042817Y161800D01*
X1042608Y162092D01*
X1042358Y162175D01*
X1042108Y162133D01*
X1041900Y161967D01*
X1041483Y161133D01*
X1041192Y160758D01*
X1040775Y160508D01*
X1040400Y160425D01*
Y162175D01*
G01Y164317D02*
X1040942Y164400D01*
X1041400Y164525D01*
X1041817Y164692D01*
X1042275Y164900D01*
X1042900Y165233D01*
Y163567D01*
G01X1042692Y135617D02*
X1042817Y135367D01*
X1042900Y135075D01*
Y134742D01*
X1042775Y134367D01*
X1042567Y134075D01*
X1042317Y133867D01*
X1041900Y133700D01*
X1041525Y133658D01*
X1041150Y133742D01*
X1040900Y133867D01*
X1040650Y134117D01*
X1040483Y134408D01*
X1040400Y134700D01*
Y134992D01*
X1040483Y135283D01*
X1040608Y135533D01*
X1040775Y135742D01*
G01Y136883D02*
X1040567Y137133D01*
X1040442Y137425D01*
X1040400Y137800D01*
X1040483Y138175D01*
X1040650Y138467D01*
X1040942Y138675D01*
X1041275Y138717D01*
X1041608Y138633D01*
X1041817Y138425D01*
X1041983Y138133D01*
X1042025Y137842D01*
X1041983Y137550D01*
X1041817Y137175D01*
X1042900Y137300D01*
Y138425D01*
G01X1040400Y140067D02*
X1042900D01*
Y141067D01*
X1042775Y141400D01*
X1042483Y141650D01*
X1042150Y141733D01*
X1041817Y141650D01*
X1041567Y141442D01*
X1041442Y141067D01*
Y140067D01*
G01X1040900Y143083D02*
X1040608Y143333D01*
X1040442Y143667D01*
X1040400Y144042D01*
X1040442Y144375D01*
X1040650Y144708D01*
X1040900Y144917D01*
X1041150Y144958D01*
X1041442Y144875D01*
X1041650Y144583D01*
X1041733Y144292D01*
Y143917D01*
G01Y144292D02*
X1041858Y144542D01*
X1042067Y144750D01*
X1042317Y144833D01*
X1042567Y144750D01*
X1042775Y144542D01*
X1042900Y144167D01*
X1042858Y143792D01*
X1042692Y143417D01*
G01X1040400Y147017D02*
X1040942Y147100D01*
X1041400Y147225D01*
X1041817Y147392D01*
X1042275Y147600D01*
X1042900Y147933D01*
Y146267D01*
G01X1046692Y152917D02*
X1046817Y152667D01*
X1046900Y152375D01*
Y152042D01*
X1046775Y151667D01*
X1046567Y151375D01*
X1046317Y151167D01*
X1045900Y151000D01*
X1045525Y150958D01*
X1045150Y151042D01*
X1044900Y151167D01*
X1044650Y151417D01*
X1044483Y151708D01*
X1044400Y152000D01*
Y152292D01*
X1044483Y152583D01*
X1044608Y152833D01*
X1044775Y153042D01*
G01Y154183D02*
X1044567Y154433D01*
X1044442Y154725D01*
X1044400Y155100D01*
X1044483Y155475D01*
X1044650Y155767D01*
X1044942Y155975D01*
X1045275Y156017D01*
X1045608Y155933D01*
X1045817Y155725D01*
X1045983Y155433D01*
X1046025Y155142D01*
X1045983Y154850D01*
X1045817Y154475D01*
X1046900Y154600D01*
Y155725D01*
G01X1044400Y157367D02*
X1046900D01*
Y158367D01*
X1046775Y158700D01*
X1046483Y158950D01*
X1046150Y159033D01*
X1045817Y158950D01*
X1045567Y158742D01*
X1045442Y158367D01*
Y157367D01*
G01X1046483Y160508D02*
X1046733Y160758D01*
X1046858Y161050D01*
X1046900Y161383D01*
X1046817Y161800D01*
X1046608Y162092D01*
X1046358Y162175D01*
X1046108Y162133D01*
X1045900Y161967D01*
X1045483Y161133D01*
X1045192Y160758D01*
X1044775Y160508D01*
X1044400Y160425D01*
Y162175D01*
G01X1045442Y163608D02*
X1045733Y163900D01*
X1045900Y164150D01*
X1045983Y164483D01*
X1045900Y164775D01*
X1045733Y164983D01*
X1045483Y165150D01*
X1045192Y165192D01*
X1044942Y165150D01*
X1044692Y164983D01*
X1044483Y164733D01*
X1044400Y164442D01*
X1044483Y164108D01*
X1044733Y163817D01*
X1045108Y163650D01*
X1045525Y163608D01*
X1046067Y163692D01*
X1046358Y163817D01*
X1046650Y164025D01*
X1046858Y164317D01*
X1046900Y164608D01*
X1046817Y164900D01*
X1046608Y165108D01*
G01X1046692Y135617D02*
X1046817Y135367D01*
X1046900Y135075D01*
Y134742D01*
X1046775Y134367D01*
X1046567Y134075D01*
X1046317Y133867D01*
X1045900Y133700D01*
X1045525Y133658D01*
X1045150Y133742D01*
X1044900Y133867D01*
X1044650Y134117D01*
X1044483Y134408D01*
X1044400Y134700D01*
Y134992D01*
X1044483Y135283D01*
X1044608Y135533D01*
X1044775Y135742D01*
G01Y136883D02*
X1044567Y137133D01*
X1044442Y137425D01*
X1044400Y137800D01*
X1044483Y138175D01*
X1044650Y138467D01*
X1044942Y138675D01*
X1045275Y138717D01*
X1045608Y138633D01*
X1045817Y138425D01*
X1045983Y138133D01*
X1046025Y137842D01*
X1045983Y137550D01*
X1045817Y137175D01*
X1046900Y137300D01*
Y138425D01*
G01X1044400Y140067D02*
X1046900D01*
Y141067D01*
X1046775Y141400D01*
X1046483Y141650D01*
X1046150Y141733D01*
X1045817Y141650D01*
X1045567Y141442D01*
X1045442Y141067D01*
Y140067D01*
G01X1044900Y143083D02*
X1044608Y143333D01*
X1044442Y143667D01*
X1044400Y144042D01*
X1044442Y144375D01*
X1044650Y144708D01*
X1044900Y144917D01*
X1045150Y144958D01*
X1045442Y144875D01*
X1045650Y144583D01*
X1045733Y144292D01*
Y143917D01*
G01Y144292D02*
X1045858Y144542D01*
X1046067Y144750D01*
X1046317Y144833D01*
X1046567Y144750D01*
X1046775Y144542D01*
X1046900Y144167D01*
X1046858Y143792D01*
X1046692Y143417D01*
G01X1045442Y146308D02*
X1045733Y146600D01*
X1045900Y146850D01*
X1045983Y147183D01*
X1045900Y147475D01*
X1045733Y147683D01*
X1045483Y147850D01*
X1045192Y147892D01*
X1044942Y147850D01*
X1044692Y147683D01*
X1044483Y147433D01*
X1044400Y147142D01*
X1044483Y146808D01*
X1044733Y146517D01*
X1045108Y146350D01*
X1045525Y146308D01*
X1046067Y146392D01*
X1046358Y146517D01*
X1046650Y146725D01*
X1046858Y147017D01*
X1046900Y147308D01*
X1046817Y147600D01*
X1046608Y147808D01*
G01X1077092Y119617D02*
X1077217Y119367D01*
X1077300Y119075D01*
Y118742D01*
X1077175Y118367D01*
X1076967Y118075D01*
X1076717Y117867D01*
X1076300Y117700D01*
X1075925Y117658D01*
X1075550Y117742D01*
X1075300Y117867D01*
X1075050Y118117D01*
X1074883Y118408D01*
X1074800Y118700D01*
Y118992D01*
X1074883Y119283D01*
X1075008Y119533D01*
X1075175Y119742D01*
G01Y120883D02*
X1074967Y121133D01*
X1074842Y121425D01*
X1074800Y121800D01*
X1074883Y122175D01*
X1075050Y122467D01*
X1075342Y122675D01*
X1075675Y122717D01*
X1076008Y122633D01*
X1076217Y122425D01*
X1076383Y122133D01*
X1076425Y121842D01*
X1076383Y121550D01*
X1076217Y121175D01*
X1077300Y121300D01*
Y122425D01*
G01X1074800Y124067D02*
X1077300D01*
Y125067D01*
X1077175Y125400D01*
X1076883Y125650D01*
X1076550Y125733D01*
X1076217Y125650D01*
X1075967Y125442D01*
X1075842Y125067D01*
Y124067D01*
G01X1074800Y128500D02*
X1077300D01*
X1075508Y126958D01*
Y129042D01*
G01X1074800Y131100D02*
X1077300D01*
X1076800Y130600D01*
G01X1074800D02*
Y131600D01*
G01X1074692Y152917D02*
X1074817Y152667D01*
X1074900Y152375D01*
Y152042D01*
X1074775Y151667D01*
X1074567Y151375D01*
X1074317Y151167D01*
X1073900Y151000D01*
X1073525Y150958D01*
X1073150Y151042D01*
X1072900Y151167D01*
X1072650Y151417D01*
X1072483Y151708D01*
X1072400Y152000D01*
Y152292D01*
X1072483Y152583D01*
X1072608Y152833D01*
X1072775Y153042D01*
G01Y154183D02*
X1072567Y154433D01*
X1072442Y154725D01*
X1072400Y155100D01*
X1072483Y155475D01*
X1072650Y155767D01*
X1072942Y155975D01*
X1073275Y156017D01*
X1073608Y155933D01*
X1073817Y155725D01*
X1073983Y155433D01*
X1074025Y155142D01*
X1073983Y154850D01*
X1073817Y154475D01*
X1074900Y154600D01*
Y155725D01*
G01X1072400Y157367D02*
X1074900D01*
Y158367D01*
X1074775Y158700D01*
X1074483Y158950D01*
X1074150Y159033D01*
X1073817Y158950D01*
X1073567Y158742D01*
X1073442Y158367D01*
Y157367D01*
G01X1072400Y161300D02*
X1074900D01*
X1074400Y160800D01*
G01X1072400D02*
Y161800D01*
G01X1072692Y163692D02*
X1072483Y163983D01*
X1072400Y164317D01*
X1072483Y164650D01*
X1072733Y164942D01*
X1073108Y165150D01*
X1073483Y165233D01*
X1073942D01*
X1074317Y165150D01*
X1074650Y164942D01*
X1074817Y164692D01*
X1074900Y164400D01*
X1074817Y164067D01*
X1074650Y163817D01*
X1074400Y163650D01*
X1074067Y163567D01*
X1073775Y163650D01*
X1073483Y163858D01*
X1073317Y164108D01*
X1073275Y164400D01*
X1073358Y164733D01*
X1073567Y164983D01*
X1073942Y165233D01*
G01X1074692Y135617D02*
X1074817Y135367D01*
X1074900Y135075D01*
Y134742D01*
X1074775Y134367D01*
X1074567Y134075D01*
X1074317Y133867D01*
X1073900Y133700D01*
X1073525Y133658D01*
X1073150Y133742D01*
X1072900Y133867D01*
X1072650Y134117D01*
X1072483Y134408D01*
X1072400Y134700D01*
Y134992D01*
X1072483Y135283D01*
X1072608Y135533D01*
X1072775Y135742D01*
G01Y136883D02*
X1072567Y137133D01*
X1072442Y137425D01*
X1072400Y137800D01*
X1072483Y138175D01*
X1072650Y138467D01*
X1072942Y138675D01*
X1073275Y138717D01*
X1073608Y138633D01*
X1073817Y138425D01*
X1073983Y138133D01*
X1074025Y137842D01*
X1073983Y137550D01*
X1073817Y137175D01*
X1074900Y137300D01*
Y138425D01*
G01X1072400Y140067D02*
X1074900D01*
Y141067D01*
X1074775Y141400D01*
X1074483Y141650D01*
X1074150Y141733D01*
X1073817Y141650D01*
X1073567Y141442D01*
X1073442Y141067D01*
Y140067D01*
G01X1074483Y143208D02*
X1074733Y143458D01*
X1074858Y143750D01*
X1074900Y144083D01*
X1074817Y144500D01*
X1074608Y144792D01*
X1074358Y144875D01*
X1074108Y144833D01*
X1073900Y144667D01*
X1073483Y143833D01*
X1073192Y143458D01*
X1072775Y143208D01*
X1072400Y143125D01*
Y144875D01*
G01X1072692Y146392D02*
X1072483Y146683D01*
X1072400Y147017D01*
X1072483Y147350D01*
X1072733Y147642D01*
X1073108Y147850D01*
X1073483Y147933D01*
X1073942D01*
X1074317Y147850D01*
X1074650Y147642D01*
X1074817Y147392D01*
X1074900Y147100D01*
X1074817Y146767D01*
X1074650Y146517D01*
X1074400Y146350D01*
X1074067Y146267D01*
X1073775Y146350D01*
X1073483Y146558D01*
X1073317Y146808D01*
X1073275Y147100D01*
X1073358Y147433D01*
X1073567Y147683D01*
X1073942Y147933D01*
G01X1073092Y119617D02*
X1073217Y119367D01*
X1073300Y119075D01*
Y118742D01*
X1073175Y118367D01*
X1072967Y118075D01*
X1072717Y117867D01*
X1072300Y117700D01*
X1071925Y117658D01*
X1071550Y117742D01*
X1071300Y117867D01*
X1071050Y118117D01*
X1070883Y118408D01*
X1070800Y118700D01*
Y118992D01*
X1070883Y119283D01*
X1071008Y119533D01*
X1071175Y119742D01*
G01Y120883D02*
X1070967Y121133D01*
X1070842Y121425D01*
X1070800Y121800D01*
X1070883Y122175D01*
X1071050Y122467D01*
X1071342Y122675D01*
X1071675Y122717D01*
X1072008Y122633D01*
X1072217Y122425D01*
X1072383Y122133D01*
X1072425Y121842D01*
X1072383Y121550D01*
X1072217Y121175D01*
X1073300Y121300D01*
Y122425D01*
G01X1070800Y124067D02*
X1073300D01*
Y125067D01*
X1073175Y125400D01*
X1072883Y125650D01*
X1072550Y125733D01*
X1072217Y125650D01*
X1071967Y125442D01*
X1071842Y125067D01*
Y124067D01*
G01X1070800Y128500D02*
X1073300D01*
X1071508Y126958D01*
Y129042D01*
G01X1072883Y130308D02*
X1073133Y130558D01*
X1073258Y130850D01*
X1073300Y131183D01*
X1073217Y131600D01*
X1073008Y131892D01*
X1072758Y131975D01*
X1072508Y131933D01*
X1072300Y131767D01*
X1071883Y130933D01*
X1071592Y130558D01*
X1071175Y130308D01*
X1070800Y130225D01*
Y131975D01*
G01X1070692Y152917D02*
X1070817Y152667D01*
X1070900Y152375D01*
Y152042D01*
X1070775Y151667D01*
X1070567Y151375D01*
X1070317Y151167D01*
X1069900Y151000D01*
X1069525Y150958D01*
X1069150Y151042D01*
X1068900Y151167D01*
X1068650Y151417D01*
X1068483Y151708D01*
X1068400Y152000D01*
Y152292D01*
X1068483Y152583D01*
X1068608Y152833D01*
X1068775Y153042D01*
G01Y154183D02*
X1068567Y154433D01*
X1068442Y154725D01*
X1068400Y155100D01*
X1068483Y155475D01*
X1068650Y155767D01*
X1068942Y155975D01*
X1069275Y156017D01*
X1069608Y155933D01*
X1069817Y155725D01*
X1069983Y155433D01*
X1070025Y155142D01*
X1069983Y154850D01*
X1069817Y154475D01*
X1070900Y154600D01*
Y155725D01*
G01X1068400Y157367D02*
X1070900D01*
Y158367D01*
X1070775Y158700D01*
X1070483Y158950D01*
X1070150Y159033D01*
X1069817Y158950D01*
X1069567Y158742D01*
X1069442Y158367D01*
Y157367D01*
G01X1070483Y160508D02*
X1070733Y160758D01*
X1070858Y161050D01*
X1070900Y161383D01*
X1070817Y161800D01*
X1070608Y162092D01*
X1070358Y162175D01*
X1070108Y162133D01*
X1069900Y161967D01*
X1069483Y161133D01*
X1069192Y160758D01*
X1068775Y160508D01*
X1068400Y160425D01*
Y162175D01*
G01X1070900Y164400D02*
X1070817Y164067D01*
X1070608Y163817D01*
X1070358Y163650D01*
X1070025Y163525D01*
X1069650Y163483D01*
X1069275Y163525D01*
X1068942Y163650D01*
X1068692Y163817D01*
X1068483Y164067D01*
X1068400Y164400D01*
X1068483Y164733D01*
X1068692Y164983D01*
X1068942Y165150D01*
X1069275Y165275D01*
X1069650Y165317D01*
X1070025Y165275D01*
X1070358Y165150D01*
X1070608Y164983D01*
X1070817Y164733D01*
X1070900Y164400D01*
G01X1070692Y135617D02*
X1070817Y135367D01*
X1070900Y135075D01*
Y134742D01*
X1070775Y134367D01*
X1070567Y134075D01*
X1070317Y133867D01*
X1069900Y133700D01*
X1069525Y133658D01*
X1069150Y133742D01*
X1068900Y133867D01*
X1068650Y134117D01*
X1068483Y134408D01*
X1068400Y134700D01*
Y134992D01*
X1068483Y135283D01*
X1068608Y135533D01*
X1068775Y135742D01*
G01Y136883D02*
X1068567Y137133D01*
X1068442Y137425D01*
X1068400Y137800D01*
X1068483Y138175D01*
X1068650Y138467D01*
X1068942Y138675D01*
X1069275Y138717D01*
X1069608Y138633D01*
X1069817Y138425D01*
X1069983Y138133D01*
X1070025Y137842D01*
X1069983Y137550D01*
X1069817Y137175D01*
X1070900Y137300D01*
Y138425D01*
G01X1068400Y140067D02*
X1070900D01*
Y141067D01*
X1070775Y141400D01*
X1070483Y141650D01*
X1070150Y141733D01*
X1069817Y141650D01*
X1069567Y141442D01*
X1069442Y141067D01*
Y140067D01*
G01X1068900Y143083D02*
X1068608Y143333D01*
X1068442Y143667D01*
X1068400Y144042D01*
X1068442Y144375D01*
X1068650Y144708D01*
X1068900Y144917D01*
X1069150Y144958D01*
X1069442Y144875D01*
X1069650Y144583D01*
X1069733Y144292D01*
Y143917D01*
G01Y144292D02*
X1069858Y144542D01*
X1070067Y144750D01*
X1070317Y144833D01*
X1070567Y144750D01*
X1070775Y144542D01*
X1070900Y144167D01*
X1070858Y143792D01*
X1070692Y143417D01*
G01X1070900Y147100D02*
X1070817Y146767D01*
X1070608Y146517D01*
X1070358Y146350D01*
X1070025Y146225D01*
X1069650Y146183D01*
X1069275Y146225D01*
X1068942Y146350D01*
X1068692Y146517D01*
X1068483Y146767D01*
X1068400Y147100D01*
X1068483Y147433D01*
X1068692Y147683D01*
X1068942Y147850D01*
X1069275Y147975D01*
X1069650Y148017D01*
X1070025Y147975D01*
X1070358Y147850D01*
X1070608Y147683D01*
X1070817Y147433D01*
X1070900Y147100D01*
G01X1054692Y135617D02*
X1054817Y135367D01*
X1054900Y135075D01*
Y134742D01*
X1054775Y134367D01*
X1054567Y134075D01*
X1054317Y133867D01*
X1053900Y133700D01*
X1053525Y133658D01*
X1053150Y133742D01*
X1052900Y133867D01*
X1052650Y134117D01*
X1052483Y134408D01*
X1052400Y134700D01*
Y134992D01*
X1052483Y135283D01*
X1052608Y135533D01*
X1052775Y135742D01*
G01Y136883D02*
X1052567Y137133D01*
X1052442Y137425D01*
X1052400Y137800D01*
X1052483Y138175D01*
X1052650Y138467D01*
X1052942Y138675D01*
X1053275Y138717D01*
X1053608Y138633D01*
X1053817Y138425D01*
X1053983Y138133D01*
X1054025Y137842D01*
X1053983Y137550D01*
X1053817Y137175D01*
X1054900Y137300D01*
Y138425D01*
G01X1052400Y140067D02*
X1054900D01*
Y141067D01*
X1054775Y141400D01*
X1054483Y141650D01*
X1054150Y141733D01*
X1053817Y141650D01*
X1053567Y141442D01*
X1053442Y141067D01*
Y140067D01*
G01X1052900Y143083D02*
X1052608Y143333D01*
X1052442Y143667D01*
X1052400Y144042D01*
X1052442Y144375D01*
X1052650Y144708D01*
X1052900Y144917D01*
X1053150Y144958D01*
X1053442Y144875D01*
X1053650Y144583D01*
X1053733Y144292D01*
Y143917D01*
G01Y144292D02*
X1053858Y144542D01*
X1054067Y144750D01*
X1054317Y144833D01*
X1054567Y144750D01*
X1054775Y144542D01*
X1054900Y144167D01*
X1054858Y143792D01*
X1054692Y143417D01*
G01X1052400Y147600D02*
X1054900D01*
X1053108Y146058D01*
Y148142D01*
G01X1069092Y119617D02*
X1069217Y119367D01*
X1069300Y119075D01*
Y118742D01*
X1069175Y118367D01*
X1068967Y118075D01*
X1068717Y117867D01*
X1068300Y117700D01*
X1067925Y117658D01*
X1067550Y117742D01*
X1067300Y117867D01*
X1067050Y118117D01*
X1066883Y118408D01*
X1066800Y118700D01*
Y118992D01*
X1066883Y119283D01*
X1067008Y119533D01*
X1067175Y119742D01*
G01Y120883D02*
X1066967Y121133D01*
X1066842Y121425D01*
X1066800Y121800D01*
X1066883Y122175D01*
X1067050Y122467D01*
X1067342Y122675D01*
X1067675Y122717D01*
X1068008Y122633D01*
X1068217Y122425D01*
X1068383Y122133D01*
X1068425Y121842D01*
X1068383Y121550D01*
X1068217Y121175D01*
X1069300Y121300D01*
Y122425D01*
G01X1066800Y124067D02*
X1069300D01*
Y125067D01*
X1069175Y125400D01*
X1068883Y125650D01*
X1068550Y125733D01*
X1068217Y125650D01*
X1067967Y125442D01*
X1067842Y125067D01*
Y124067D01*
G01X1066800Y128500D02*
X1069300D01*
X1067508Y126958D01*
Y129042D01*
G01X1067300Y130183D02*
X1067008Y130433D01*
X1066842Y130767D01*
X1066800Y131142D01*
X1066842Y131475D01*
X1067050Y131808D01*
X1067300Y132017D01*
X1067550Y132058D01*
X1067842Y131975D01*
X1068050Y131683D01*
X1068133Y131392D01*
Y131017D01*
G01Y131392D02*
X1068258Y131642D01*
X1068467Y131850D01*
X1068717Y131933D01*
X1068967Y131850D01*
X1069175Y131642D01*
X1069300Y131267D01*
X1069258Y130892D01*
X1069092Y130517D01*
G01X1065092Y119617D02*
X1065217Y119367D01*
X1065300Y119075D01*
Y118742D01*
X1065175Y118367D01*
X1064967Y118075D01*
X1064717Y117867D01*
X1064300Y117700D01*
X1063925Y117658D01*
X1063550Y117742D01*
X1063300Y117867D01*
X1063050Y118117D01*
X1062883Y118408D01*
X1062800Y118700D01*
Y118992D01*
X1062883Y119283D01*
X1063008Y119533D01*
X1063175Y119742D01*
G01Y120883D02*
X1062967Y121133D01*
X1062842Y121425D01*
X1062800Y121800D01*
X1062883Y122175D01*
X1063050Y122467D01*
X1063342Y122675D01*
X1063675Y122717D01*
X1064008Y122633D01*
X1064217Y122425D01*
X1064383Y122133D01*
X1064425Y121842D01*
X1064383Y121550D01*
X1064217Y121175D01*
X1065300Y121300D01*
Y122425D01*
G01X1062800Y124067D02*
X1065300D01*
Y125067D01*
X1065175Y125400D01*
X1064883Y125650D01*
X1064550Y125733D01*
X1064217Y125650D01*
X1063967Y125442D01*
X1063842Y125067D01*
Y124067D01*
G01X1062800Y128500D02*
X1065300D01*
X1063508Y126958D01*
Y129042D01*
G01X1062800Y131600D02*
X1065300D01*
X1063508Y130058D01*
Y132142D01*
G01X1050692Y152917D02*
X1050817Y152667D01*
X1050900Y152375D01*
Y152042D01*
X1050775Y151667D01*
X1050567Y151375D01*
X1050317Y151167D01*
X1049900Y151000D01*
X1049525Y150958D01*
X1049150Y151042D01*
X1048900Y151167D01*
X1048650Y151417D01*
X1048483Y151708D01*
X1048400Y152000D01*
Y152292D01*
X1048483Y152583D01*
X1048608Y152833D01*
X1048775Y153042D01*
G01Y154183D02*
X1048567Y154433D01*
X1048442Y154725D01*
X1048400Y155100D01*
X1048483Y155475D01*
X1048650Y155767D01*
X1048942Y155975D01*
X1049275Y156017D01*
X1049608Y155933D01*
X1049817Y155725D01*
X1049983Y155433D01*
X1050025Y155142D01*
X1049983Y154850D01*
X1049817Y154475D01*
X1050900Y154600D01*
Y155725D01*
G01X1048400Y157367D02*
X1050900D01*
Y158367D01*
X1050775Y158700D01*
X1050483Y158950D01*
X1050150Y159033D01*
X1049817Y158950D01*
X1049567Y158742D01*
X1049442Y158367D01*
Y157367D01*
G01X1050483Y160508D02*
X1050733Y160758D01*
X1050858Y161050D01*
X1050900Y161383D01*
X1050817Y161800D01*
X1050608Y162092D01*
X1050358Y162175D01*
X1050108Y162133D01*
X1049900Y161967D01*
X1049483Y161133D01*
X1049192Y160758D01*
X1048775Y160508D01*
X1048400Y160425D01*
Y162175D01*
G01X1048775Y163483D02*
X1048567Y163733D01*
X1048442Y164025D01*
X1048400Y164400D01*
X1048483Y164775D01*
X1048650Y165067D01*
X1048942Y165275D01*
X1049275Y165317D01*
X1049608Y165233D01*
X1049817Y165025D01*
X1049983Y164733D01*
X1050025Y164442D01*
X1049983Y164150D01*
X1049817Y163775D01*
X1050900Y163900D01*
Y165025D01*
G01X1050692Y135617D02*
X1050817Y135367D01*
X1050900Y135075D01*
Y134742D01*
X1050775Y134367D01*
X1050567Y134075D01*
X1050317Y133867D01*
X1049900Y133700D01*
X1049525Y133658D01*
X1049150Y133742D01*
X1048900Y133867D01*
X1048650Y134117D01*
X1048483Y134408D01*
X1048400Y134700D01*
Y134992D01*
X1048483Y135283D01*
X1048608Y135533D01*
X1048775Y135742D01*
G01Y136883D02*
X1048567Y137133D01*
X1048442Y137425D01*
X1048400Y137800D01*
X1048483Y138175D01*
X1048650Y138467D01*
X1048942Y138675D01*
X1049275Y138717D01*
X1049608Y138633D01*
X1049817Y138425D01*
X1049983Y138133D01*
X1050025Y137842D01*
X1049983Y137550D01*
X1049817Y137175D01*
X1050900Y137300D01*
Y138425D01*
G01X1048400Y140067D02*
X1050900D01*
Y141067D01*
X1050775Y141400D01*
X1050483Y141650D01*
X1050150Y141733D01*
X1049817Y141650D01*
X1049567Y141442D01*
X1049442Y141067D01*
Y140067D01*
G01X1048900Y143083D02*
X1048608Y143333D01*
X1048442Y143667D01*
X1048400Y144042D01*
X1048442Y144375D01*
X1048650Y144708D01*
X1048900Y144917D01*
X1049150Y144958D01*
X1049442Y144875D01*
X1049650Y144583D01*
X1049733Y144292D01*
Y143917D01*
G01Y144292D02*
X1049858Y144542D01*
X1050067Y144750D01*
X1050317Y144833D01*
X1050567Y144750D01*
X1050775Y144542D01*
X1050900Y144167D01*
X1050858Y143792D01*
X1050692Y143417D01*
G01X1048775Y146183D02*
X1048567Y146433D01*
X1048442Y146725D01*
X1048400Y147100D01*
X1048483Y147475D01*
X1048650Y147767D01*
X1048942Y147975D01*
X1049275Y148017D01*
X1049608Y147933D01*
X1049817Y147725D01*
X1049983Y147433D01*
X1050025Y147142D01*
X1049983Y146850D01*
X1049817Y146475D01*
X1050900Y146600D01*
Y147725D01*
G01X1066692Y152917D02*
X1066817Y152667D01*
X1066900Y152375D01*
Y152042D01*
X1066775Y151667D01*
X1066567Y151375D01*
X1066317Y151167D01*
X1065900Y151000D01*
X1065525Y150958D01*
X1065150Y151042D01*
X1064900Y151167D01*
X1064650Y151417D01*
X1064483Y151708D01*
X1064400Y152000D01*
Y152292D01*
X1064483Y152583D01*
X1064608Y152833D01*
X1064775Y153042D01*
G01Y154183D02*
X1064567Y154433D01*
X1064442Y154725D01*
X1064400Y155100D01*
X1064483Y155475D01*
X1064650Y155767D01*
X1064942Y155975D01*
X1065275Y156017D01*
X1065608Y155933D01*
X1065817Y155725D01*
X1065983Y155433D01*
X1066025Y155142D01*
X1065983Y154850D01*
X1065817Y154475D01*
X1066900Y154600D01*
Y155725D01*
G01X1064400Y157367D02*
X1066900D01*
Y158367D01*
X1066775Y158700D01*
X1066483Y158950D01*
X1066150Y159033D01*
X1065817Y158950D01*
X1065567Y158742D01*
X1065442Y158367D01*
Y157367D01*
G01X1066483Y160508D02*
X1066733Y160758D01*
X1066858Y161050D01*
X1066900Y161383D01*
X1066817Y161800D01*
X1066608Y162092D01*
X1066358Y162175D01*
X1066108Y162133D01*
X1065900Y161967D01*
X1065483Y161133D01*
X1065192Y160758D01*
X1064775Y160508D01*
X1064400Y160425D01*
Y162175D01*
G01Y164400D02*
X1066900D01*
X1066400Y163900D01*
G01X1064400D02*
Y164900D01*
G01X1062692Y152917D02*
X1062817Y152667D01*
X1062900Y152375D01*
Y152042D01*
X1062775Y151667D01*
X1062567Y151375D01*
X1062317Y151167D01*
X1061900Y151000D01*
X1061525Y150958D01*
X1061150Y151042D01*
X1060900Y151167D01*
X1060650Y151417D01*
X1060483Y151708D01*
X1060400Y152000D01*
Y152292D01*
X1060483Y152583D01*
X1060608Y152833D01*
X1060775Y153042D01*
G01Y154183D02*
X1060567Y154433D01*
X1060442Y154725D01*
X1060400Y155100D01*
X1060483Y155475D01*
X1060650Y155767D01*
X1060942Y155975D01*
X1061275Y156017D01*
X1061608Y155933D01*
X1061817Y155725D01*
X1061983Y155433D01*
X1062025Y155142D01*
X1061983Y154850D01*
X1061817Y154475D01*
X1062900Y154600D01*
Y155725D01*
G01X1060400Y157367D02*
X1062900D01*
Y158367D01*
X1062775Y158700D01*
X1062483Y158950D01*
X1062150Y159033D01*
X1061817Y158950D01*
X1061567Y158742D01*
X1061442Y158367D01*
Y157367D01*
G01X1062483Y160508D02*
X1062733Y160758D01*
X1062858Y161050D01*
X1062900Y161383D01*
X1062817Y161800D01*
X1062608Y162092D01*
X1062358Y162175D01*
X1062108Y162133D01*
X1061900Y161967D01*
X1061483Y161133D01*
X1061192Y160758D01*
X1060775Y160508D01*
X1060400Y160425D01*
Y162175D01*
G01X1062483Y163608D02*
X1062733Y163858D01*
X1062858Y164150D01*
X1062900Y164483D01*
X1062817Y164900D01*
X1062608Y165192D01*
X1062358Y165275D01*
X1062108Y165233D01*
X1061900Y165067D01*
X1061483Y164233D01*
X1061192Y163858D01*
X1060775Y163608D01*
X1060400Y163525D01*
Y165275D01*
G01X1066692Y135617D02*
X1066817Y135367D01*
X1066900Y135075D01*
Y134742D01*
X1066775Y134367D01*
X1066567Y134075D01*
X1066317Y133867D01*
X1065900Y133700D01*
X1065525Y133658D01*
X1065150Y133742D01*
X1064900Y133867D01*
X1064650Y134117D01*
X1064483Y134408D01*
X1064400Y134700D01*
Y134992D01*
X1064483Y135283D01*
X1064608Y135533D01*
X1064775Y135742D01*
G01Y136883D02*
X1064567Y137133D01*
X1064442Y137425D01*
X1064400Y137800D01*
X1064483Y138175D01*
X1064650Y138467D01*
X1064942Y138675D01*
X1065275Y138717D01*
X1065608Y138633D01*
X1065817Y138425D01*
X1065983Y138133D01*
X1066025Y137842D01*
X1065983Y137550D01*
X1065817Y137175D01*
X1066900Y137300D01*
Y138425D01*
G01X1064400Y140067D02*
X1066900D01*
Y141067D01*
X1066775Y141400D01*
X1066483Y141650D01*
X1066150Y141733D01*
X1065817Y141650D01*
X1065567Y141442D01*
X1065442Y141067D01*
Y140067D01*
G01X1064900Y143083D02*
X1064608Y143333D01*
X1064442Y143667D01*
X1064400Y144042D01*
X1064442Y144375D01*
X1064650Y144708D01*
X1064900Y144917D01*
X1065150Y144958D01*
X1065442Y144875D01*
X1065650Y144583D01*
X1065733Y144292D01*
Y143917D01*
G01Y144292D02*
X1065858Y144542D01*
X1066067Y144750D01*
X1066317Y144833D01*
X1066567Y144750D01*
X1066775Y144542D01*
X1066900Y144167D01*
X1066858Y143792D01*
X1066692Y143417D01*
G01X1064400Y147100D02*
X1066900D01*
X1066400Y146600D01*
G01X1064400D02*
Y147600D01*
G01X1062692Y135617D02*
X1062817Y135367D01*
X1062900Y135075D01*
Y134742D01*
X1062775Y134367D01*
X1062567Y134075D01*
X1062317Y133867D01*
X1061900Y133700D01*
X1061525Y133658D01*
X1061150Y133742D01*
X1060900Y133867D01*
X1060650Y134117D01*
X1060483Y134408D01*
X1060400Y134700D01*
Y134992D01*
X1060483Y135283D01*
X1060608Y135533D01*
X1060775Y135742D01*
G01Y136883D02*
X1060567Y137133D01*
X1060442Y137425D01*
X1060400Y137800D01*
X1060483Y138175D01*
X1060650Y138467D01*
X1060942Y138675D01*
X1061275Y138717D01*
X1061608Y138633D01*
X1061817Y138425D01*
X1061983Y138133D01*
X1062025Y137842D01*
X1061983Y137550D01*
X1061817Y137175D01*
X1062900Y137300D01*
Y138425D01*
G01X1060400Y140067D02*
X1062900D01*
Y141067D01*
X1062775Y141400D01*
X1062483Y141650D01*
X1062150Y141733D01*
X1061817Y141650D01*
X1061567Y141442D01*
X1061442Y141067D01*
Y140067D01*
G01X1060900Y143083D02*
X1060608Y143333D01*
X1060442Y143667D01*
X1060400Y144042D01*
X1060442Y144375D01*
X1060650Y144708D01*
X1060900Y144917D01*
X1061150Y144958D01*
X1061442Y144875D01*
X1061650Y144583D01*
X1061733Y144292D01*
Y143917D01*
G01Y144292D02*
X1061858Y144542D01*
X1062067Y144750D01*
X1062317Y144833D01*
X1062567Y144750D01*
X1062775Y144542D01*
X1062900Y144167D01*
X1062858Y143792D01*
X1062692Y143417D01*
G01X1062483Y146308D02*
X1062733Y146558D01*
X1062858Y146850D01*
X1062900Y147183D01*
X1062817Y147600D01*
X1062608Y147892D01*
X1062358Y147975D01*
X1062108Y147933D01*
X1061900Y147767D01*
X1061483Y146933D01*
X1061192Y146558D01*
X1060775Y146308D01*
X1060400Y146225D01*
Y147975D01*
G01X1061092Y119617D02*
X1061217Y119367D01*
X1061300Y119075D01*
Y118742D01*
X1061175Y118367D01*
X1060967Y118075D01*
X1060717Y117867D01*
X1060300Y117700D01*
X1059925Y117658D01*
X1059550Y117742D01*
X1059300Y117867D01*
X1059050Y118117D01*
X1058883Y118408D01*
X1058800Y118700D01*
Y118992D01*
X1058883Y119283D01*
X1059008Y119533D01*
X1059175Y119742D01*
G01Y120883D02*
X1058967Y121133D01*
X1058842Y121425D01*
X1058800Y121800D01*
X1058883Y122175D01*
X1059050Y122467D01*
X1059342Y122675D01*
X1059675Y122717D01*
X1060008Y122633D01*
X1060217Y122425D01*
X1060383Y122133D01*
X1060425Y121842D01*
X1060383Y121550D01*
X1060217Y121175D01*
X1061300Y121300D01*
Y122425D01*
G01X1058800Y124067D02*
X1061300D01*
Y125067D01*
X1061175Y125400D01*
X1060883Y125650D01*
X1060550Y125733D01*
X1060217Y125650D01*
X1059967Y125442D01*
X1059842Y125067D01*
Y124067D01*
G01X1059300Y127083D02*
X1059008Y127333D01*
X1058842Y127667D01*
X1058800Y128042D01*
X1058842Y128375D01*
X1059050Y128708D01*
X1059300Y128917D01*
X1059550Y128958D01*
X1059842Y128875D01*
X1060050Y128583D01*
X1060133Y128292D01*
Y127917D01*
G01Y128292D02*
X1060258Y128542D01*
X1060467Y128750D01*
X1060717Y128833D01*
X1060967Y128750D01*
X1061175Y128542D01*
X1061300Y128167D01*
X1061258Y127792D01*
X1061092Y127417D01*
G01X1059092Y130392D02*
X1058883Y130683D01*
X1058800Y131017D01*
X1058883Y131350D01*
X1059133Y131642D01*
X1059508Y131850D01*
X1059883Y131933D01*
X1060342D01*
X1060717Y131850D01*
X1061050Y131642D01*
X1061217Y131392D01*
X1061300Y131100D01*
X1061217Y130767D01*
X1061050Y130517D01*
X1060800Y130350D01*
X1060467Y130267D01*
X1060175Y130350D01*
X1059883Y130558D01*
X1059717Y130808D01*
X1059675Y131100D01*
X1059758Y131433D01*
X1059967Y131683D01*
X1060342Y131933D01*
G01X1055039Y119833D02*
X1055289Y119958D01*
X1055581Y120041D01*
X1055914D01*
X1056289Y119916D01*
X1056581Y119708D01*
X1056789Y119458D01*
X1056956Y119041D01*
X1056998Y118666D01*
X1056914Y118291D01*
X1056789Y118041D01*
X1056539Y117791D01*
X1056248Y117624D01*
X1055956Y117541D01*
X1055664D01*
X1055373Y117624D01*
X1055123Y117749D01*
X1054914Y117916D01*
G01X1053773D02*
X1053523Y117708D01*
X1053231Y117583D01*
X1052856Y117541D01*
X1052481Y117624D01*
X1052189Y117791D01*
X1051981Y118083D01*
X1051939Y118416D01*
X1052023Y118749D01*
X1052231Y118958D01*
X1052523Y119124D01*
X1052814Y119166D01*
X1053106Y119124D01*
X1053481Y118958D01*
X1053356Y120041D01*
X1052231D01*
G01X1050589Y117541D02*
Y120041D01*
X1049589D01*
X1049256Y119916D01*
X1049006Y119624D01*
X1048923Y119291D01*
X1049006Y118958D01*
X1049214Y118708D01*
X1049589Y118583D01*
X1050589D01*
G01X1047573Y118041D02*
X1047323Y117749D01*
X1046989Y117583D01*
X1046614Y117541D01*
X1046281Y117583D01*
X1045948Y117791D01*
X1045739Y118041D01*
X1045698Y118291D01*
X1045781Y118583D01*
X1046073Y118791D01*
X1046364Y118874D01*
X1046739D01*
G01X1046364D02*
X1046114Y118999D01*
X1045906Y119208D01*
X1045823Y119458D01*
X1045906Y119708D01*
X1046114Y119916D01*
X1046489Y120041D01*
X1046864Y119999D01*
X1047239Y119833D01*
G01X1043556Y117541D02*
X1043264Y117583D01*
X1042931Y117708D01*
X1042723Y117916D01*
X1042639Y118208D01*
X1042723Y118499D01*
X1042973Y118749D01*
X1043348Y118874D01*
X1043764D01*
X1044014Y118958D01*
X1044223Y119166D01*
X1044306Y119458D01*
X1044181Y119749D01*
X1043889Y119958D01*
X1043556Y120041D01*
X1043223Y119958D01*
X1042931Y119749D01*
X1042806Y119458D01*
X1042889Y119166D01*
X1043098Y118958D01*
X1043348Y118874D01*
X1043764D01*
X1044139Y118749D01*
X1044389Y118499D01*
X1044473Y118208D01*
X1044389Y117916D01*
X1044181Y117708D01*
X1043848Y117583D01*
X1043556Y117541D01*
G01X1058692Y152917D02*
X1058817Y152667D01*
X1058900Y152375D01*
Y152042D01*
X1058775Y151667D01*
X1058567Y151375D01*
X1058317Y151167D01*
X1057900Y151000D01*
X1057525Y150958D01*
X1057150Y151042D01*
X1056900Y151167D01*
X1056650Y151417D01*
X1056483Y151708D01*
X1056400Y152000D01*
Y152292D01*
X1056483Y152583D01*
X1056608Y152833D01*
X1056775Y153042D01*
G01Y154183D02*
X1056567Y154433D01*
X1056442Y154725D01*
X1056400Y155100D01*
X1056483Y155475D01*
X1056650Y155767D01*
X1056942Y155975D01*
X1057275Y156017D01*
X1057608Y155933D01*
X1057817Y155725D01*
X1057983Y155433D01*
X1058025Y155142D01*
X1057983Y154850D01*
X1057817Y154475D01*
X1058900Y154600D01*
Y155725D01*
G01X1056400Y157367D02*
X1058900D01*
Y158367D01*
X1058775Y158700D01*
X1058483Y158950D01*
X1058150Y159033D01*
X1057817Y158950D01*
X1057567Y158742D01*
X1057442Y158367D01*
Y157367D01*
G01X1058483Y160508D02*
X1058733Y160758D01*
X1058858Y161050D01*
X1058900Y161383D01*
X1058817Y161800D01*
X1058608Y162092D01*
X1058358Y162175D01*
X1058108Y162133D01*
X1057900Y161967D01*
X1057483Y161133D01*
X1057192Y160758D01*
X1056775Y160508D01*
X1056400Y160425D01*
Y162175D01*
G01X1056900Y163483D02*
X1056608Y163733D01*
X1056442Y164067D01*
X1056400Y164442D01*
X1056442Y164775D01*
X1056650Y165108D01*
X1056900Y165317D01*
X1057150Y165358D01*
X1057442Y165275D01*
X1057650Y164983D01*
X1057733Y164692D01*
Y164317D01*
G01Y164692D02*
X1057858Y164942D01*
X1058067Y165150D01*
X1058317Y165233D01*
X1058567Y165150D01*
X1058775Y164942D01*
X1058900Y164567D01*
X1058858Y164192D01*
X1058692Y163817D01*
G01Y135617D02*
X1058817Y135367D01*
X1058900Y135075D01*
Y134742D01*
X1058775Y134367D01*
X1058567Y134075D01*
X1058317Y133867D01*
X1057900Y133700D01*
X1057525Y133658D01*
X1057150Y133742D01*
X1056900Y133867D01*
X1056650Y134117D01*
X1056483Y134408D01*
X1056400Y134700D01*
Y134992D01*
X1056483Y135283D01*
X1056608Y135533D01*
X1056775Y135742D01*
G01Y136883D02*
X1056567Y137133D01*
X1056442Y137425D01*
X1056400Y137800D01*
X1056483Y138175D01*
X1056650Y138467D01*
X1056942Y138675D01*
X1057275Y138717D01*
X1057608Y138633D01*
X1057817Y138425D01*
X1057983Y138133D01*
X1058025Y137842D01*
X1057983Y137550D01*
X1057817Y137175D01*
X1058900Y137300D01*
Y138425D01*
G01X1056400Y140067D02*
X1058900D01*
Y141067D01*
X1058775Y141400D01*
X1058483Y141650D01*
X1058150Y141733D01*
X1057817Y141650D01*
X1057567Y141442D01*
X1057442Y141067D01*
Y140067D01*
G01X1056900Y143083D02*
X1056608Y143333D01*
X1056442Y143667D01*
X1056400Y144042D01*
X1056442Y144375D01*
X1056650Y144708D01*
X1056900Y144917D01*
X1057150Y144958D01*
X1057442Y144875D01*
X1057650Y144583D01*
X1057733Y144292D01*
Y143917D01*
G01Y144292D02*
X1057858Y144542D01*
X1058067Y144750D01*
X1058317Y144833D01*
X1058567Y144750D01*
X1058775Y144542D01*
X1058900Y144167D01*
X1058858Y143792D01*
X1058692Y143417D01*
G01X1056900Y146183D02*
X1056608Y146433D01*
X1056442Y146767D01*
X1056400Y147142D01*
X1056442Y147475D01*
X1056650Y147808D01*
X1056900Y148017D01*
X1057150Y148058D01*
X1057442Y147975D01*
X1057650Y147683D01*
X1057733Y147392D01*
Y147017D01*
G01Y147392D02*
X1057858Y147642D01*
X1058067Y147850D01*
X1058317Y147933D01*
X1058567Y147850D01*
X1058775Y147642D01*
X1058900Y147267D01*
X1058858Y146892D01*
X1058692Y146517D01*
G01X1054692Y152917D02*
X1054817Y152667D01*
X1054900Y152375D01*
Y152042D01*
X1054775Y151667D01*
X1054567Y151375D01*
X1054317Y151167D01*
X1053900Y151000D01*
X1053525Y150958D01*
X1053150Y151042D01*
X1052900Y151167D01*
X1052650Y151417D01*
X1052483Y151708D01*
X1052400Y152000D01*
Y152292D01*
X1052483Y152583D01*
X1052608Y152833D01*
X1052775Y153042D01*
G01Y154183D02*
X1052567Y154433D01*
X1052442Y154725D01*
X1052400Y155100D01*
X1052483Y155475D01*
X1052650Y155767D01*
X1052942Y155975D01*
X1053275Y156017D01*
X1053608Y155933D01*
X1053817Y155725D01*
X1053983Y155433D01*
X1054025Y155142D01*
X1053983Y154850D01*
X1053817Y154475D01*
X1054900Y154600D01*
Y155725D01*
G01X1052400Y157367D02*
X1054900D01*
Y158367D01*
X1054775Y158700D01*
X1054483Y158950D01*
X1054150Y159033D01*
X1053817Y158950D01*
X1053567Y158742D01*
X1053442Y158367D01*
Y157367D01*
G01X1054483Y160508D02*
X1054733Y160758D01*
X1054858Y161050D01*
X1054900Y161383D01*
X1054817Y161800D01*
X1054608Y162092D01*
X1054358Y162175D01*
X1054108Y162133D01*
X1053900Y161967D01*
X1053483Y161133D01*
X1053192Y160758D01*
X1052775Y160508D01*
X1052400Y160425D01*
Y162175D01*
G01Y164900D02*
X1054900D01*
X1053108Y163358D01*
Y165442D01*
G01X1106783Y136600D02*
Y139100D01*
X1105742D01*
X1105408Y138975D01*
X1105200Y138808D01*
X1105117Y138475D01*
X1105200Y138142D01*
X1105450Y137933D01*
X1105742Y137808D01*
X1106783D01*
G01X1105742D02*
X1105117Y136600D01*
G01X1102350D02*
Y139100D01*
X1103892Y137308D01*
X1101808D01*
G01X1100583Y136600D02*
Y139100D01*
X1099583D01*
X1099250Y138975D01*
X1099000Y138683D01*
X1098917Y138350D01*
X1099000Y138017D01*
X1099208Y137767D01*
X1099583Y137642D01*
X1100583D01*
G01X1096650Y136600D02*
Y139100D01*
X1097150Y138600D01*
G01Y136600D02*
X1096150D01*
G01X1093550Y139100D02*
X1093883Y139017D01*
X1094133Y138808D01*
X1094300Y138558D01*
X1094425Y138225D01*
X1094467Y137850D01*
X1094425Y137475D01*
X1094300Y137142D01*
X1094133Y136892D01*
X1093883Y136683D01*
X1093550Y136600D01*
X1093217Y136683D01*
X1092967Y136892D01*
X1092800Y137142D01*
X1092675Y137475D01*
X1092633Y137850D01*
X1092675Y138225D01*
X1092800Y138558D01*
X1092967Y138808D01*
X1093217Y139017D01*
X1093550Y139100D01*
G01X1096933Y119700D02*
Y122200D01*
X1095892D01*
X1095558Y122075D01*
X1095350Y121908D01*
X1095267Y121575D01*
X1095350Y121242D01*
X1095600Y121033D01*
X1095892Y120908D01*
X1096933D01*
G01X1095892D02*
X1095267Y119700D01*
G01X1092500D02*
Y122200D01*
X1094042Y120408D01*
X1091958D01*
G01X1090733Y119700D02*
Y122200D01*
X1089733D01*
X1089400Y122075D01*
X1089150Y121783D01*
X1089067Y121450D01*
X1089150Y121117D01*
X1089358Y120867D01*
X1089733Y120742D01*
X1090733D01*
G01X1086800Y119700D02*
Y122200D01*
X1087300Y121700D01*
G01Y119700D02*
X1086300D01*
G01X1083783D02*
X1083700Y120242D01*
X1083575Y120700D01*
X1083408Y121117D01*
X1083200Y121575D01*
X1082867Y122200D01*
X1084533D01*
G01X1100033Y127600D02*
Y130100D01*
X1098992D01*
X1098658Y129975D01*
X1098450Y129808D01*
X1098367Y129475D01*
X1098450Y129142D01*
X1098700Y128933D01*
X1098992Y128808D01*
X1100033D01*
G01X1098992D02*
X1098367Y127600D01*
G01X1095600D02*
Y130100D01*
X1097142Y128308D01*
X1095058D01*
G01X1093833Y127600D02*
Y130100D01*
X1092833D01*
X1092500Y129975D01*
X1092250Y129683D01*
X1092167Y129350D01*
X1092250Y129017D01*
X1092458Y128767D01*
X1092833Y128642D01*
X1093833D01*
G01X1089900Y127600D02*
Y130100D01*
X1090400Y129600D01*
G01Y127600D02*
X1089400D01*
G01X1086300D02*
Y130100D01*
X1087842Y128308D01*
X1085758D01*
G01X1106783Y132600D02*
Y135100D01*
X1105742D01*
X1105408Y134975D01*
X1105200Y134808D01*
X1105117Y134475D01*
X1105200Y134142D01*
X1105450Y133933D01*
X1105742Y133808D01*
X1106783D01*
G01X1105742D02*
X1105117Y132600D01*
G01X1102350D02*
Y135100D01*
X1103892Y133308D01*
X1101808D01*
G01X1100583Y132600D02*
Y135100D01*
X1099583D01*
X1099250Y134975D01*
X1099000Y134683D01*
X1098917Y134350D01*
X1099000Y134017D01*
X1099208Y133767D01*
X1099583Y133642D01*
X1100583D01*
G01X1096650Y132600D02*
Y135100D01*
X1097150Y134600D01*
G01Y132600D02*
X1096150D01*
G01X1093550D02*
Y135100D01*
X1094050Y134600D01*
G01Y132600D02*
X1093050D01*
G01X1090692Y152917D02*
X1090817Y152667D01*
X1090900Y152375D01*
Y152042D01*
X1090775Y151667D01*
X1090567Y151375D01*
X1090317Y151167D01*
X1089900Y151000D01*
X1089525Y150958D01*
X1089150Y151042D01*
X1088900Y151167D01*
X1088650Y151417D01*
X1088483Y151708D01*
X1088400Y152000D01*
Y152292D01*
X1088483Y152583D01*
X1088608Y152833D01*
X1088775Y153042D01*
G01X1088400Y155600D02*
X1090900D01*
X1089108Y154058D01*
Y156142D01*
G01X1088400Y157367D02*
X1090900D01*
Y158367D01*
X1090775Y158700D01*
X1090483Y158950D01*
X1090150Y159033D01*
X1089817Y158950D01*
X1089567Y158742D01*
X1089442Y158367D01*
Y157367D01*
G01Y160508D02*
X1089733Y160800D01*
X1089900Y161050D01*
X1089983Y161383D01*
X1089900Y161675D01*
X1089733Y161883D01*
X1089483Y162050D01*
X1089192Y162092D01*
X1088942Y162050D01*
X1088692Y161883D01*
X1088483Y161633D01*
X1088400Y161342D01*
X1088483Y161008D01*
X1088733Y160717D01*
X1089108Y160550D01*
X1089525Y160508D01*
X1090067Y160592D01*
X1090358Y160717D01*
X1090650Y160925D01*
X1090858Y161217D01*
X1090900Y161508D01*
X1090817Y161800D01*
X1090608Y162008D01*
G01X1090692Y135617D02*
X1090817Y135367D01*
X1090900Y135075D01*
Y134742D01*
X1090775Y134367D01*
X1090567Y134075D01*
X1090317Y133867D01*
X1089900Y133700D01*
X1089525Y133658D01*
X1089150Y133742D01*
X1088900Y133867D01*
X1088650Y134117D01*
X1088483Y134408D01*
X1088400Y134700D01*
Y134992D01*
X1088483Y135283D01*
X1088608Y135533D01*
X1088775Y135742D01*
G01X1088400Y138300D02*
X1090900D01*
X1089108Y136758D01*
Y138842D01*
G01X1088400Y140067D02*
X1090900D01*
Y141067D01*
X1090775Y141400D01*
X1090483Y141650D01*
X1090150Y141733D01*
X1089817Y141650D01*
X1089567Y141442D01*
X1089442Y141067D01*
Y140067D01*
G01X1088400Y144000D02*
X1088442Y144292D01*
X1088567Y144625D01*
X1088775Y144833D01*
X1089067Y144917D01*
X1089358Y144833D01*
X1089608Y144583D01*
X1089733Y144208D01*
Y143792D01*
X1089817Y143542D01*
X1090025Y143333D01*
X1090317Y143250D01*
X1090608Y143375D01*
X1090817Y143667D01*
X1090900Y144000D01*
X1090817Y144333D01*
X1090608Y144625D01*
X1090317Y144750D01*
X1090025Y144667D01*
X1089817Y144458D01*
X1089733Y144208D01*
Y143792D01*
X1089608Y143417D01*
X1089358Y143167D01*
X1089067Y143083D01*
X1088775Y143167D01*
X1088567Y143375D01*
X1088442Y143708D01*
X1088400Y144000D01*
G01X1046277Y103047D02*
X1046200Y103719D01*
X1046085Y104287D01*
X1045932Y104804D01*
X1045740Y105372D01*
X1045433Y106147D01*
X1046967D01*
G01X1043100Y103047D02*
X1042832Y103099D01*
X1042525Y103254D01*
X1042333Y103512D01*
X1042257Y103874D01*
X1042333Y104235D01*
X1042563Y104545D01*
X1042908Y104700D01*
X1043292D01*
X1043522Y104804D01*
X1043713Y105062D01*
X1043790Y105424D01*
X1043675Y105785D01*
X1043407Y106044D01*
X1043100Y106147D01*
X1042793Y106044D01*
X1042525Y105785D01*
X1042410Y105424D01*
X1042487Y105062D01*
X1042678Y104804D01*
X1042908Y104700D01*
X1043292D01*
X1043637Y104545D01*
X1043867Y104235D01*
X1043943Y103874D01*
X1043867Y103512D01*
X1043675Y103254D01*
X1043368Y103099D01*
X1043100Y103047D01*
G01X1040000Y200900D02*
X1088100D01*
Y182800D01*
X1098500D01*
Y169700D01*
X1109700D01*
G01X1062100Y200900D02*
X1061800D01*
Y260039D01*
X1061795Y260044D01*
X1060295Y258544D01*
X1063295D01*
X1061795Y260044D01*
G01X1090892Y170067D02*
X1091017Y169817D01*
X1091100Y169525D01*
Y169192D01*
X1090975Y168817D01*
X1090767Y168525D01*
X1090517Y168317D01*
X1090100Y168150D01*
X1089725Y168108D01*
X1089350Y168192D01*
X1089100Y168317D01*
X1088850Y168567D01*
X1088683Y168858D01*
X1088600Y169150D01*
Y169442D01*
X1088683Y169733D01*
X1088808Y169983D01*
X1088975Y170192D01*
G01X1088600Y172750D02*
X1091100D01*
X1089308Y171208D01*
Y173292D01*
G01X1088600Y174517D02*
X1091100D01*
Y175517D01*
X1090975Y175850D01*
X1090683Y176100D01*
X1090350Y176183D01*
X1090017Y176100D01*
X1089767Y175892D01*
X1089642Y175517D01*
Y174517D01*
G01X1088600Y178450D02*
X1091100D01*
X1090600Y177950D01*
G01X1088600D02*
Y178950D01*
G01X1082092Y186967D02*
X1082217Y186717D01*
X1082300Y186425D01*
Y186092D01*
X1082175Y185717D01*
X1081967Y185425D01*
X1081717Y185217D01*
X1081300Y185050D01*
X1080925Y185008D01*
X1080550Y185092D01*
X1080300Y185217D01*
X1080050Y185467D01*
X1079883Y185758D01*
X1079800Y186050D01*
Y186342D01*
X1079883Y186633D01*
X1080008Y186883D01*
X1080175Y187092D01*
G01Y188233D02*
X1079967Y188483D01*
X1079842Y188775D01*
X1079800Y189150D01*
X1079883Y189525D01*
X1080050Y189817D01*
X1080342Y190025D01*
X1080675Y190067D01*
X1081008Y189983D01*
X1081217Y189775D01*
X1081383Y189483D01*
X1081425Y189192D01*
X1081383Y188900D01*
X1081217Y188525D01*
X1082300Y188650D01*
Y189775D01*
G01X1079800Y191417D02*
X1082300D01*
Y192417D01*
X1082175Y192750D01*
X1081883Y193000D01*
X1081550Y193083D01*
X1081217Y193000D01*
X1080967Y192792D01*
X1080842Y192417D01*
Y191417D01*
G01X1080300Y194433D02*
X1080008Y194683D01*
X1079842Y195017D01*
X1079800Y195392D01*
X1079842Y195725D01*
X1080050Y196058D01*
X1080300Y196267D01*
X1080550Y196308D01*
X1080842Y196225D01*
X1081050Y195933D01*
X1081133Y195642D01*
Y195267D01*
G01Y195642D02*
X1081258Y195892D01*
X1081467Y196100D01*
X1081717Y196183D01*
X1081967Y196100D01*
X1082175Y195892D01*
X1082300Y195517D01*
X1082258Y195142D01*
X1082092Y194767D01*
G01X1074892Y170067D02*
X1075017Y169817D01*
X1075100Y169525D01*
Y169192D01*
X1074975Y168817D01*
X1074767Y168525D01*
X1074517Y168317D01*
X1074100Y168150D01*
X1073725Y168108D01*
X1073350Y168192D01*
X1073100Y168317D01*
X1072850Y168567D01*
X1072683Y168858D01*
X1072600Y169150D01*
Y169442D01*
X1072683Y169733D01*
X1072808Y169983D01*
X1072975Y170192D01*
G01Y171333D02*
X1072767Y171583D01*
X1072642Y171875D01*
X1072600Y172250D01*
X1072683Y172625D01*
X1072850Y172917D01*
X1073142Y173125D01*
X1073475Y173167D01*
X1073808Y173083D01*
X1074017Y172875D01*
X1074183Y172583D01*
X1074225Y172292D01*
X1074183Y172000D01*
X1074017Y171625D01*
X1075100Y171750D01*
Y172875D01*
G01X1072600Y174517D02*
X1075100D01*
Y175517D01*
X1074975Y175850D01*
X1074683Y176100D01*
X1074350Y176183D01*
X1074017Y176100D01*
X1073767Y175892D01*
X1073642Y175517D01*
Y174517D01*
G01X1072600Y178450D02*
X1075100D01*
X1074600Y177950D01*
G01X1072600D02*
Y178950D01*
G01Y181550D02*
X1075100D01*
X1074600Y181050D01*
G01X1072600D02*
Y182050D01*
G01X1078892Y170067D02*
X1079017Y169817D01*
X1079100Y169525D01*
Y169192D01*
X1078975Y168817D01*
X1078767Y168525D01*
X1078517Y168317D01*
X1078100Y168150D01*
X1077725Y168108D01*
X1077350Y168192D01*
X1077100Y168317D01*
X1076850Y168567D01*
X1076683Y168858D01*
X1076600Y169150D01*
Y169442D01*
X1076683Y169733D01*
X1076808Y169983D01*
X1076975Y170192D01*
G01Y171333D02*
X1076767Y171583D01*
X1076642Y171875D01*
X1076600Y172250D01*
X1076683Y172625D01*
X1076850Y172917D01*
X1077142Y173125D01*
X1077475Y173167D01*
X1077808Y173083D01*
X1078017Y172875D01*
X1078183Y172583D01*
X1078225Y172292D01*
X1078183Y172000D01*
X1078017Y171625D01*
X1079100Y171750D01*
Y172875D01*
G01X1076600Y174517D02*
X1079100D01*
Y175517D01*
X1078975Y175850D01*
X1078683Y176100D01*
X1078350Y176183D01*
X1078017Y176100D01*
X1077767Y175892D01*
X1077642Y175517D01*
Y174517D01*
G01X1076600Y178450D02*
X1079100D01*
X1078600Y177950D01*
G01X1076600D02*
Y178950D01*
G01X1079100Y181550D02*
X1079017Y181217D01*
X1078808Y180967D01*
X1078558Y180800D01*
X1078225Y180675D01*
X1077850Y180633D01*
X1077475Y180675D01*
X1077142Y180800D01*
X1076892Y180967D01*
X1076683Y181217D01*
X1076600Y181550D01*
X1076683Y181883D01*
X1076892Y182133D01*
X1077142Y182300D01*
X1077475Y182425D01*
X1077850Y182467D01*
X1078225Y182425D01*
X1078558Y182300D01*
X1078808Y182133D01*
X1079017Y181883D01*
X1079100Y181550D01*
G01X1082892Y170067D02*
X1083017Y169817D01*
X1083100Y169525D01*
Y169192D01*
X1082975Y168817D01*
X1082767Y168525D01*
X1082517Y168317D01*
X1082100Y168150D01*
X1081725Y168108D01*
X1081350Y168192D01*
X1081100Y168317D01*
X1080850Y168567D01*
X1080683Y168858D01*
X1080600Y169150D01*
Y169442D01*
X1080683Y169733D01*
X1080808Y169983D01*
X1080975Y170192D01*
G01X1080600Y172750D02*
X1083100D01*
X1081308Y171208D01*
Y173292D01*
G01X1080600Y174517D02*
X1083100D01*
Y175517D01*
X1082975Y175850D01*
X1082683Y176100D01*
X1082350Y176183D01*
X1082017Y176100D01*
X1081767Y175892D01*
X1081642Y175517D01*
Y174517D01*
G01X1081100Y177533D02*
X1080808Y177783D01*
X1080642Y178117D01*
X1080600Y178492D01*
X1080642Y178825D01*
X1080850Y179158D01*
X1081100Y179367D01*
X1081350Y179408D01*
X1081642Y179325D01*
X1081850Y179033D01*
X1081933Y178742D01*
Y178367D01*
G01Y178742D02*
X1082058Y178992D01*
X1082267Y179200D01*
X1082517Y179283D01*
X1082767Y179200D01*
X1082975Y178992D01*
X1083100Y178617D01*
X1083058Y178242D01*
X1082892Y177867D01*
G01X1086892Y170067D02*
X1087017Y169817D01*
X1087100Y169525D01*
Y169192D01*
X1086975Y168817D01*
X1086767Y168525D01*
X1086517Y168317D01*
X1086100Y168150D01*
X1085725Y168108D01*
X1085350Y168192D01*
X1085100Y168317D01*
X1084850Y168567D01*
X1084683Y168858D01*
X1084600Y169150D01*
Y169442D01*
X1084683Y169733D01*
X1084808Y169983D01*
X1084975Y170192D01*
G01X1084600Y172750D02*
X1087100D01*
X1085308Y171208D01*
Y173292D01*
G01X1084600Y174517D02*
X1087100D01*
Y175517D01*
X1086975Y175850D01*
X1086683Y176100D01*
X1086350Y176183D01*
X1086017Y176100D01*
X1085767Y175892D01*
X1085642Y175517D01*
Y174517D01*
G01X1086683Y177658D02*
X1086933Y177908D01*
X1087058Y178200D01*
X1087100Y178533D01*
X1087017Y178950D01*
X1086808Y179242D01*
X1086558Y179325D01*
X1086308Y179283D01*
X1086100Y179117D01*
X1085683Y178283D01*
X1085392Y177908D01*
X1084975Y177658D01*
X1084600Y177575D01*
Y179325D01*
G01X1046892Y170067D02*
X1047017Y169817D01*
X1047100Y169525D01*
Y169192D01*
X1046975Y168817D01*
X1046767Y168525D01*
X1046517Y168317D01*
X1046100Y168150D01*
X1045725Y168108D01*
X1045350Y168192D01*
X1045100Y168317D01*
X1044850Y168567D01*
X1044683Y168858D01*
X1044600Y169150D01*
Y169442D01*
X1044683Y169733D01*
X1044808Y169983D01*
X1044975Y170192D01*
G01Y171333D02*
X1044767Y171583D01*
X1044642Y171875D01*
X1044600Y172250D01*
X1044683Y172625D01*
X1044850Y172917D01*
X1045142Y173125D01*
X1045475Y173167D01*
X1045808Y173083D01*
X1046017Y172875D01*
X1046183Y172583D01*
X1046225Y172292D01*
X1046183Y172000D01*
X1046017Y171625D01*
X1047100Y171750D01*
Y172875D01*
G01X1044600Y174517D02*
X1047100D01*
Y175517D01*
X1046975Y175850D01*
X1046683Y176100D01*
X1046350Y176183D01*
X1046017Y176100D01*
X1045767Y175892D01*
X1045642Y175517D01*
Y174517D01*
G01X1044600Y178450D02*
X1044642Y178742D01*
X1044767Y179075D01*
X1044975Y179283D01*
X1045267Y179367D01*
X1045558Y179283D01*
X1045808Y179033D01*
X1045933Y178658D01*
Y178242D01*
X1046017Y177992D01*
X1046225Y177783D01*
X1046517Y177700D01*
X1046808Y177825D01*
X1047017Y178117D01*
X1047100Y178450D01*
X1047017Y178783D01*
X1046808Y179075D01*
X1046517Y179200D01*
X1046225Y179117D01*
X1046017Y178908D01*
X1045933Y178658D01*
Y178242D01*
X1045808Y177867D01*
X1045558Y177617D01*
X1045267Y177533D01*
X1044975Y177617D01*
X1044767Y177825D01*
X1044642Y178158D01*
X1044600Y178450D01*
G01X1042892Y170067D02*
X1043017Y169817D01*
X1043100Y169525D01*
Y169192D01*
X1042975Y168817D01*
X1042767Y168525D01*
X1042517Y168317D01*
X1042100Y168150D01*
X1041725Y168108D01*
X1041350Y168192D01*
X1041100Y168317D01*
X1040850Y168567D01*
X1040683Y168858D01*
X1040600Y169150D01*
Y169442D01*
X1040683Y169733D01*
X1040808Y169983D01*
X1040975Y170192D01*
G01Y171333D02*
X1040767Y171583D01*
X1040642Y171875D01*
X1040600Y172250D01*
X1040683Y172625D01*
X1040850Y172917D01*
X1041142Y173125D01*
X1041475Y173167D01*
X1041808Y173083D01*
X1042017Y172875D01*
X1042183Y172583D01*
X1042225Y172292D01*
X1042183Y172000D01*
X1042017Y171625D01*
X1043100Y171750D01*
Y172875D01*
G01X1040600Y174517D02*
X1043100D01*
Y175517D01*
X1042975Y175850D01*
X1042683Y176100D01*
X1042350Y176183D01*
X1042017Y176100D01*
X1041767Y175892D01*
X1041642Y175517D01*
Y174517D01*
G01X1040892Y177742D02*
X1040683Y178033D01*
X1040600Y178367D01*
X1040683Y178700D01*
X1040933Y178992D01*
X1041308Y179200D01*
X1041683Y179283D01*
X1042142D01*
X1042517Y179200D01*
X1042850Y178992D01*
X1043017Y178742D01*
X1043100Y178450D01*
X1043017Y178117D01*
X1042850Y177867D01*
X1042600Y177700D01*
X1042267Y177617D01*
X1041975Y177700D01*
X1041683Y177908D01*
X1041517Y178158D01*
X1041475Y178450D01*
X1041558Y178783D01*
X1041767Y179033D01*
X1042142Y179283D01*
G01X1078092Y186967D02*
X1078217Y186717D01*
X1078300Y186425D01*
Y186092D01*
X1078175Y185717D01*
X1077967Y185425D01*
X1077717Y185217D01*
X1077300Y185050D01*
X1076925Y185008D01*
X1076550Y185092D01*
X1076300Y185217D01*
X1076050Y185467D01*
X1075883Y185758D01*
X1075800Y186050D01*
Y186342D01*
X1075883Y186633D01*
X1076008Y186883D01*
X1076175Y187092D01*
G01Y188233D02*
X1075967Y188483D01*
X1075842Y188775D01*
X1075800Y189150D01*
X1075883Y189525D01*
X1076050Y189817D01*
X1076342Y190025D01*
X1076675Y190067D01*
X1077008Y189983D01*
X1077217Y189775D01*
X1077383Y189483D01*
X1077425Y189192D01*
X1077383Y188900D01*
X1077217Y188525D01*
X1078300Y188650D01*
Y189775D01*
G01X1075800Y191417D02*
X1078300D01*
Y192417D01*
X1078175Y192750D01*
X1077883Y193000D01*
X1077550Y193083D01*
X1077217Y193000D01*
X1076967Y192792D01*
X1076842Y192417D01*
Y191417D01*
G01X1075800Y195850D02*
X1078300D01*
X1076508Y194308D01*
Y196392D01*
G01X1070892Y170067D02*
X1071017Y169817D01*
X1071100Y169525D01*
Y169192D01*
X1070975Y168817D01*
X1070767Y168525D01*
X1070517Y168317D01*
X1070100Y168150D01*
X1069725Y168108D01*
X1069350Y168192D01*
X1069100Y168317D01*
X1068850Y168567D01*
X1068683Y168858D01*
X1068600Y169150D01*
Y169442D01*
X1068683Y169733D01*
X1068808Y169983D01*
X1068975Y170192D01*
G01Y171333D02*
X1068767Y171583D01*
X1068642Y171875D01*
X1068600Y172250D01*
X1068683Y172625D01*
X1068850Y172917D01*
X1069142Y173125D01*
X1069475Y173167D01*
X1069808Y173083D01*
X1070017Y172875D01*
X1070183Y172583D01*
X1070225Y172292D01*
X1070183Y172000D01*
X1070017Y171625D01*
X1071100Y171750D01*
Y172875D01*
G01X1068600Y174517D02*
X1071100D01*
Y175517D01*
X1070975Y175850D01*
X1070683Y176100D01*
X1070350Y176183D01*
X1070017Y176100D01*
X1069767Y175892D01*
X1069642Y175517D01*
Y174517D01*
G01X1068600Y178450D02*
X1071100D01*
X1070600Y177950D01*
G01X1068600D02*
Y178950D01*
G01X1070683Y180758D02*
X1070933Y181008D01*
X1071058Y181300D01*
X1071100Y181633D01*
X1071017Y182050D01*
X1070808Y182342D01*
X1070558Y182425D01*
X1070308Y182383D01*
X1070100Y182217D01*
X1069683Y181383D01*
X1069392Y181008D01*
X1068975Y180758D01*
X1068600Y180675D01*
Y182425D01*
G01X1050892Y170067D02*
X1051017Y169817D01*
X1051100Y169525D01*
Y169192D01*
X1050975Y168817D01*
X1050767Y168525D01*
X1050517Y168317D01*
X1050100Y168150D01*
X1049725Y168108D01*
X1049350Y168192D01*
X1049100Y168317D01*
X1048850Y168567D01*
X1048683Y168858D01*
X1048600Y169150D01*
Y169442D01*
X1048683Y169733D01*
X1048808Y169983D01*
X1048975Y170192D01*
G01Y171333D02*
X1048767Y171583D01*
X1048642Y171875D01*
X1048600Y172250D01*
X1048683Y172625D01*
X1048850Y172917D01*
X1049142Y173125D01*
X1049475Y173167D01*
X1049808Y173083D01*
X1050017Y172875D01*
X1050183Y172583D01*
X1050225Y172292D01*
X1050183Y172000D01*
X1050017Y171625D01*
X1051100Y171750D01*
Y172875D01*
G01X1048600Y174517D02*
X1051100D01*
Y175517D01*
X1050975Y175850D01*
X1050683Y176100D01*
X1050350Y176183D01*
X1050017Y176100D01*
X1049767Y175892D01*
X1049642Y175517D01*
Y174517D01*
G01X1048600Y178450D02*
X1051100D01*
X1050600Y177950D01*
G01X1048600D02*
Y178950D01*
G01Y181467D02*
X1049142Y181550D01*
X1049600Y181675D01*
X1050017Y181842D01*
X1050475Y182050D01*
X1051100Y182383D01*
Y180717D01*
G01X1066892Y170067D02*
X1067017Y169817D01*
X1067100Y169525D01*
Y169192D01*
X1066975Y168817D01*
X1066767Y168525D01*
X1066517Y168317D01*
X1066100Y168150D01*
X1065725Y168108D01*
X1065350Y168192D01*
X1065100Y168317D01*
X1064850Y168567D01*
X1064683Y168858D01*
X1064600Y169150D01*
Y169442D01*
X1064683Y169733D01*
X1064808Y169983D01*
X1064975Y170192D01*
G01Y171333D02*
X1064767Y171583D01*
X1064642Y171875D01*
X1064600Y172250D01*
X1064683Y172625D01*
X1064850Y172917D01*
X1065142Y173125D01*
X1065475Y173167D01*
X1065808Y173083D01*
X1066017Y172875D01*
X1066183Y172583D01*
X1066225Y172292D01*
X1066183Y172000D01*
X1066017Y171625D01*
X1067100Y171750D01*
Y172875D01*
G01X1064600Y174517D02*
X1067100D01*
Y175517D01*
X1066975Y175850D01*
X1066683Y176100D01*
X1066350Y176183D01*
X1066017Y176100D01*
X1065767Y175892D01*
X1065642Y175517D01*
Y174517D01*
G01X1064600Y178450D02*
X1067100D01*
X1066600Y177950D01*
G01X1064600D02*
Y178950D01*
G01X1065100Y180633D02*
X1064808Y180883D01*
X1064642Y181217D01*
X1064600Y181592D01*
X1064642Y181925D01*
X1064850Y182258D01*
X1065100Y182467D01*
X1065350Y182508D01*
X1065642Y182425D01*
X1065850Y182133D01*
X1065933Y181842D01*
Y181467D01*
G01Y181842D02*
X1066058Y182092D01*
X1066267Y182300D01*
X1066517Y182383D01*
X1066767Y182300D01*
X1066975Y182092D01*
X1067100Y181717D01*
X1067058Y181342D01*
X1066892Y180967D01*
G01X1062892Y170067D02*
X1063017Y169817D01*
X1063100Y169525D01*
Y169192D01*
X1062975Y168817D01*
X1062767Y168525D01*
X1062517Y168317D01*
X1062100Y168150D01*
X1061725Y168108D01*
X1061350Y168192D01*
X1061100Y168317D01*
X1060850Y168567D01*
X1060683Y168858D01*
X1060600Y169150D01*
Y169442D01*
X1060683Y169733D01*
X1060808Y169983D01*
X1060975Y170192D01*
G01Y171333D02*
X1060767Y171583D01*
X1060642Y171875D01*
X1060600Y172250D01*
X1060683Y172625D01*
X1060850Y172917D01*
X1061142Y173125D01*
X1061475Y173167D01*
X1061808Y173083D01*
X1062017Y172875D01*
X1062183Y172583D01*
X1062225Y172292D01*
X1062183Y172000D01*
X1062017Y171625D01*
X1063100Y171750D01*
Y172875D01*
G01X1060600Y174517D02*
X1063100D01*
Y175517D01*
X1062975Y175850D01*
X1062683Y176100D01*
X1062350Y176183D01*
X1062017Y176100D01*
X1061767Y175892D01*
X1061642Y175517D01*
Y174517D01*
G01X1060600Y178450D02*
X1063100D01*
X1062600Y177950D01*
G01X1060600D02*
Y178950D01*
G01Y182050D02*
X1063100D01*
X1061308Y180508D01*
Y182592D01*
G01X1058892Y170067D02*
X1059017Y169817D01*
X1059100Y169525D01*
Y169192D01*
X1058975Y168817D01*
X1058767Y168525D01*
X1058517Y168317D01*
X1058100Y168150D01*
X1057725Y168108D01*
X1057350Y168192D01*
X1057100Y168317D01*
X1056850Y168567D01*
X1056683Y168858D01*
X1056600Y169150D01*
Y169442D01*
X1056683Y169733D01*
X1056808Y169983D01*
X1056975Y170192D01*
G01Y171333D02*
X1056767Y171583D01*
X1056642Y171875D01*
X1056600Y172250D01*
X1056683Y172625D01*
X1056850Y172917D01*
X1057142Y173125D01*
X1057475Y173167D01*
X1057808Y173083D01*
X1058017Y172875D01*
X1058183Y172583D01*
X1058225Y172292D01*
X1058183Y172000D01*
X1058017Y171625D01*
X1059100Y171750D01*
Y172875D01*
G01X1056600Y174517D02*
X1059100D01*
Y175517D01*
X1058975Y175850D01*
X1058683Y176100D01*
X1058350Y176183D01*
X1058017Y176100D01*
X1057767Y175892D01*
X1057642Y175517D01*
Y174517D01*
G01X1056600Y178450D02*
X1059100D01*
X1058600Y177950D01*
G01X1056600D02*
Y178950D01*
G01X1056975Y180633D02*
X1056767Y180883D01*
X1056642Y181175D01*
X1056600Y181550D01*
X1056683Y181925D01*
X1056850Y182217D01*
X1057142Y182425D01*
X1057475Y182467D01*
X1057808Y182383D01*
X1058017Y182175D01*
X1058183Y181883D01*
X1058225Y181592D01*
X1058183Y181300D01*
X1058017Y180925D01*
X1059100Y181050D01*
Y182175D01*
G01X1054892Y170067D02*
X1055017Y169817D01*
X1055100Y169525D01*
Y169192D01*
X1054975Y168817D01*
X1054767Y168525D01*
X1054517Y168317D01*
X1054100Y168150D01*
X1053725Y168108D01*
X1053350Y168192D01*
X1053100Y168317D01*
X1052850Y168567D01*
X1052683Y168858D01*
X1052600Y169150D01*
Y169442D01*
X1052683Y169733D01*
X1052808Y169983D01*
X1052975Y170192D01*
G01Y171333D02*
X1052767Y171583D01*
X1052642Y171875D01*
X1052600Y172250D01*
X1052683Y172625D01*
X1052850Y172917D01*
X1053142Y173125D01*
X1053475Y173167D01*
X1053808Y173083D01*
X1054017Y172875D01*
X1054183Y172583D01*
X1054225Y172292D01*
X1054183Y172000D01*
X1054017Y171625D01*
X1055100Y171750D01*
Y172875D01*
G01X1052600Y174517D02*
X1055100D01*
Y175517D01*
X1054975Y175850D01*
X1054683Y176100D01*
X1054350Y176183D01*
X1054017Y176100D01*
X1053767Y175892D01*
X1053642Y175517D01*
Y174517D01*
G01X1052600Y178450D02*
X1055100D01*
X1054600Y177950D01*
G01X1052600D02*
Y178950D01*
G01X1053642Y180758D02*
X1053933Y181050D01*
X1054100Y181300D01*
X1054183Y181633D01*
X1054100Y181925D01*
X1053933Y182133D01*
X1053683Y182300D01*
X1053392Y182342D01*
X1053142Y182300D01*
X1052892Y182133D01*
X1052683Y181883D01*
X1052600Y181592D01*
X1052683Y181258D01*
X1052933Y180967D01*
X1053308Y180800D01*
X1053725Y180758D01*
X1054267Y180842D01*
X1054558Y180967D01*
X1054850Y181175D01*
X1055058Y181467D01*
X1055100Y181758D01*
X1055017Y182050D01*
X1054808Y182258D01*
G01X1074092Y186967D02*
X1074217Y186717D01*
X1074300Y186425D01*
Y186092D01*
X1074175Y185717D01*
X1073967Y185425D01*
X1073717Y185217D01*
X1073300Y185050D01*
X1072925Y185008D01*
X1072550Y185092D01*
X1072300Y185217D01*
X1072050Y185467D01*
X1071883Y185758D01*
X1071800Y186050D01*
Y186342D01*
X1071883Y186633D01*
X1072008Y186883D01*
X1072175Y187092D01*
G01Y188233D02*
X1071967Y188483D01*
X1071842Y188775D01*
X1071800Y189150D01*
X1071883Y189525D01*
X1072050Y189817D01*
X1072342Y190025D01*
X1072675Y190067D01*
X1073008Y189983D01*
X1073217Y189775D01*
X1073383Y189483D01*
X1073425Y189192D01*
X1073383Y188900D01*
X1073217Y188525D01*
X1074300Y188650D01*
Y189775D01*
G01X1071800Y191417D02*
X1074300D01*
Y192417D01*
X1074175Y192750D01*
X1073883Y193000D01*
X1073550Y193083D01*
X1073217Y193000D01*
X1072967Y192792D01*
X1072842Y192417D01*
Y191417D01*
G01X1072175Y194433D02*
X1071967Y194683D01*
X1071842Y194975D01*
X1071800Y195350D01*
X1071883Y195725D01*
X1072050Y196017D01*
X1072342Y196225D01*
X1072675Y196267D01*
X1073008Y196183D01*
X1073217Y195975D01*
X1073383Y195683D01*
X1073425Y195392D01*
X1073383Y195100D01*
X1073217Y194725D01*
X1074300Y194850D01*
Y195975D01*
G01X1055783Y191792D02*
X1056033Y191917D01*
X1056325Y192000D01*
X1056658D01*
X1057033Y191875D01*
X1057325Y191667D01*
X1057533Y191417D01*
X1057700Y191000D01*
X1057742Y190625D01*
X1057658Y190250D01*
X1057533Y190000D01*
X1057283Y189750D01*
X1056992Y189583D01*
X1056700Y189500D01*
X1056408D01*
X1056117Y189583D01*
X1055867Y189708D01*
X1055658Y189875D01*
G01X1054517D02*
X1054267Y189667D01*
X1053975Y189542D01*
X1053600Y189500D01*
X1053225Y189583D01*
X1052933Y189750D01*
X1052725Y190042D01*
X1052683Y190375D01*
X1052767Y190708D01*
X1052975Y190917D01*
X1053267Y191083D01*
X1053558Y191125D01*
X1053850Y191083D01*
X1054225Y190917D01*
X1054100Y192000D01*
X1052975D01*
G01X1051333Y189500D02*
Y192000D01*
X1050333D01*
X1050000Y191875D01*
X1049750Y191583D01*
X1049667Y191250D01*
X1049750Y190917D01*
X1049958Y190667D01*
X1050333Y190542D01*
X1051333D01*
G01X1047483Y189500D02*
X1047400Y190042D01*
X1047275Y190500D01*
X1047108Y190917D01*
X1046900Y191375D01*
X1046567Y192000D01*
X1048233D01*
G01X1070092Y186967D02*
X1070217Y186717D01*
X1070300Y186425D01*
Y186092D01*
X1070175Y185717D01*
X1069967Y185425D01*
X1069717Y185217D01*
X1069300Y185050D01*
X1068925Y185008D01*
X1068550Y185092D01*
X1068300Y185217D01*
X1068050Y185467D01*
X1067883Y185758D01*
X1067800Y186050D01*
Y186342D01*
X1067883Y186633D01*
X1068008Y186883D01*
X1068175Y187092D01*
G01Y188233D02*
X1067967Y188483D01*
X1067842Y188775D01*
X1067800Y189150D01*
X1067883Y189525D01*
X1068050Y189817D01*
X1068342Y190025D01*
X1068675Y190067D01*
X1069008Y189983D01*
X1069217Y189775D01*
X1069383Y189483D01*
X1069425Y189192D01*
X1069383Y188900D01*
X1069217Y188525D01*
X1070300Y188650D01*
Y189775D01*
G01X1067800Y191417D02*
X1070300D01*
Y192417D01*
X1070175Y192750D01*
X1069883Y193000D01*
X1069550Y193083D01*
X1069217Y193000D01*
X1068967Y192792D01*
X1068842Y192417D01*
Y191417D01*
G01Y194558D02*
X1069133Y194850D01*
X1069300Y195100D01*
X1069383Y195433D01*
X1069300Y195725D01*
X1069133Y195933D01*
X1068883Y196100D01*
X1068592Y196142D01*
X1068342Y196100D01*
X1068092Y195933D01*
X1067883Y195683D01*
X1067800Y195392D01*
X1067883Y195058D01*
X1068133Y194767D01*
X1068508Y194600D01*
X1068925Y194558D01*
X1069467Y194642D01*
X1069758Y194767D01*
X1070050Y194975D01*
X1070258Y195267D01*
X1070300Y195558D01*
X1070217Y195850D01*
X1070008Y196058D01*
G01X1066092Y186967D02*
X1066217Y186717D01*
X1066300Y186425D01*
Y186092D01*
X1066175Y185717D01*
X1065967Y185425D01*
X1065717Y185217D01*
X1065300Y185050D01*
X1064925Y185008D01*
X1064550Y185092D01*
X1064300Y185217D01*
X1064050Y185467D01*
X1063883Y185758D01*
X1063800Y186050D01*
Y186342D01*
X1063883Y186633D01*
X1064008Y186883D01*
X1064175Y187092D01*
G01Y188233D02*
X1063967Y188483D01*
X1063842Y188775D01*
X1063800Y189150D01*
X1063883Y189525D01*
X1064050Y189817D01*
X1064342Y190025D01*
X1064675Y190067D01*
X1065008Y189983D01*
X1065217Y189775D01*
X1065383Y189483D01*
X1065425Y189192D01*
X1065383Y188900D01*
X1065217Y188525D01*
X1066300Y188650D01*
Y189775D01*
G01X1063800Y191417D02*
X1066300D01*
Y192417D01*
X1066175Y192750D01*
X1065883Y193000D01*
X1065550Y193083D01*
X1065217Y193000D01*
X1064967Y192792D01*
X1064842Y192417D01*
Y191417D01*
G01X1063800Y195350D02*
X1066300D01*
X1065800Y194850D01*
G01X1063800D02*
Y195850D01*
G01X1062092Y186967D02*
X1062217Y186717D01*
X1062300Y186425D01*
Y186092D01*
X1062175Y185717D01*
X1061967Y185425D01*
X1061717Y185217D01*
X1061300Y185050D01*
X1060925Y185008D01*
X1060550Y185092D01*
X1060300Y185217D01*
X1060050Y185467D01*
X1059883Y185758D01*
X1059800Y186050D01*
Y186342D01*
X1059883Y186633D01*
X1060008Y186883D01*
X1060175Y187092D01*
G01Y188233D02*
X1059967Y188483D01*
X1059842Y188775D01*
X1059800Y189150D01*
X1059883Y189525D01*
X1060050Y189817D01*
X1060342Y190025D01*
X1060675Y190067D01*
X1061008Y189983D01*
X1061217Y189775D01*
X1061383Y189483D01*
X1061425Y189192D01*
X1061383Y188900D01*
X1061217Y188525D01*
X1062300Y188650D01*
Y189775D01*
G01X1059800Y191417D02*
X1062300D01*
Y192417D01*
X1062175Y192750D01*
X1061883Y193000D01*
X1061550Y193083D01*
X1061217Y193000D01*
X1060967Y192792D01*
X1060842Y192417D01*
Y191417D01*
G01X1061883Y194558D02*
X1062133Y194808D01*
X1062258Y195100D01*
X1062300Y195433D01*
X1062217Y195850D01*
X1062008Y196142D01*
X1061758Y196225D01*
X1061508Y196183D01*
X1061300Y196017D01*
X1060883Y195183D01*
X1060592Y194808D01*
X1060175Y194558D01*
X1059800Y194475D01*
Y196225D01*
G01X1086958Y186767D02*
X1087083Y186517D01*
X1087166Y186225D01*
Y185892D01*
X1087041Y185517D01*
X1086833Y185225D01*
X1086583Y185017D01*
X1086166Y184850D01*
X1085791Y184808D01*
X1085416Y184892D01*
X1085166Y185017D01*
X1084916Y185267D01*
X1084749Y185558D01*
X1084666Y185850D01*
Y186142D01*
X1084749Y186433D01*
X1084874Y186683D01*
X1085041Y186892D01*
G01X1084666Y188950D02*
X1084708Y189242D01*
X1084833Y189575D01*
X1085041Y189783D01*
X1085333Y189867D01*
X1085624Y189783D01*
X1085874Y189533D01*
X1085999Y189158D01*
Y188742D01*
X1086083Y188492D01*
X1086291Y188283D01*
X1086583Y188200D01*
X1086874Y188325D01*
X1087083Y188617D01*
X1087166Y188950D01*
X1087083Y189283D01*
X1086874Y189575D01*
X1086583Y189700D01*
X1086291Y189617D01*
X1086083Y189408D01*
X1085999Y189158D01*
Y188742D01*
X1085874Y188367D01*
X1085624Y188117D01*
X1085333Y188033D01*
X1085041Y188117D01*
X1084833Y188325D01*
X1084708Y188658D01*
X1084666Y188950D01*
G01X1087166Y190800D02*
X1084666Y191383D01*
X1087166Y192050D01*
X1084666Y192717D01*
X1087166Y193300D01*
G01X1085166Y194233D02*
X1084874Y194483D01*
X1084708Y194817D01*
X1084666Y195192D01*
X1084708Y195525D01*
X1084916Y195858D01*
X1085166Y196067D01*
X1085416Y196108D01*
X1085708Y196025D01*
X1085916Y195733D01*
X1085999Y195442D01*
Y195067D01*
G01Y195442D02*
X1086124Y195692D01*
X1086333Y195900D01*
X1086583Y195983D01*
X1086833Y195900D01*
X1087041Y195692D01*
X1087166Y195317D01*
X1087124Y194942D01*
X1086958Y194567D01*
G01X1092600Y168317D02*
X1095100D01*
Y169358D01*
X1094975Y169692D01*
X1094808Y169900D01*
X1094475Y169983D01*
X1094142Y169900D01*
X1093933Y169650D01*
X1093808Y169358D01*
Y168317D01*
G01Y169358D02*
X1092600Y169983D01*
G01Y172750D02*
X1095100D01*
X1093308Y171208D01*
Y173292D01*
G01X1092600Y174517D02*
X1095100D01*
Y175517D01*
X1094975Y175850D01*
X1094683Y176100D01*
X1094350Y176183D01*
X1094017Y176100D01*
X1093767Y175892D01*
X1093642Y175517D01*
Y174517D01*
G01X1092600Y178450D02*
X1095100D01*
X1094600Y177950D01*
G01X1092600D02*
Y178950D01*
G01X1080264Y466408D02*
X1080514Y466533D01*
X1080806Y466616D01*
X1081139D01*
X1081514Y466491D01*
X1081806Y466283D01*
X1082014Y466033D01*
X1082181Y465616D01*
X1082223Y465241D01*
X1082139Y464866D01*
X1082014Y464616D01*
X1081764Y464366D01*
X1081473Y464199D01*
X1081181Y464116D01*
X1080889D01*
X1080598Y464199D01*
X1080348Y464324D01*
X1080139Y464491D01*
G01X1078998D02*
X1078748Y464283D01*
X1078456Y464158D01*
X1078081Y464116D01*
X1077706Y464199D01*
X1077414Y464366D01*
X1077206Y464658D01*
X1077164Y464991D01*
X1077248Y465324D01*
X1077456Y465533D01*
X1077748Y465699D01*
X1078039Y465741D01*
X1078331Y465699D01*
X1078706Y465533D01*
X1078581Y466616D01*
X1077456D01*
G01X1076064Y464116D02*
Y466616D01*
X1074981Y464533D01*
X1073898Y466616D01*
Y464116D01*
G01X1071881D02*
X1071589Y464158D01*
X1071256Y464283D01*
X1071048Y464491D01*
X1070964Y464783D01*
X1071048Y465074D01*
X1071298Y465324D01*
X1071673Y465449D01*
X1072089D01*
X1072339Y465533D01*
X1072548Y465741D01*
X1072631Y466033D01*
X1072506Y466324D01*
X1072214Y466533D01*
X1071881Y466616D01*
X1071548Y466533D01*
X1071256Y466324D01*
X1071131Y466033D01*
X1071214Y465741D01*
X1071423Y465533D01*
X1071673Y465449D01*
X1072089D01*
X1072464Y465324D01*
X1072714Y465074D01*
X1072798Y464783D01*
X1072714Y464491D01*
X1072506Y464283D01*
X1072173Y464158D01*
X1071881Y464116D01*
G01X1108566Y441725D02*
Y444225D01*
X1107525D01*
X1107191Y444100D01*
X1106983Y443933D01*
X1106900Y443600D01*
X1106983Y443267D01*
X1107233Y443058D01*
X1107525Y442933D01*
X1108566D01*
G01X1107525D02*
X1106900Y441725D01*
G01X1105425Y443808D02*
X1105175Y444058D01*
X1104883Y444183D01*
X1104550Y444225D01*
X1104133Y444142D01*
X1103841Y443933D01*
X1103758Y443683D01*
X1103800Y443433D01*
X1103966Y443225D01*
X1104800Y442808D01*
X1105175Y442517D01*
X1105425Y442100D01*
X1105508Y441725D01*
X1103758D01*
G01X1102450Y442100D02*
X1102200Y441892D01*
X1101908Y441767D01*
X1101533Y441725D01*
X1101158Y441808D01*
X1100866Y441975D01*
X1100658Y442267D01*
X1100616Y442600D01*
X1100700Y442933D01*
X1100908Y443142D01*
X1101200Y443308D01*
X1101491Y443350D01*
X1101783Y443308D01*
X1102158Y443142D01*
X1102033Y444225D01*
X1100908D01*
G01X1099683D02*
X1099100Y441725D01*
X1098433Y444225D01*
X1097766Y441725D01*
X1097183Y444225D01*
G01X1095333Y441725D02*
Y444225D01*
X1095833Y443725D01*
G01Y441725D02*
X1094833D01*
G01X1093150Y442225D02*
X1092900Y441933D01*
X1092566Y441767D01*
X1092191Y441725D01*
X1091858Y441767D01*
X1091525Y441975D01*
X1091316Y442225D01*
X1091275Y442475D01*
X1091358Y442767D01*
X1091650Y442975D01*
X1091941Y443058D01*
X1092316D01*
G01X1091941D02*
X1091691Y443183D01*
X1091483Y443392D01*
X1091400Y443642D01*
X1091483Y443892D01*
X1091691Y444100D01*
X1092066Y444225D01*
X1092441Y444183D01*
X1092816Y444017D01*
G01X1090050Y442225D02*
X1089800Y441933D01*
X1089466Y441767D01*
X1089091Y441725D01*
X1088758Y441767D01*
X1088425Y441975D01*
X1088216Y442225D01*
X1088175Y442475D01*
X1088258Y442767D01*
X1088550Y442975D01*
X1088841Y443058D01*
X1089216D01*
G01X1088841D02*
X1088591Y443183D01*
X1088383Y443392D01*
X1088300Y443642D01*
X1088383Y443892D01*
X1088591Y444100D01*
X1088966Y444225D01*
X1089341Y444183D01*
X1089716Y444017D01*
G01X1068216Y434595D02*
Y437095D01*
X1067175D01*
X1066841Y436970D01*
X1066633Y436803D01*
X1066550Y436470D01*
X1066633Y436137D01*
X1066883Y435928D01*
X1067175Y435803D01*
X1068216D01*
G01X1067175D02*
X1066550Y434595D01*
G01X1065075Y436678D02*
X1064825Y436928D01*
X1064533Y437053D01*
X1064200Y437095D01*
X1063783Y437012D01*
X1063491Y436803D01*
X1063408Y436553D01*
X1063450Y436303D01*
X1063616Y436095D01*
X1064450Y435678D01*
X1064825Y435387D01*
X1065075Y434970D01*
X1065158Y434595D01*
X1063408D01*
G01X1062100Y434970D02*
X1061850Y434762D01*
X1061558Y434637D01*
X1061183Y434595D01*
X1060808Y434678D01*
X1060516Y434845D01*
X1060308Y435137D01*
X1060266Y435470D01*
X1060350Y435803D01*
X1060558Y436012D01*
X1060850Y436178D01*
X1061141Y436220D01*
X1061433Y436178D01*
X1061808Y436012D01*
X1061683Y437095D01*
X1060558D01*
G01X1059333D02*
X1058750Y434595D01*
X1058083Y437095D01*
X1057416Y434595D01*
X1056833Y437095D01*
G01X1054983Y434595D02*
Y437095D01*
X1055483Y436595D01*
G01Y434595D02*
X1054483D01*
G01X1052800Y435095D02*
X1052550Y434803D01*
X1052216Y434637D01*
X1051841Y434595D01*
X1051508Y434637D01*
X1051175Y434845D01*
X1050966Y435095D01*
X1050925Y435345D01*
X1051008Y435637D01*
X1051300Y435845D01*
X1051591Y435928D01*
X1051966D01*
G01X1051591D02*
X1051341Y436053D01*
X1051133Y436262D01*
X1051050Y436512D01*
X1051133Y436762D01*
X1051341Y436970D01*
X1051716Y437095D01*
X1052091Y437053D01*
X1052466Y436887D01*
G01X1048783Y434595D02*
Y437095D01*
X1049283Y436595D01*
G01Y434595D02*
X1048283D01*
G01X1068216Y438095D02*
Y440595D01*
X1067175D01*
X1066841Y440470D01*
X1066633Y440303D01*
X1066550Y439970D01*
X1066633Y439637D01*
X1066883Y439428D01*
X1067175Y439303D01*
X1068216D01*
G01X1067175D02*
X1066550Y438095D01*
G01X1065075Y440178D02*
X1064825Y440428D01*
X1064533Y440553D01*
X1064200Y440595D01*
X1063783Y440512D01*
X1063491Y440303D01*
X1063408Y440053D01*
X1063450Y439803D01*
X1063616Y439595D01*
X1064450Y439178D01*
X1064825Y438887D01*
X1065075Y438470D01*
X1065158Y438095D01*
X1063408D01*
G01X1062100Y438470D02*
X1061850Y438262D01*
X1061558Y438137D01*
X1061183Y438095D01*
X1060808Y438178D01*
X1060516Y438345D01*
X1060308Y438637D01*
X1060266Y438970D01*
X1060350Y439303D01*
X1060558Y439512D01*
X1060850Y439678D01*
X1061141Y439720D01*
X1061433Y439678D01*
X1061808Y439512D01*
X1061683Y440595D01*
X1060558D01*
G01X1059333D02*
X1058750Y438095D01*
X1058083Y440595D01*
X1057416Y438095D01*
X1056833Y440595D01*
G01X1054983Y438095D02*
Y440595D01*
X1055483Y440095D01*
G01Y438095D02*
X1054483D01*
G01X1052800Y438595D02*
X1052550Y438303D01*
X1052216Y438137D01*
X1051841Y438095D01*
X1051508Y438137D01*
X1051175Y438345D01*
X1050966Y438595D01*
X1050925Y438845D01*
X1051008Y439137D01*
X1051300Y439345D01*
X1051591Y439428D01*
X1051966D01*
G01X1051591D02*
X1051341Y439553D01*
X1051133Y439762D01*
X1051050Y440012D01*
X1051133Y440262D01*
X1051341Y440470D01*
X1051716Y440595D01*
X1052091Y440553D01*
X1052466Y440387D01*
G01X1048283Y438095D02*
Y440595D01*
X1049825Y438803D01*
X1047741D01*
G01X1094186Y427159D02*
Y429659D01*
X1093145D01*
X1092811Y429534D01*
X1092603Y429367D01*
X1092520Y429034D01*
X1092603Y428701D01*
X1092853Y428492D01*
X1093145Y428367D01*
X1094186D01*
G01X1093145D02*
X1092520Y427159D01*
G01X1091045Y429242D02*
X1090795Y429492D01*
X1090503Y429617D01*
X1090170Y429659D01*
X1089753Y429576D01*
X1089461Y429367D01*
X1089378Y429117D01*
X1089420Y428867D01*
X1089586Y428659D01*
X1090420Y428242D01*
X1090795Y427951D01*
X1091045Y427534D01*
X1091128Y427159D01*
X1089378D01*
G01X1088070Y427534D02*
X1087820Y427326D01*
X1087528Y427201D01*
X1087153Y427159D01*
X1086778Y427242D01*
X1086486Y427409D01*
X1086278Y427701D01*
X1086236Y428034D01*
X1086320Y428367D01*
X1086528Y428576D01*
X1086820Y428742D01*
X1087111Y428784D01*
X1087403Y428742D01*
X1087778Y428576D01*
X1087653Y429659D01*
X1086528D01*
G01X1085303D02*
X1084720Y427159D01*
X1084053Y429659D01*
X1083386Y427159D01*
X1082803Y429659D01*
G01X1080953Y427159D02*
Y429659D01*
X1081453Y429159D01*
G01Y427159D02*
X1080453D01*
G01X1078770Y427659D02*
X1078520Y427367D01*
X1078186Y427201D01*
X1077811Y427159D01*
X1077478Y427201D01*
X1077145Y427409D01*
X1076936Y427659D01*
X1076895Y427909D01*
X1076978Y428201D01*
X1077270Y428409D01*
X1077561Y428492D01*
X1077936D01*
G01X1077561D02*
X1077311Y428617D01*
X1077103Y428826D01*
X1077020Y429076D01*
X1077103Y429326D01*
X1077311Y429534D01*
X1077686Y429659D01*
X1078061Y429617D01*
X1078436Y429451D01*
G01X1074753Y427159D02*
X1074461Y427201D01*
X1074128Y427326D01*
X1073920Y427534D01*
X1073836Y427826D01*
X1073920Y428117D01*
X1074170Y428367D01*
X1074545Y428492D01*
X1074961D01*
X1075211Y428576D01*
X1075420Y428784D01*
X1075503Y429076D01*
X1075378Y429367D01*
X1075086Y429576D01*
X1074753Y429659D01*
X1074420Y429576D01*
X1074128Y429367D01*
X1074003Y429076D01*
X1074086Y428784D01*
X1074295Y428576D01*
X1074545Y428492D01*
X1074961D01*
X1075336Y428367D01*
X1075586Y428117D01*
X1075670Y427826D01*
X1075586Y427534D01*
X1075378Y427326D01*
X1075045Y427201D01*
X1074753Y427159D01*
G01X1108566Y438330D02*
Y440830D01*
X1107525D01*
X1107191Y440705D01*
X1106983Y440538D01*
X1106900Y440205D01*
X1106983Y439872D01*
X1107233Y439663D01*
X1107525Y439538D01*
X1108566D01*
G01X1107525D02*
X1106900Y438330D01*
G01X1105425Y440413D02*
X1105175Y440663D01*
X1104883Y440788D01*
X1104550Y440830D01*
X1104133Y440747D01*
X1103841Y440538D01*
X1103758Y440288D01*
X1103800Y440038D01*
X1103966Y439830D01*
X1104800Y439413D01*
X1105175Y439122D01*
X1105425Y438705D01*
X1105508Y438330D01*
X1103758D01*
G01X1102450Y438705D02*
X1102200Y438497D01*
X1101908Y438372D01*
X1101533Y438330D01*
X1101158Y438413D01*
X1100866Y438580D01*
X1100658Y438872D01*
X1100616Y439205D01*
X1100700Y439538D01*
X1100908Y439747D01*
X1101200Y439913D01*
X1101491Y439955D01*
X1101783Y439913D01*
X1102158Y439747D01*
X1102033Y440830D01*
X1100908D01*
G01X1099683D02*
X1099100Y438330D01*
X1098433Y440830D01*
X1097766Y438330D01*
X1097183Y440830D01*
G01X1095333Y438330D02*
Y440830D01*
X1095833Y440330D01*
G01Y438330D02*
X1094833D01*
G01X1093150Y438830D02*
X1092900Y438538D01*
X1092566Y438372D01*
X1092191Y438330D01*
X1091858Y438372D01*
X1091525Y438580D01*
X1091316Y438830D01*
X1091275Y439080D01*
X1091358Y439372D01*
X1091650Y439580D01*
X1091941Y439663D01*
X1092316D01*
G01X1091941D02*
X1091691Y439788D01*
X1091483Y439997D01*
X1091400Y440247D01*
X1091483Y440497D01*
X1091691Y440705D01*
X1092066Y440830D01*
X1092441Y440788D01*
X1092816Y440622D01*
G01X1089925Y439372D02*
X1089633Y439663D01*
X1089383Y439830D01*
X1089050Y439913D01*
X1088758Y439830D01*
X1088550Y439663D01*
X1088383Y439413D01*
X1088341Y439122D01*
X1088383Y438872D01*
X1088550Y438622D01*
X1088800Y438413D01*
X1089091Y438330D01*
X1089425Y438413D01*
X1089716Y438663D01*
X1089883Y439038D01*
X1089925Y439455D01*
X1089841Y439997D01*
X1089716Y440288D01*
X1089508Y440580D01*
X1089216Y440788D01*
X1088925Y440830D01*
X1088633Y440747D01*
X1088425Y440538D01*
G01X1078846Y422485D02*
Y424985D01*
X1077805D01*
X1077471Y424860D01*
X1077263Y424693D01*
X1077180Y424360D01*
X1077263Y424027D01*
X1077513Y423818D01*
X1077805Y423693D01*
X1078846D01*
G01X1077805D02*
X1077180Y422485D01*
G01X1074913D02*
Y424985D01*
X1075413Y424485D01*
G01Y422485D02*
X1074413D01*
G01X1071813Y424985D02*
Y422485D01*
G01X1072771Y424985D02*
X1070855D01*
G01X1068713Y422485D02*
Y424985D01*
X1069213Y424485D01*
G01Y422485D02*
X1068213D01*
G01X1106486Y408715D02*
Y411215D01*
X1105445D01*
X1105111Y411090D01*
X1104903Y410923D01*
X1104820Y410590D01*
X1104903Y410257D01*
X1105153Y410048D01*
X1105445Y409923D01*
X1106486D01*
G01X1105445D02*
X1104820Y408715D01*
G01X1103261Y409007D02*
X1102970Y408798D01*
X1102636Y408715D01*
X1102303Y408798D01*
X1102011Y409048D01*
X1101803Y409423D01*
X1101720Y409798D01*
Y410257D01*
X1101803Y410632D01*
X1102011Y410965D01*
X1102261Y411132D01*
X1102553Y411215D01*
X1102886Y411132D01*
X1103136Y410965D01*
X1103303Y410715D01*
X1103386Y410382D01*
X1103303Y410090D01*
X1103095Y409798D01*
X1102845Y409632D01*
X1102553Y409590D01*
X1102220Y409673D01*
X1101970Y409882D01*
X1101720Y410257D01*
G01X1100245Y408715D02*
Y411215D01*
X1098661D01*
G01X1099245Y410007D02*
X1100245D01*
G01X1097145Y410798D02*
X1096895Y411048D01*
X1096603Y411173D01*
X1096270Y411215D01*
X1095853Y411132D01*
X1095561Y410923D01*
X1095478Y410673D01*
X1095520Y410423D01*
X1095686Y410215D01*
X1096520Y409798D01*
X1096895Y409507D01*
X1097145Y409090D01*
X1097228Y408715D01*
X1095478D01*
G01X1093336D02*
X1093253Y409257D01*
X1093128Y409715D01*
X1092961Y410132D01*
X1092753Y410590D01*
X1092420Y411215D01*
X1094086D01*
G01X1090486Y408715D02*
Y411215D01*
X1089445D01*
X1089111Y411090D01*
X1088903Y410923D01*
X1088820Y410590D01*
X1088903Y410257D01*
X1089153Y410048D01*
X1089445Y409923D01*
X1090486D01*
G01X1089445D02*
X1088820Y408715D01*
G01X1087261Y409007D02*
X1086970Y408798D01*
X1086636Y408715D01*
X1086303Y408798D01*
X1086011Y409048D01*
X1085803Y409423D01*
X1085720Y409798D01*
Y410257D01*
X1085803Y410632D01*
X1086011Y410965D01*
X1086261Y411132D01*
X1086553Y411215D01*
X1086886Y411132D01*
X1087136Y410965D01*
X1087303Y410715D01*
X1087386Y410382D01*
X1087303Y410090D01*
X1087095Y409798D01*
X1086845Y409632D01*
X1086553Y409590D01*
X1086220Y409673D01*
X1085970Y409882D01*
X1085720Y410257D01*
G01X1084245Y408715D02*
Y411215D01*
X1082661D01*
G01X1083245Y410007D02*
X1084245D01*
G01X1081145Y410798D02*
X1080895Y411048D01*
X1080603Y411173D01*
X1080270Y411215D01*
X1079853Y411132D01*
X1079561Y410923D01*
X1079478Y410673D01*
X1079520Y410423D01*
X1079686Y410215D01*
X1080520Y409798D01*
X1080895Y409507D01*
X1081145Y409090D01*
X1081228Y408715D01*
X1079478D01*
G01X1078045Y409757D02*
X1077753Y410048D01*
X1077503Y410215D01*
X1077170Y410298D01*
X1076878Y410215D01*
X1076670Y410048D01*
X1076503Y409798D01*
X1076461Y409507D01*
X1076503Y409257D01*
X1076670Y409007D01*
X1076920Y408798D01*
X1077211Y408715D01*
X1077545Y408798D01*
X1077836Y409048D01*
X1078003Y409423D01*
X1078045Y409840D01*
X1077961Y410382D01*
X1077836Y410673D01*
X1077628Y410965D01*
X1077336Y411173D01*
X1077045Y411215D01*
X1076753Y411132D01*
X1076545Y410923D01*
G01X1098633Y417550D02*
Y420050D01*
X1097592D01*
X1097258Y419925D01*
X1097050Y419758D01*
X1096967Y419425D01*
X1097050Y419092D01*
X1097300Y418883D01*
X1097592Y418758D01*
X1098633D01*
G01X1097592D02*
X1096967Y417550D01*
G01X1095408Y417842D02*
X1095117Y417633D01*
X1094783Y417550D01*
X1094450Y417633D01*
X1094158Y417883D01*
X1093950Y418258D01*
X1093867Y418633D01*
Y419092D01*
X1093950Y419467D01*
X1094158Y419800D01*
X1094408Y419967D01*
X1094700Y420050D01*
X1095033Y419967D01*
X1095283Y419800D01*
X1095450Y419550D01*
X1095533Y419217D01*
X1095450Y418925D01*
X1095242Y418633D01*
X1094992Y418467D01*
X1094700Y418425D01*
X1094367Y418508D01*
X1094117Y418717D01*
X1093867Y419092D01*
G01X1092850Y420050D02*
X1092267Y417550D01*
X1091600Y420050D01*
X1090933Y417550D01*
X1090350Y420050D01*
G01X1089417Y418050D02*
X1089167Y417758D01*
X1088833Y417592D01*
X1088458Y417550D01*
X1088125Y417592D01*
X1087792Y417800D01*
X1087583Y418050D01*
X1087542Y418300D01*
X1087625Y418592D01*
X1087917Y418800D01*
X1088208Y418883D01*
X1088583D01*
G01X1088208D02*
X1087958Y419008D01*
X1087750Y419217D01*
X1087667Y419467D01*
X1087750Y419717D01*
X1087958Y419925D01*
X1088333Y420050D01*
X1088708Y420008D01*
X1089083Y419842D01*
G01X1086317Y418050D02*
X1086067Y417758D01*
X1085733Y417592D01*
X1085358Y417550D01*
X1085025Y417592D01*
X1084692Y417800D01*
X1084483Y418050D01*
X1084442Y418300D01*
X1084525Y418592D01*
X1084817Y418800D01*
X1085108Y418883D01*
X1085483D01*
G01X1085108D02*
X1084858Y419008D01*
X1084650Y419217D01*
X1084567Y419467D01*
X1084650Y419717D01*
X1084858Y419925D01*
X1085233Y420050D01*
X1085608Y420008D01*
X1085983Y419842D01*
G01X1044436Y444247D02*
X1044686Y444372D01*
X1044978Y444455D01*
X1045311D01*
X1045686Y444330D01*
X1045978Y444122D01*
X1046186Y443872D01*
X1046353Y443455D01*
X1046395Y443080D01*
X1046311Y442705D01*
X1046186Y442455D01*
X1045936Y442205D01*
X1045645Y442038D01*
X1045353Y441955D01*
X1045061D01*
X1044770Y442038D01*
X1044520Y442163D01*
X1044311Y442330D01*
G01X1042961Y442247D02*
X1042670Y442038D01*
X1042336Y441955D01*
X1042003Y442038D01*
X1041711Y442288D01*
X1041503Y442663D01*
X1041420Y443038D01*
Y443497D01*
X1041503Y443872D01*
X1041711Y444205D01*
X1041961Y444372D01*
X1042253Y444455D01*
X1042586Y444372D01*
X1042836Y444205D01*
X1043003Y443955D01*
X1043086Y443622D01*
X1043003Y443330D01*
X1042795Y443038D01*
X1042545Y442872D01*
X1042253Y442830D01*
X1041920Y442913D01*
X1041670Y443122D01*
X1041420Y443497D01*
G01X1038320Y441955D02*
X1039986D01*
Y444455D01*
X1038320D01*
G01X1038986Y443247D02*
X1039986D01*
G01X1036053Y441955D02*
Y444455D01*
X1036553Y443955D01*
G01Y441955D02*
X1035553D01*
G01X1106816Y437017D02*
X1107066Y437142D01*
X1107358Y437225D01*
X1107691D01*
X1108066Y437100D01*
X1108358Y436892D01*
X1108566Y436642D01*
X1108733Y436225D01*
X1108775Y435850D01*
X1108691Y435475D01*
X1108566Y435225D01*
X1108316Y434975D01*
X1108025Y434808D01*
X1107733Y434725D01*
X1107441D01*
X1107150Y434808D01*
X1106900Y434933D01*
X1106691Y435100D01*
G01X1105425Y436808D02*
X1105175Y437058D01*
X1104883Y437183D01*
X1104550Y437225D01*
X1104133Y437142D01*
X1103841Y436933D01*
X1103758Y436683D01*
X1103800Y436433D01*
X1103966Y436225D01*
X1104800Y435808D01*
X1105175Y435517D01*
X1105425Y435100D01*
X1105508Y434725D01*
X1103758D01*
G01X1102450Y435100D02*
X1102200Y434892D01*
X1101908Y434767D01*
X1101533Y434725D01*
X1101158Y434808D01*
X1100866Y434975D01*
X1100658Y435267D01*
X1100616Y435600D01*
X1100700Y435933D01*
X1100908Y436142D01*
X1101200Y436308D01*
X1101491Y436350D01*
X1101783Y436308D01*
X1102158Y436142D01*
X1102033Y437225D01*
X1100908D01*
G01X1099683D02*
X1099100Y434725D01*
X1098433Y437225D01*
X1097766Y434725D01*
X1097183Y437225D01*
G01X1095416Y434725D02*
X1095333Y435267D01*
X1095208Y435725D01*
X1095041Y436142D01*
X1094833Y436600D01*
X1094500Y437225D01*
X1096166D01*
G01X1092941Y435017D02*
X1092650Y434808D01*
X1092316Y434725D01*
X1091983Y434808D01*
X1091691Y435058D01*
X1091483Y435433D01*
X1091400Y435808D01*
Y436267D01*
X1091483Y436642D01*
X1091691Y436975D01*
X1091941Y437142D01*
X1092233Y437225D01*
X1092566Y437142D01*
X1092816Y436975D01*
X1092983Y436725D01*
X1093066Y436392D01*
X1092983Y436100D01*
X1092775Y435808D01*
X1092525Y435642D01*
X1092233Y435600D01*
X1091900Y435683D01*
X1091650Y435892D01*
X1091400Y436267D01*
G01X1092730Y432951D02*
X1092980Y433076D01*
X1093272Y433159D01*
X1093605D01*
X1093980Y433034D01*
X1094272Y432826D01*
X1094480Y432576D01*
X1094647Y432159D01*
X1094689Y431784D01*
X1094605Y431409D01*
X1094480Y431159D01*
X1094230Y430909D01*
X1093939Y430742D01*
X1093647Y430659D01*
X1093355D01*
X1093064Y430742D01*
X1092814Y430867D01*
X1092605Y431034D01*
G01X1091339Y432742D02*
X1091089Y432992D01*
X1090797Y433117D01*
X1090464Y433159D01*
X1090047Y433076D01*
X1089755Y432867D01*
X1089672Y432617D01*
X1089714Y432367D01*
X1089880Y432159D01*
X1090714Y431742D01*
X1091089Y431451D01*
X1091339Y431034D01*
X1091422Y430659D01*
X1089672D01*
G01X1088364Y431034D02*
X1088114Y430826D01*
X1087822Y430701D01*
X1087447Y430659D01*
X1087072Y430742D01*
X1086780Y430909D01*
X1086572Y431201D01*
X1086530Y431534D01*
X1086614Y431867D01*
X1086822Y432076D01*
X1087114Y432242D01*
X1087405Y432284D01*
X1087697Y432242D01*
X1088072Y432076D01*
X1087947Y433159D01*
X1086822D01*
G01X1085597D02*
X1085014Y430659D01*
X1084347Y433159D01*
X1083680Y430659D01*
X1083097Y433159D01*
G01X1081247Y430659D02*
X1080955Y430701D01*
X1080622Y430826D01*
X1080414Y431034D01*
X1080330Y431326D01*
X1080414Y431617D01*
X1080664Y431867D01*
X1081039Y431992D01*
X1081455D01*
X1081705Y432076D01*
X1081914Y432284D01*
X1081997Y432576D01*
X1081872Y432867D01*
X1081580Y433076D01*
X1081247Y433159D01*
X1080914Y433076D01*
X1080622Y432867D01*
X1080497Y432576D01*
X1080580Y432284D01*
X1080789Y432076D01*
X1081039Y431992D01*
X1081455D01*
X1081830Y431867D01*
X1082080Y431617D01*
X1082164Y431326D01*
X1082080Y431034D01*
X1081872Y430826D01*
X1081539Y430701D01*
X1081247Y430659D01*
G01X1078147D02*
Y433159D01*
X1078647Y432659D01*
G01Y430659D02*
X1077647D01*
G01X1106816Y447655D02*
X1107066Y447780D01*
X1107358Y447863D01*
X1107691D01*
X1108066Y447738D01*
X1108358Y447530D01*
X1108566Y447280D01*
X1108733Y446863D01*
X1108775Y446488D01*
X1108691Y446113D01*
X1108566Y445863D01*
X1108316Y445613D01*
X1108025Y445446D01*
X1107733Y445363D01*
X1107441D01*
X1107150Y445446D01*
X1106900Y445571D01*
X1106691Y445738D01*
G01X1105425Y447446D02*
X1105175Y447696D01*
X1104883Y447821D01*
X1104550Y447863D01*
X1104133Y447780D01*
X1103841Y447571D01*
X1103758Y447321D01*
X1103800Y447071D01*
X1103966Y446863D01*
X1104800Y446446D01*
X1105175Y446155D01*
X1105425Y445738D01*
X1105508Y445363D01*
X1103758D01*
G01X1102450Y445738D02*
X1102200Y445530D01*
X1101908Y445405D01*
X1101533Y445363D01*
X1101158Y445446D01*
X1100866Y445613D01*
X1100658Y445905D01*
X1100616Y446238D01*
X1100700Y446571D01*
X1100908Y446780D01*
X1101200Y446946D01*
X1101491Y446988D01*
X1101783Y446946D01*
X1102158Y446780D01*
X1102033Y447863D01*
X1100908D01*
G01X1099683D02*
X1099100Y445363D01*
X1098433Y447863D01*
X1097766Y445363D01*
X1097183Y447863D01*
G01X1095416Y445363D02*
X1095333Y445905D01*
X1095208Y446363D01*
X1095041Y446780D01*
X1094833Y447238D01*
X1094500Y447863D01*
X1096166D01*
G01X1092233Y445363D02*
X1091941Y445405D01*
X1091608Y445530D01*
X1091400Y445738D01*
X1091316Y446030D01*
X1091400Y446321D01*
X1091650Y446571D01*
X1092025Y446696D01*
X1092441D01*
X1092691Y446780D01*
X1092900Y446988D01*
X1092983Y447280D01*
X1092858Y447571D01*
X1092566Y447780D01*
X1092233Y447863D01*
X1091900Y447780D01*
X1091608Y447571D01*
X1091483Y447280D01*
X1091566Y446988D01*
X1091775Y446780D01*
X1092025Y446696D01*
X1092441D01*
X1092816Y446571D01*
X1093066Y446321D01*
X1093150Y446030D01*
X1093066Y445738D01*
X1092858Y445530D01*
X1092525Y445405D01*
X1092233Y445363D01*
G01X1064152Y466291D02*
X1064402Y466416D01*
X1064694Y466499D01*
X1065027D01*
X1065402Y466374D01*
X1065694Y466166D01*
X1065902Y465916D01*
X1066069Y465499D01*
X1066111Y465124D01*
X1066027Y464749D01*
X1065902Y464499D01*
X1065652Y464249D01*
X1065361Y464082D01*
X1065069Y463999D01*
X1064777D01*
X1064486Y464082D01*
X1064236Y464207D01*
X1064027Y464374D01*
G01X1062886D02*
X1062636Y464166D01*
X1062344Y464041D01*
X1061969Y463999D01*
X1061594Y464082D01*
X1061302Y464249D01*
X1061094Y464541D01*
X1061052Y464874D01*
X1061136Y465207D01*
X1061344Y465416D01*
X1061636Y465582D01*
X1061927Y465624D01*
X1062219Y465582D01*
X1062594Y465416D01*
X1062469Y466499D01*
X1061344D01*
G01X1059952Y463999D02*
Y466499D01*
X1058869Y464416D01*
X1057786Y466499D01*
Y463999D01*
G01X1056477Y464291D02*
X1056186Y464082D01*
X1055852Y463999D01*
X1055519Y464082D01*
X1055227Y464332D01*
X1055019Y464707D01*
X1054936Y465082D01*
Y465541D01*
X1055019Y465916D01*
X1055227Y466249D01*
X1055477Y466416D01*
X1055769Y466499D01*
X1056102Y466416D01*
X1056352Y466249D01*
X1056519Y465999D01*
X1056602Y465666D01*
X1056519Y465374D01*
X1056311Y465082D01*
X1056061Y464916D01*
X1055769Y464874D01*
X1055436Y464957D01*
X1055186Y465166D01*
X1054936Y465541D01*
G01X1096733Y466172D02*
X1096983Y466297D01*
X1097275Y466380D01*
X1097608D01*
X1097983Y466255D01*
X1098275Y466047D01*
X1098483Y465797D01*
X1098650Y465380D01*
X1098692Y465005D01*
X1098608Y464630D01*
X1098483Y464380D01*
X1098233Y464130D01*
X1097942Y463963D01*
X1097650Y463880D01*
X1097358D01*
X1097067Y463963D01*
X1096817Y464088D01*
X1096608Y464255D01*
G01X1095467D02*
X1095217Y464047D01*
X1094925Y463922D01*
X1094550Y463880D01*
X1094175Y463963D01*
X1093883Y464130D01*
X1093675Y464422D01*
X1093633Y464755D01*
X1093717Y465088D01*
X1093925Y465297D01*
X1094217Y465463D01*
X1094508Y465505D01*
X1094800Y465463D01*
X1095175Y465297D01*
X1095050Y466380D01*
X1093925D01*
G01X1092533Y463880D02*
Y466380D01*
X1091450Y464297D01*
X1090367Y466380D01*
Y463880D01*
G01X1089267Y464380D02*
X1089017Y464088D01*
X1088683Y463922D01*
X1088308Y463880D01*
X1087975Y463922D01*
X1087642Y464130D01*
X1087433Y464380D01*
X1087392Y464630D01*
X1087475Y464922D01*
X1087767Y465130D01*
X1088058Y465213D01*
X1088433D01*
G01X1088058D02*
X1087808Y465338D01*
X1087600Y465547D01*
X1087517Y465797D01*
X1087600Y466047D01*
X1087808Y466255D01*
X1088183Y466380D01*
X1088558Y466338D01*
X1088933Y466172D01*
G01X1047443Y466053D02*
X1047693Y466178D01*
X1047985Y466261D01*
X1048318D01*
X1048693Y466136D01*
X1048985Y465928D01*
X1049193Y465678D01*
X1049360Y465261D01*
X1049402Y464886D01*
X1049318Y464511D01*
X1049193Y464261D01*
X1048943Y464011D01*
X1048652Y463844D01*
X1048360Y463761D01*
X1048068D01*
X1047777Y463844D01*
X1047527Y463969D01*
X1047318Y464136D01*
G01X1046177D02*
X1045927Y463928D01*
X1045635Y463803D01*
X1045260Y463761D01*
X1044885Y463844D01*
X1044593Y464011D01*
X1044385Y464303D01*
X1044343Y464636D01*
X1044427Y464969D01*
X1044635Y465178D01*
X1044927Y465344D01*
X1045218Y465386D01*
X1045510Y465344D01*
X1045885Y465178D01*
X1045760Y466261D01*
X1044635D01*
G01X1043243Y463761D02*
Y466261D01*
X1042160Y464178D01*
X1041077Y466261D01*
Y463761D01*
G01X1038560D02*
Y466261D01*
X1040102Y464469D01*
X1038018D01*
G01X1084784Y438736D02*
X1085117Y438778D01*
X1085409Y438944D01*
X1085659Y439194D01*
X1085826Y439486D01*
X1085909Y439819D01*
Y440153D01*
X1085826Y440486D01*
X1085659Y440778D01*
X1085409Y441028D01*
X1085117Y441194D01*
X1084784Y441236D01*
X1084451Y441194D01*
X1084159Y441028D01*
X1083909Y440778D01*
X1083742Y440486D01*
X1083659Y440153D01*
Y439819D01*
X1083742Y439486D01*
X1083909Y439194D01*
X1084159Y438944D01*
X1084451Y438778D01*
X1084784Y438736D01*
G01X1084451Y439403D02*
X1083951Y438736D01*
G01X1082476Y440819D02*
X1082226Y441069D01*
X1081934Y441194D01*
X1081601Y441236D01*
X1081184Y441153D01*
X1080892Y440944D01*
X1080809Y440694D01*
X1080851Y440444D01*
X1081017Y440236D01*
X1081851Y439819D01*
X1082226Y439528D01*
X1082476Y439111D01*
X1082559Y438736D01*
X1080809D01*
G01X1079501Y439111D02*
X1079251Y438903D01*
X1078959Y438778D01*
X1078584Y438736D01*
X1078209Y438819D01*
X1077917Y438986D01*
X1077709Y439278D01*
X1077667Y439611D01*
X1077751Y439944D01*
X1077959Y440153D01*
X1078251Y440319D01*
X1078542Y440361D01*
X1078834Y440319D01*
X1079209Y440153D01*
X1079084Y441236D01*
X1077959D01*
G01X1076734D02*
X1076151Y438736D01*
X1075484Y441236D01*
X1074817Y438736D01*
X1074234Y441236D01*
G01X1071884Y438736D02*
Y441236D01*
X1073426Y439444D01*
X1071342D01*
G01X1079900Y484000D02*
X1079400D01*
Y499000D01*
X1077400Y497000D01*
X1081400D01*
X1079400Y499000D01*
G01X1064283Y497459D02*
X1064533Y497584D01*
X1064825Y497667D01*
X1065158D01*
X1065533Y497542D01*
X1065825Y497334D01*
X1066033Y497084D01*
X1066200Y496667D01*
X1066242Y496292D01*
X1066158Y495917D01*
X1066033Y495667D01*
X1065783Y495417D01*
X1065492Y495250D01*
X1065200Y495167D01*
X1064908D01*
X1064617Y495250D01*
X1064367Y495375D01*
X1064158Y495542D01*
G01X1063017D02*
X1062767Y495334D01*
X1062475Y495209D01*
X1062100Y495167D01*
X1061725Y495250D01*
X1061433Y495417D01*
X1061225Y495709D01*
X1061183Y496042D01*
X1061267Y496375D01*
X1061475Y496584D01*
X1061767Y496750D01*
X1062058Y496792D01*
X1062350Y496750D01*
X1062725Y496584D01*
X1062600Y497667D01*
X1061475D01*
G01X1060083Y495167D02*
Y497667D01*
X1059000Y495584D01*
X1057917Y497667D01*
Y495167D01*
G01X1055900D02*
Y497667D01*
X1056400Y497167D01*
G01Y495167D02*
X1055400D01*
G01X1053592Y497250D02*
X1053342Y497500D01*
X1053050Y497625D01*
X1052717Y497667D01*
X1052300Y497584D01*
X1052008Y497375D01*
X1051925Y497125D01*
X1051967Y496875D01*
X1052133Y496667D01*
X1052967Y496250D01*
X1053342Y495959D01*
X1053592Y495542D01*
X1053675Y495167D01*
X1051925D01*
G01X1080264Y470408D02*
X1080514Y470533D01*
X1080806Y470616D01*
X1081139D01*
X1081514Y470491D01*
X1081806Y470283D01*
X1082014Y470033D01*
X1082181Y469616D01*
X1082223Y469241D01*
X1082139Y468866D01*
X1082014Y468616D01*
X1081764Y468366D01*
X1081473Y468199D01*
X1081181Y468116D01*
X1080889D01*
X1080598Y468199D01*
X1080348Y468324D01*
X1080139Y468491D01*
G01X1078998D02*
X1078748Y468283D01*
X1078456Y468158D01*
X1078081Y468116D01*
X1077706Y468199D01*
X1077414Y468366D01*
X1077206Y468658D01*
X1077164Y468991D01*
X1077248Y469324D01*
X1077456Y469533D01*
X1077748Y469699D01*
X1078039Y469741D01*
X1078331Y469699D01*
X1078706Y469533D01*
X1078581Y470616D01*
X1077456D01*
G01X1074731Y469366D02*
X1073898D01*
Y468616D01*
X1074148Y468366D01*
X1074439Y468199D01*
X1074856Y468116D01*
X1075273Y468199D01*
X1075564Y468366D01*
X1075814Y468616D01*
X1075981Y468908D01*
X1076064Y469241D01*
Y469533D01*
X1075981Y469783D01*
X1075814Y470074D01*
X1075564Y470324D01*
X1075314Y470491D01*
X1074981Y470616D01*
X1074689D01*
X1074356Y470533D01*
X1074106Y470366D01*
G01X1071964Y468116D02*
X1071881Y468658D01*
X1071756Y469116D01*
X1071589Y469533D01*
X1071381Y469991D01*
X1071048Y470616D01*
X1072714D01*
G01X1068781Y468116D02*
X1068489Y468158D01*
X1068156Y468283D01*
X1067948Y468491D01*
X1067864Y468783D01*
X1067948Y469074D01*
X1068198Y469324D01*
X1068573Y469449D01*
X1068989D01*
X1069239Y469533D01*
X1069448Y469741D01*
X1069531Y470033D01*
X1069406Y470324D01*
X1069114Y470533D01*
X1068781Y470616D01*
X1068448Y470533D01*
X1068156Y470324D01*
X1068031Y470033D01*
X1068114Y469741D01*
X1068323Y469533D01*
X1068573Y469449D01*
X1068989D01*
X1069364Y469324D01*
X1069614Y469074D01*
X1069698Y468783D01*
X1069614Y468491D01*
X1069406Y468283D01*
X1069073Y468158D01*
X1068781Y468116D01*
G01X1080264Y474408D02*
X1080514Y474533D01*
X1080806Y474616D01*
X1081139D01*
X1081514Y474491D01*
X1081806Y474283D01*
X1082014Y474033D01*
X1082181Y473616D01*
X1082223Y473241D01*
X1082139Y472866D01*
X1082014Y472616D01*
X1081764Y472366D01*
X1081473Y472199D01*
X1081181Y472116D01*
X1080889D01*
X1080598Y472199D01*
X1080348Y472324D01*
X1080139Y472491D01*
G01X1078998D02*
X1078748Y472283D01*
X1078456Y472158D01*
X1078081Y472116D01*
X1077706Y472199D01*
X1077414Y472366D01*
X1077206Y472658D01*
X1077164Y472991D01*
X1077248Y473324D01*
X1077456Y473533D01*
X1077748Y473699D01*
X1078039Y473741D01*
X1078331Y473699D01*
X1078706Y473533D01*
X1078581Y474616D01*
X1077456D01*
G01X1075814D02*
Y472116D01*
X1074148D01*
G01X1071881D02*
Y474616D01*
X1072381Y474116D01*
G01Y472116D02*
X1071381D01*
G01X1068281D02*
Y474616D01*
X1069823Y472824D01*
X1067739D01*
G01X1080564Y478408D02*
X1080814Y478533D01*
X1081106Y478616D01*
X1081439D01*
X1081814Y478491D01*
X1082106Y478283D01*
X1082314Y478033D01*
X1082481Y477616D01*
X1082523Y477241D01*
X1082439Y476866D01*
X1082314Y476616D01*
X1082064Y476366D01*
X1081773Y476199D01*
X1081481Y476116D01*
X1081189D01*
X1080898Y476199D01*
X1080648Y476324D01*
X1080439Y476491D01*
G01X1079298D02*
X1079048Y476283D01*
X1078756Y476158D01*
X1078381Y476116D01*
X1078006Y476199D01*
X1077714Y476366D01*
X1077506Y476658D01*
X1077464Y476991D01*
X1077548Y477324D01*
X1077756Y477533D01*
X1078048Y477699D01*
X1078339Y477741D01*
X1078631Y477699D01*
X1079006Y477533D01*
X1078881Y478616D01*
X1077756D01*
G01X1075031Y477366D02*
X1074198D01*
Y476616D01*
X1074448Y476366D01*
X1074739Y476199D01*
X1075156Y476116D01*
X1075573Y476199D01*
X1075864Y476366D01*
X1076114Y476616D01*
X1076281Y476908D01*
X1076364Y477241D01*
Y477533D01*
X1076281Y477783D01*
X1076114Y478074D01*
X1075864Y478324D01*
X1075614Y478491D01*
X1075281Y478616D01*
X1074989D01*
X1074656Y478533D01*
X1074406Y478366D01*
G01X1072264Y476116D02*
X1072181Y476658D01*
X1072056Y477116D01*
X1071889Y477533D01*
X1071681Y477991D01*
X1071348Y478616D01*
X1073014D01*
G01X1069164Y476116D02*
X1069081Y476658D01*
X1068956Y477116D01*
X1068789Y477533D01*
X1068581Y477991D01*
X1068248Y478616D01*
X1069914D01*
G01X1096733Y470172D02*
X1096983Y470297D01*
X1097275Y470380D01*
X1097608D01*
X1097983Y470255D01*
X1098275Y470047D01*
X1098483Y469797D01*
X1098650Y469380D01*
X1098692Y469005D01*
X1098608Y468630D01*
X1098483Y468380D01*
X1098233Y468130D01*
X1097942Y467963D01*
X1097650Y467880D01*
X1097358D01*
X1097067Y467963D01*
X1096817Y468088D01*
X1096608Y468255D01*
G01X1095467D02*
X1095217Y468047D01*
X1094925Y467922D01*
X1094550Y467880D01*
X1094175Y467963D01*
X1093883Y468130D01*
X1093675Y468422D01*
X1093633Y468755D01*
X1093717Y469088D01*
X1093925Y469297D01*
X1094217Y469463D01*
X1094508Y469505D01*
X1094800Y469463D01*
X1095175Y469297D01*
X1095050Y470380D01*
X1093925D01*
G01X1091200Y469130D02*
X1090367D01*
Y468380D01*
X1090617Y468130D01*
X1090908Y467963D01*
X1091325Y467880D01*
X1091742Y467963D01*
X1092033Y468130D01*
X1092283Y468380D01*
X1092450Y468672D01*
X1092533Y469005D01*
Y469297D01*
X1092450Y469547D01*
X1092283Y469838D01*
X1092033Y470088D01*
X1091783Y470255D01*
X1091450Y470380D01*
X1091158D01*
X1090825Y470297D01*
X1090575Y470130D01*
G01X1088433Y467880D02*
X1088350Y468422D01*
X1088225Y468880D01*
X1088058Y469297D01*
X1087850Y469755D01*
X1087517Y470380D01*
X1089183D01*
G01X1086167Y468380D02*
X1085917Y468088D01*
X1085583Y467922D01*
X1085208Y467880D01*
X1084875Y467922D01*
X1084542Y468130D01*
X1084333Y468380D01*
X1084292Y468630D01*
X1084375Y468922D01*
X1084667Y469130D01*
X1084958Y469213D01*
X1085333D01*
G01X1084958D02*
X1084708Y469338D01*
X1084500Y469547D01*
X1084417Y469797D01*
X1084500Y470047D01*
X1084708Y470255D01*
X1085083Y470380D01*
X1085458Y470338D01*
X1085833Y470172D01*
G01X1064152Y478291D02*
X1064402Y478416D01*
X1064694Y478499D01*
X1065027D01*
X1065402Y478374D01*
X1065694Y478166D01*
X1065902Y477916D01*
X1066069Y477499D01*
X1066111Y477124D01*
X1066027Y476749D01*
X1065902Y476499D01*
X1065652Y476249D01*
X1065361Y476082D01*
X1065069Y475999D01*
X1064777D01*
X1064486Y476082D01*
X1064236Y476207D01*
X1064027Y476374D01*
G01X1062886D02*
X1062636Y476166D01*
X1062344Y476041D01*
X1061969Y475999D01*
X1061594Y476082D01*
X1061302Y476249D01*
X1061094Y476541D01*
X1061052Y476874D01*
X1061136Y477207D01*
X1061344Y477416D01*
X1061636Y477582D01*
X1061927Y477624D01*
X1062219Y477582D01*
X1062594Y477416D01*
X1062469Y478499D01*
X1061344D01*
G01X1058619Y477249D02*
X1057786D01*
Y476499D01*
X1058036Y476249D01*
X1058327Y476082D01*
X1058744Y475999D01*
X1059161Y476082D01*
X1059452Y476249D01*
X1059702Y476499D01*
X1059869Y476791D01*
X1059952Y477124D01*
Y477416D01*
X1059869Y477666D01*
X1059702Y477957D01*
X1059452Y478207D01*
X1059202Y478374D01*
X1058869Y478499D01*
X1058577D01*
X1058244Y478416D01*
X1057994Y478249D01*
G01X1056561Y477041D02*
X1056269Y477332D01*
X1056019Y477499D01*
X1055686Y477582D01*
X1055394Y477499D01*
X1055186Y477332D01*
X1055019Y477082D01*
X1054977Y476791D01*
X1055019Y476541D01*
X1055186Y476291D01*
X1055436Y476082D01*
X1055727Y475999D01*
X1056061Y476082D01*
X1056352Y476332D01*
X1056519Y476707D01*
X1056561Y477124D01*
X1056477Y477666D01*
X1056352Y477957D01*
X1056144Y478249D01*
X1055852Y478457D01*
X1055561Y478499D01*
X1055269Y478416D01*
X1055061Y478207D01*
G01X1053586Y476499D02*
X1053336Y476207D01*
X1053002Y476041D01*
X1052627Y475999D01*
X1052294Y476041D01*
X1051961Y476249D01*
X1051752Y476499D01*
X1051711Y476749D01*
X1051794Y477041D01*
X1052086Y477249D01*
X1052377Y477332D01*
X1052752D01*
G01X1052377D02*
X1052127Y477457D01*
X1051919Y477666D01*
X1051836Y477916D01*
X1051919Y478166D01*
X1052127Y478374D01*
X1052502Y478499D01*
X1052877Y478457D01*
X1053252Y478291D01*
G01X1096733Y478172D02*
X1096983Y478297D01*
X1097275Y478380D01*
X1097608D01*
X1097983Y478255D01*
X1098275Y478047D01*
X1098483Y477797D01*
X1098650Y477380D01*
X1098692Y477005D01*
X1098608Y476630D01*
X1098483Y476380D01*
X1098233Y476130D01*
X1097942Y475963D01*
X1097650Y475880D01*
X1097358D01*
X1097067Y475963D01*
X1096817Y476088D01*
X1096608Y476255D01*
G01X1095467D02*
X1095217Y476047D01*
X1094925Y475922D01*
X1094550Y475880D01*
X1094175Y475963D01*
X1093883Y476130D01*
X1093675Y476422D01*
X1093633Y476755D01*
X1093717Y477088D01*
X1093925Y477297D01*
X1094217Y477463D01*
X1094508Y477505D01*
X1094800Y477463D01*
X1095175Y477297D01*
X1095050Y478380D01*
X1093925D01*
G01X1091200Y477130D02*
X1090367D01*
Y476380D01*
X1090617Y476130D01*
X1090908Y475963D01*
X1091325Y475880D01*
X1091742Y475963D01*
X1092033Y476130D01*
X1092283Y476380D01*
X1092450Y476672D01*
X1092533Y477005D01*
Y477297D01*
X1092450Y477547D01*
X1092283Y477838D01*
X1092033Y478088D01*
X1091783Y478255D01*
X1091450Y478380D01*
X1091158D01*
X1090825Y478297D01*
X1090575Y478130D01*
G01X1089142Y476922D02*
X1088850Y477213D01*
X1088600Y477380D01*
X1088267Y477463D01*
X1087975Y477380D01*
X1087767Y477213D01*
X1087600Y476963D01*
X1087558Y476672D01*
X1087600Y476422D01*
X1087767Y476172D01*
X1088017Y475963D01*
X1088308Y475880D01*
X1088642Y475963D01*
X1088933Y476213D01*
X1089100Y476588D01*
X1089142Y477005D01*
X1089058Y477547D01*
X1088933Y477838D01*
X1088725Y478130D01*
X1088433Y478338D01*
X1088142Y478380D01*
X1087850Y478297D01*
X1087642Y478088D01*
G01X1085958Y476172D02*
X1085667Y475963D01*
X1085333Y475880D01*
X1085000Y475963D01*
X1084708Y476213D01*
X1084500Y476588D01*
X1084417Y476963D01*
Y477422D01*
X1084500Y477797D01*
X1084708Y478130D01*
X1084958Y478297D01*
X1085250Y478380D01*
X1085583Y478297D01*
X1085833Y478130D01*
X1086000Y477880D01*
X1086083Y477547D01*
X1086000Y477255D01*
X1085792Y476963D01*
X1085542Y476797D01*
X1085250Y476755D01*
X1084917Y476838D01*
X1084667Y477047D01*
X1084417Y477422D01*
G01X1047443Y470053D02*
X1047693Y470178D01*
X1047985Y470261D01*
X1048318D01*
X1048693Y470136D01*
X1048985Y469928D01*
X1049193Y469678D01*
X1049360Y469261D01*
X1049402Y468886D01*
X1049318Y468511D01*
X1049193Y468261D01*
X1048943Y468011D01*
X1048652Y467844D01*
X1048360Y467761D01*
X1048068D01*
X1047777Y467844D01*
X1047527Y467969D01*
X1047318Y468136D01*
G01X1046177D02*
X1045927Y467928D01*
X1045635Y467803D01*
X1045260Y467761D01*
X1044885Y467844D01*
X1044593Y468011D01*
X1044385Y468303D01*
X1044343Y468636D01*
X1044427Y468969D01*
X1044635Y469178D01*
X1044927Y469344D01*
X1045218Y469386D01*
X1045510Y469344D01*
X1045885Y469178D01*
X1045760Y470261D01*
X1044635D01*
G01X1041910Y469011D02*
X1041077D01*
Y468261D01*
X1041327Y468011D01*
X1041618Y467844D01*
X1042035Y467761D01*
X1042452Y467844D01*
X1042743Y468011D01*
X1042993Y468261D01*
X1043160Y468553D01*
X1043243Y468886D01*
Y469178D01*
X1043160Y469428D01*
X1042993Y469719D01*
X1042743Y469969D01*
X1042493Y470136D01*
X1042160Y470261D01*
X1041868D01*
X1041535Y470178D01*
X1041285Y470011D01*
G01X1039852Y468803D02*
X1039560Y469094D01*
X1039310Y469261D01*
X1038977Y469344D01*
X1038685Y469261D01*
X1038477Y469094D01*
X1038310Y468844D01*
X1038268Y468553D01*
X1038310Y468303D01*
X1038477Y468053D01*
X1038727Y467844D01*
X1039018Y467761D01*
X1039352Y467844D01*
X1039643Y468094D01*
X1039810Y468469D01*
X1039852Y468886D01*
X1039768Y469428D01*
X1039643Y469719D01*
X1039435Y470011D01*
X1039143Y470219D01*
X1038852Y470261D01*
X1038560Y470178D01*
X1038352Y469969D01*
G01X1036043Y467761D02*
X1035960Y468303D01*
X1035835Y468761D01*
X1035668Y469178D01*
X1035460Y469636D01*
X1035127Y470261D01*
X1036793D01*
G01X1064152Y470291D02*
X1064402Y470416D01*
X1064694Y470499D01*
X1065027D01*
X1065402Y470374D01*
X1065694Y470166D01*
X1065902Y469916D01*
X1066069Y469499D01*
X1066111Y469124D01*
X1066027Y468749D01*
X1065902Y468499D01*
X1065652Y468249D01*
X1065361Y468082D01*
X1065069Y467999D01*
X1064777D01*
X1064486Y468082D01*
X1064236Y468207D01*
X1064027Y468374D01*
G01X1062886D02*
X1062636Y468166D01*
X1062344Y468041D01*
X1061969Y467999D01*
X1061594Y468082D01*
X1061302Y468249D01*
X1061094Y468541D01*
X1061052Y468874D01*
X1061136Y469207D01*
X1061344Y469416D01*
X1061636Y469582D01*
X1061927Y469624D01*
X1062219Y469582D01*
X1062594Y469416D01*
X1062469Y470499D01*
X1061344D01*
G01X1058619Y469249D02*
X1057786D01*
Y468499D01*
X1058036Y468249D01*
X1058327Y468082D01*
X1058744Y467999D01*
X1059161Y468082D01*
X1059452Y468249D01*
X1059702Y468499D01*
X1059869Y468791D01*
X1059952Y469124D01*
Y469416D01*
X1059869Y469666D01*
X1059702Y469957D01*
X1059452Y470207D01*
X1059202Y470374D01*
X1058869Y470499D01*
X1058577D01*
X1058244Y470416D01*
X1057994Y470249D01*
G01X1056561Y469041D02*
X1056269Y469332D01*
X1056019Y469499D01*
X1055686Y469582D01*
X1055394Y469499D01*
X1055186Y469332D01*
X1055019Y469082D01*
X1054977Y468791D01*
X1055019Y468541D01*
X1055186Y468291D01*
X1055436Y468082D01*
X1055727Y467999D01*
X1056061Y468082D01*
X1056352Y468332D01*
X1056519Y468707D01*
X1056561Y469124D01*
X1056477Y469666D01*
X1056352Y469957D01*
X1056144Y470249D01*
X1055852Y470457D01*
X1055561Y470499D01*
X1055269Y470416D01*
X1055061Y470207D01*
G01X1052669Y467999D02*
X1052377Y468041D01*
X1052044Y468166D01*
X1051836Y468374D01*
X1051752Y468666D01*
X1051836Y468957D01*
X1052086Y469207D01*
X1052461Y469332D01*
X1052877D01*
X1053127Y469416D01*
X1053336Y469624D01*
X1053419Y469916D01*
X1053294Y470207D01*
X1053002Y470416D01*
X1052669Y470499D01*
X1052336Y470416D01*
X1052044Y470207D01*
X1051919Y469916D01*
X1052002Y469624D01*
X1052211Y469416D01*
X1052461Y469332D01*
X1052877D01*
X1053252Y469207D01*
X1053502Y468957D01*
X1053586Y468666D01*
X1053502Y468374D01*
X1053294Y468166D01*
X1052961Y468041D01*
X1052669Y467999D01*
G01X1047443Y478053D02*
X1047693Y478178D01*
X1047985Y478261D01*
X1048318D01*
X1048693Y478136D01*
X1048985Y477928D01*
X1049193Y477678D01*
X1049360Y477261D01*
X1049402Y476886D01*
X1049318Y476511D01*
X1049193Y476261D01*
X1048943Y476011D01*
X1048652Y475844D01*
X1048360Y475761D01*
X1048068D01*
X1047777Y475844D01*
X1047527Y475969D01*
X1047318Y476136D01*
G01X1046177D02*
X1045927Y475928D01*
X1045635Y475803D01*
X1045260Y475761D01*
X1044885Y475844D01*
X1044593Y476011D01*
X1044385Y476303D01*
X1044343Y476636D01*
X1044427Y476969D01*
X1044635Y477178D01*
X1044927Y477344D01*
X1045218Y477386D01*
X1045510Y477344D01*
X1045885Y477178D01*
X1045760Y478261D01*
X1044635D01*
G01X1041910Y477011D02*
X1041077D01*
Y476261D01*
X1041327Y476011D01*
X1041618Y475844D01*
X1042035Y475761D01*
X1042452Y475844D01*
X1042743Y476011D01*
X1042993Y476261D01*
X1043160Y476553D01*
X1043243Y476886D01*
Y477178D01*
X1043160Y477428D01*
X1042993Y477719D01*
X1042743Y477969D01*
X1042493Y478136D01*
X1042160Y478261D01*
X1041868D01*
X1041535Y478178D01*
X1041285Y478011D01*
G01X1039852Y476803D02*
X1039560Y477094D01*
X1039310Y477261D01*
X1038977Y477344D01*
X1038685Y477261D01*
X1038477Y477094D01*
X1038310Y476844D01*
X1038268Y476553D01*
X1038310Y476303D01*
X1038477Y476053D01*
X1038727Y475844D01*
X1039018Y475761D01*
X1039352Y475844D01*
X1039643Y476094D01*
X1039810Y476469D01*
X1039852Y476886D01*
X1039768Y477428D01*
X1039643Y477719D01*
X1039435Y478011D01*
X1039143Y478219D01*
X1038852Y478261D01*
X1038560Y478178D01*
X1038352Y477969D01*
G01X1036752Y477844D02*
X1036502Y478094D01*
X1036210Y478219D01*
X1035877Y478261D01*
X1035460Y478178D01*
X1035168Y477969D01*
X1035085Y477719D01*
X1035127Y477469D01*
X1035293Y477261D01*
X1036127Y476844D01*
X1036502Y476553D01*
X1036752Y476136D01*
X1036835Y475761D01*
X1035085D01*
G01X1045429Y527501D02*
X1045352Y528173D01*
X1045237Y528741D01*
X1045084Y529258D01*
X1044892Y529826D01*
X1044585Y530601D01*
X1046119D01*
G01X1042252Y527501D02*
X1041984Y527553D01*
X1041677Y527708D01*
X1041485Y527966D01*
X1041409Y528328D01*
X1041485Y528689D01*
X1041715Y528999D01*
X1042060Y529154D01*
X1042444D01*
X1042674Y529258D01*
X1042865Y529516D01*
X1042942Y529878D01*
X1042827Y530239D01*
X1042559Y530498D01*
X1042252Y530601D01*
X1041945Y530498D01*
X1041677Y530239D01*
X1041562Y529878D01*
X1041639Y529516D01*
X1041830Y529258D01*
X1042060Y529154D01*
X1042444D01*
X1042789Y528999D01*
X1043019Y528689D01*
X1043095Y528328D01*
X1043019Y527966D01*
X1042827Y527708D01*
X1042520Y527553D01*
X1042252Y527501D01*
G01X1064152Y474291D02*
X1064402Y474416D01*
X1064694Y474499D01*
X1065027D01*
X1065402Y474374D01*
X1065694Y474166D01*
X1065902Y473916D01*
X1066069Y473499D01*
X1066111Y473124D01*
X1066027Y472749D01*
X1065902Y472499D01*
X1065652Y472249D01*
X1065361Y472082D01*
X1065069Y471999D01*
X1064777D01*
X1064486Y472082D01*
X1064236Y472207D01*
X1064027Y472374D01*
G01X1062886D02*
X1062636Y472166D01*
X1062344Y472041D01*
X1061969Y471999D01*
X1061594Y472082D01*
X1061302Y472249D01*
X1061094Y472541D01*
X1061052Y472874D01*
X1061136Y473207D01*
X1061344Y473416D01*
X1061636Y473582D01*
X1061927Y473624D01*
X1062219Y473582D01*
X1062594Y473416D01*
X1062469Y474499D01*
X1061344D01*
G01X1059702D02*
Y471999D01*
X1058036D01*
G01X1055769D02*
Y474499D01*
X1056269Y473999D01*
G01Y471999D02*
X1055269D01*
G01X1053586Y472374D02*
X1053336Y472166D01*
X1053044Y472041D01*
X1052669Y471999D01*
X1052294Y472082D01*
X1052002Y472249D01*
X1051794Y472541D01*
X1051752Y472874D01*
X1051836Y473207D01*
X1052044Y473416D01*
X1052336Y473582D01*
X1052627Y473624D01*
X1052919Y473582D01*
X1053294Y473416D01*
X1053169Y474499D01*
X1052044D01*
G01X1047443Y474053D02*
X1047693Y474178D01*
X1047985Y474261D01*
X1048318D01*
X1048693Y474136D01*
X1048985Y473928D01*
X1049193Y473678D01*
X1049360Y473261D01*
X1049402Y472886D01*
X1049318Y472511D01*
X1049193Y472261D01*
X1048943Y472011D01*
X1048652Y471844D01*
X1048360Y471761D01*
X1048068D01*
X1047777Y471844D01*
X1047527Y471969D01*
X1047318Y472136D01*
G01X1046177D02*
X1045927Y471928D01*
X1045635Y471803D01*
X1045260Y471761D01*
X1044885Y471844D01*
X1044593Y472011D01*
X1044385Y472303D01*
X1044343Y472636D01*
X1044427Y472969D01*
X1044635Y473178D01*
X1044927Y473344D01*
X1045218Y473386D01*
X1045510Y473344D01*
X1045885Y473178D01*
X1045760Y474261D01*
X1044635D01*
G01X1042993D02*
Y471761D01*
X1041327D01*
G01X1039060D02*
Y474261D01*
X1039560Y473761D01*
G01Y471761D02*
X1038560D01*
G01X1035960Y474261D02*
X1036293Y474178D01*
X1036543Y473969D01*
X1036710Y473719D01*
X1036835Y473386D01*
X1036877Y473011D01*
X1036835Y472636D01*
X1036710Y472303D01*
X1036543Y472053D01*
X1036293Y471844D01*
X1035960Y471761D01*
X1035627Y471844D01*
X1035377Y472053D01*
X1035210Y472303D01*
X1035085Y472636D01*
X1035043Y473011D01*
X1035085Y473386D01*
X1035210Y473719D01*
X1035377Y473969D01*
X1035627Y474178D01*
X1035960Y474261D01*
G01X1096733Y474172D02*
X1096983Y474297D01*
X1097275Y474380D01*
X1097608D01*
X1097983Y474255D01*
X1098275Y474047D01*
X1098483Y473797D01*
X1098650Y473380D01*
X1098692Y473005D01*
X1098608Y472630D01*
X1098483Y472380D01*
X1098233Y472130D01*
X1097942Y471963D01*
X1097650Y471880D01*
X1097358D01*
X1097067Y471963D01*
X1096817Y472088D01*
X1096608Y472255D01*
G01X1095467D02*
X1095217Y472047D01*
X1094925Y471922D01*
X1094550Y471880D01*
X1094175Y471963D01*
X1093883Y472130D01*
X1093675Y472422D01*
X1093633Y472755D01*
X1093717Y473088D01*
X1093925Y473297D01*
X1094217Y473463D01*
X1094508Y473505D01*
X1094800Y473463D01*
X1095175Y473297D01*
X1095050Y474380D01*
X1093925D01*
G01X1092283D02*
Y471880D01*
X1090617D01*
G01X1089058Y472172D02*
X1088767Y471963D01*
X1088433Y471880D01*
X1088100Y471963D01*
X1087808Y472213D01*
X1087600Y472588D01*
X1087517Y472963D01*
Y473422D01*
X1087600Y473797D01*
X1087808Y474130D01*
X1088058Y474297D01*
X1088350Y474380D01*
X1088683Y474297D01*
X1088933Y474130D01*
X1089100Y473880D01*
X1089183Y473547D01*
X1089100Y473255D01*
X1088892Y472963D01*
X1088642Y472797D01*
X1088350Y472755D01*
X1088017Y472838D01*
X1087767Y473047D01*
X1087517Y473422D01*
G01X1049080Y576084D02*
X1048850Y576394D01*
X1048582Y576549D01*
X1048275Y576601D01*
X1047892Y576498D01*
X1047624Y576239D01*
X1047547Y575929D01*
X1047585Y575619D01*
X1047739Y575361D01*
X1048505Y574844D01*
X1048850Y574483D01*
X1049080Y573966D01*
X1049157Y573501D01*
X1047547D01*
G01X1045980Y576084D02*
X1045750Y576394D01*
X1045482Y576549D01*
X1045175Y576601D01*
X1044792Y576498D01*
X1044524Y576239D01*
X1044447Y575929D01*
X1044485Y575619D01*
X1044639Y575361D01*
X1045405Y574844D01*
X1045750Y574483D01*
X1045980Y573966D01*
X1046057Y573501D01*
X1044447D01*
G01X1042880Y576084D02*
X1042650Y576394D01*
X1042382Y576549D01*
X1042075Y576601D01*
X1041692Y576498D01*
X1041424Y576239D01*
X1041347Y575929D01*
X1041385Y575619D01*
X1041539Y575361D01*
X1042305Y574844D01*
X1042650Y574483D01*
X1042880Y573966D01*
X1042957Y573501D01*
X1041347D01*
G01X1045929Y565501D02*
X1045852Y566173D01*
X1045737Y566741D01*
X1045584Y567258D01*
X1045392Y567826D01*
X1045085Y568601D01*
X1046619D01*
G01X1042752Y565501D02*
X1042484Y565553D01*
X1042177Y565708D01*
X1041985Y565966D01*
X1041909Y566328D01*
X1041985Y566689D01*
X1042215Y566999D01*
X1042560Y567154D01*
X1042944D01*
X1043174Y567258D01*
X1043365Y567516D01*
X1043442Y567878D01*
X1043327Y568239D01*
X1043059Y568498D01*
X1042752Y568601D01*
X1042445Y568498D01*
X1042177Y568239D01*
X1042062Y567878D01*
X1042139Y567516D01*
X1042330Y567258D01*
X1042560Y567154D01*
X1042944D01*
X1043289Y566999D01*
X1043519Y566689D01*
X1043595Y566328D01*
X1043519Y565966D01*
X1043327Y565708D01*
X1043020Y565553D01*
X1042752Y565501D01*
G01X1049580Y538084D02*
X1049350Y538394D01*
X1049082Y538549D01*
X1048775Y538601D01*
X1048392Y538498D01*
X1048124Y538239D01*
X1048047Y537929D01*
X1048085Y537619D01*
X1048239Y537361D01*
X1049005Y536844D01*
X1049350Y536483D01*
X1049580Y535966D01*
X1049657Y535501D01*
X1048047D01*
G01X1046480Y538084D02*
X1046250Y538394D01*
X1045982Y538549D01*
X1045675Y538601D01*
X1045292Y538498D01*
X1045024Y538239D01*
X1044947Y537929D01*
X1044985Y537619D01*
X1045139Y537361D01*
X1045905Y536844D01*
X1046250Y536483D01*
X1046480Y535966D01*
X1046557Y535501D01*
X1044947D01*
G01X1043380Y538084D02*
X1043150Y538394D01*
X1042882Y538549D01*
X1042575Y538601D01*
X1042192Y538498D01*
X1041924Y538239D01*
X1041847Y537929D01*
X1041885Y537619D01*
X1042039Y537361D01*
X1042805Y536844D01*
X1043150Y536483D01*
X1043380Y535966D01*
X1043457Y535501D01*
X1041847D01*
G01X1054117Y618008D02*
X1054367Y618133D01*
X1054659Y618216D01*
X1054992D01*
X1055367Y618091D01*
X1055659Y617883D01*
X1055867Y617633D01*
X1056034Y617216D01*
X1056076Y616841D01*
X1055992Y616466D01*
X1055867Y616216D01*
X1055617Y615966D01*
X1055326Y615799D01*
X1055034Y615716D01*
X1054742D01*
X1054451Y615799D01*
X1054201Y615924D01*
X1053992Y616091D01*
G01X1052851D02*
X1052601Y615883D01*
X1052309Y615758D01*
X1051934Y615716D01*
X1051559Y615799D01*
X1051267Y615966D01*
X1051059Y616258D01*
X1051017Y616591D01*
X1051101Y616924D01*
X1051309Y617133D01*
X1051601Y617299D01*
X1051892Y617341D01*
X1052184Y617299D01*
X1052559Y617133D01*
X1052434Y618216D01*
X1051309D01*
G01X1049667D02*
Y615716D01*
X1048001D01*
G01X1046651Y616216D02*
X1046401Y615924D01*
X1046067Y615758D01*
X1045692Y615716D01*
X1045359Y615758D01*
X1045026Y615966D01*
X1044817Y616216D01*
X1044776Y616466D01*
X1044859Y616758D01*
X1045151Y616966D01*
X1045442Y617049D01*
X1045817D01*
G01X1045442D02*
X1045192Y617174D01*
X1044984Y617383D01*
X1044901Y617633D01*
X1044984Y617883D01*
X1045192Y618091D01*
X1045567Y618216D01*
X1045942Y618174D01*
X1046317Y618008D01*
G01X1045683Y621442D02*
X1045933Y621567D01*
X1046225Y621650D01*
X1046558D01*
X1046933Y621525D01*
X1047225Y621317D01*
X1047433Y621067D01*
X1047600Y620650D01*
X1047642Y620275D01*
X1047558Y619900D01*
X1047433Y619650D01*
X1047183Y619400D01*
X1046892Y619233D01*
X1046600Y619150D01*
X1046308D01*
X1046017Y619233D01*
X1045767Y619358D01*
X1045558Y619525D01*
G01X1044417D02*
X1044167Y619317D01*
X1043875Y619192D01*
X1043500Y619150D01*
X1043125Y619233D01*
X1042833Y619400D01*
X1042625Y619692D01*
X1042583Y620025D01*
X1042667Y620358D01*
X1042875Y620567D01*
X1043167Y620733D01*
X1043458Y620775D01*
X1043750Y620733D01*
X1044125Y620567D01*
X1044000Y621650D01*
X1042875D01*
G01X1041233D02*
Y619150D01*
X1039567D01*
G01X1038217Y619525D02*
X1037967Y619317D01*
X1037675Y619192D01*
X1037300Y619150D01*
X1036925Y619233D01*
X1036633Y619400D01*
X1036425Y619692D01*
X1036383Y620025D01*
X1036467Y620358D01*
X1036675Y620567D01*
X1036967Y620733D01*
X1037258Y620775D01*
X1037550Y620733D01*
X1037925Y620567D01*
X1037800Y621650D01*
X1036675D01*
G01X1045929Y604001D02*
X1045852Y604673D01*
X1045737Y605241D01*
X1045584Y605758D01*
X1045392Y606326D01*
X1045085Y607101D01*
X1046619D01*
G01X1042752Y604001D02*
X1042484Y604053D01*
X1042177Y604208D01*
X1041985Y604466D01*
X1041909Y604828D01*
X1041985Y605189D01*
X1042215Y605499D01*
X1042560Y605654D01*
X1042944D01*
X1043174Y605758D01*
X1043365Y606016D01*
X1043442Y606378D01*
X1043327Y606739D01*
X1043059Y606998D01*
X1042752Y607101D01*
X1042445Y606998D01*
X1042177Y606739D01*
X1042062Y606378D01*
X1042139Y606016D01*
X1042330Y605758D01*
X1042560Y605654D01*
X1042944D01*
X1043289Y605499D01*
X1043519Y605189D01*
X1043595Y604828D01*
X1043519Y604466D01*
X1043327Y604208D01*
X1043020Y604053D01*
X1042752Y604001D01*
G01X1113200Y657200D02*
Y660200D01*
X1112200D01*
X1111800Y660050D01*
X1111500Y659850D01*
X1111250Y659550D01*
X1111050Y659200D01*
X1111000Y658700D01*
X1111050Y658200D01*
X1111250Y657850D01*
X1111500Y657550D01*
X1111800Y657350D01*
X1112200Y657200D01*
X1113200D01*
G01X1109250Y658550D02*
X1107650D01*
X1107800Y658900D01*
X1108050Y659100D01*
X1108400Y659200D01*
X1108750Y659150D01*
X1109050Y659000D01*
X1109250Y658650D01*
X1109350Y658350D01*
Y658050D01*
X1109250Y657750D01*
X1109000Y657450D01*
X1108700Y657250D01*
X1108350Y657200D01*
X1108000Y657300D01*
X1107650Y657600D01*
G01X1104900Y657200D02*
Y660200D01*
G01X1101300D02*
Y657200D01*
G01X1102000Y659200D02*
X1100600D01*
G01X1096800Y657200D02*
Y659200D01*
G01Y658850D02*
X1097000Y659050D01*
X1097300Y659150D01*
X1097650Y659200D01*
X1098000Y659100D01*
X1098300Y658900D01*
X1098500Y658600D01*
X1098600Y658200D01*
X1098500Y657800D01*
X1098300Y657500D01*
X1098000Y657300D01*
X1097650Y657200D01*
X1097300Y657250D01*
X1097000Y657400D01*
X1096800Y657600D01*
G01X1095600Y656200D02*
X1092600D01*
G01X1091500Y660200D02*
Y657200D01*
X1089500D01*
G01X1088000Y657800D02*
X1087700Y657450D01*
X1087300Y657250D01*
X1086850Y657200D01*
X1086450Y657250D01*
X1086050Y657500D01*
X1085800Y657800D01*
X1085750Y658100D01*
X1085850Y658450D01*
X1086200Y658700D01*
X1086550Y658800D01*
X1087000D01*
G01X1086550D02*
X1086250Y658950D01*
X1086000Y659200D01*
X1085900Y659500D01*
X1086000Y659800D01*
X1086250Y660050D01*
X1086700Y660200D01*
X1087150Y660150D01*
X1087600Y659950D01*
G01X1084800Y656200D02*
X1081800D01*
G01X1079700Y657200D02*
Y660200D01*
X1080300Y659600D01*
G01Y657200D02*
X1079100D01*
G01X1076100Y660200D02*
X1076500Y660100D01*
X1076800Y659850D01*
X1077000Y659550D01*
X1077150Y659150D01*
X1077200Y658700D01*
X1077150Y658250D01*
X1077000Y657850D01*
X1076800Y657550D01*
X1076500Y657300D01*
X1076100Y657200D01*
X1075700Y657300D01*
X1075400Y657550D01*
X1075200Y657850D01*
X1075050Y658250D01*
X1075000Y658700D01*
X1075050Y659150D01*
X1075200Y659550D01*
X1075400Y659850D01*
X1075700Y660100D01*
X1076100Y660200D01*
G01X1072500Y659200D02*
Y657200D01*
G01Y660000D02*
X1072600Y660050D01*
Y660150D01*
X1072500Y660200D01*
X1072400Y660150D01*
Y660050D01*
X1072500Y660000D01*
G01X1069750Y657200D02*
Y659200D01*
G01Y658700D02*
X1069550Y658950D01*
X1069250Y659150D01*
X1068850Y659200D01*
X1068500Y659150D01*
X1068200Y658950D01*
X1068050Y658600D01*
Y657200D01*
G01X1064500Y658950D02*
X1064850Y659150D01*
X1065150Y659200D01*
X1065550Y659100D01*
X1065850Y658900D01*
X1066050Y658550D01*
X1066100Y658200D01*
X1066050Y657850D01*
X1065850Y657550D01*
X1065550Y657300D01*
X1065150Y657200D01*
X1064800Y657300D01*
X1064500Y657500D01*
G01X1062550Y657200D02*
Y660200D01*
G01Y658750D02*
X1062300Y659000D01*
X1062050Y659150D01*
X1061650Y659200D01*
X1061350Y659150D01*
X1061000Y658950D01*
X1060850Y658650D01*
Y657200D01*
G01X1112233Y107040D02*
X1112483Y107165D01*
X1112775Y107248D01*
X1113108D01*
X1113483Y107123D01*
X1113775Y106915D01*
X1113983Y106665D01*
X1114150Y106248D01*
X1114192Y105873D01*
X1114108Y105498D01*
X1113983Y105248D01*
X1113733Y104998D01*
X1113442Y104831D01*
X1113150Y104748D01*
X1112858D01*
X1112567Y104831D01*
X1112317Y104956D01*
X1112108Y105123D01*
G01X1109550Y104748D02*
Y107248D01*
X1111092Y105456D01*
X1109008D01*
G01X1106950Y107248D02*
Y104748D01*
G01X1107908Y107248D02*
X1105992D01*
G01X1103350Y104748D02*
Y107248D01*
X1104892Y105456D01*
X1102808D01*
G01X1106783Y156600D02*
Y159100D01*
X1105742D01*
X1105408Y158975D01*
X1105200Y158808D01*
X1105117Y158475D01*
X1105200Y158142D01*
X1105450Y157933D01*
X1105742Y157808D01*
X1106783D01*
G01X1105742D02*
X1105117Y156600D01*
G01X1102350D02*
Y159100D01*
X1103892Y157308D01*
X1101808D01*
G01X1100583Y156600D02*
Y159100D01*
X1099583D01*
X1099250Y158975D01*
X1099000Y158683D01*
X1098917Y158350D01*
X1099000Y158017D01*
X1099208Y157767D01*
X1099583Y157642D01*
X1100583D01*
G01X1096150Y156600D02*
Y159100D01*
X1097692Y157308D01*
X1095608D01*
G01X1106783Y144600D02*
Y147100D01*
X1105742D01*
X1105408Y146975D01*
X1105200Y146808D01*
X1105117Y146475D01*
X1105200Y146142D01*
X1105450Y145933D01*
X1105742Y145808D01*
X1106783D01*
G01X1105742D02*
X1105117Y144600D01*
G01X1102350D02*
Y147100D01*
X1103892Y145308D01*
X1101808D01*
G01X1100583Y144600D02*
Y147100D01*
X1099583D01*
X1099250Y146975D01*
X1099000Y146683D01*
X1098917Y146350D01*
X1099000Y146017D01*
X1099208Y145767D01*
X1099583Y145642D01*
X1100583D01*
G01X1096733Y144600D02*
X1096650Y145142D01*
X1096525Y145600D01*
X1096358Y146017D01*
X1096150Y146475D01*
X1095817Y147100D01*
X1097483D01*
G01X1106783Y148600D02*
Y151100D01*
X1105742D01*
X1105408Y150975D01*
X1105200Y150808D01*
X1105117Y150475D01*
X1105200Y150142D01*
X1105450Y149933D01*
X1105742Y149808D01*
X1106783D01*
G01X1105742D02*
X1105117Y148600D01*
G01X1102350D02*
Y151100D01*
X1103892Y149308D01*
X1101808D01*
G01X1100583Y148600D02*
Y151100D01*
X1099583D01*
X1099250Y150975D01*
X1099000Y150683D01*
X1098917Y150350D01*
X1099000Y150017D01*
X1099208Y149767D01*
X1099583Y149642D01*
X1100583D01*
G01X1097442D02*
X1097150Y149933D01*
X1096900Y150100D01*
X1096567Y150183D01*
X1096275Y150100D01*
X1096067Y149933D01*
X1095900Y149683D01*
X1095858Y149392D01*
X1095900Y149142D01*
X1096067Y148892D01*
X1096317Y148683D01*
X1096608Y148600D01*
X1096942Y148683D01*
X1097233Y148933D01*
X1097400Y149308D01*
X1097442Y149725D01*
X1097358Y150267D01*
X1097233Y150558D01*
X1097025Y150850D01*
X1096733Y151058D01*
X1096442Y151100D01*
X1096150Y151017D01*
X1095942Y150808D01*
G01X1106783Y152600D02*
Y155100D01*
X1105742D01*
X1105408Y154975D01*
X1105200Y154808D01*
X1105117Y154475D01*
X1105200Y154142D01*
X1105450Y153933D01*
X1105742Y153808D01*
X1106783D01*
G01X1105742D02*
X1105117Y152600D01*
G01X1102350D02*
Y155100D01*
X1103892Y153308D01*
X1101808D01*
G01X1100583Y152600D02*
Y155100D01*
X1099583D01*
X1099250Y154975D01*
X1099000Y154683D01*
X1098917Y154350D01*
X1099000Y154017D01*
X1099208Y153767D01*
X1099583Y153642D01*
X1100583D01*
G01X1097567Y152975D02*
X1097317Y152767D01*
X1097025Y152642D01*
X1096650Y152600D01*
X1096275Y152683D01*
X1095983Y152850D01*
X1095775Y153142D01*
X1095733Y153475D01*
X1095817Y153808D01*
X1096025Y154017D01*
X1096317Y154183D01*
X1096608Y154225D01*
X1096900Y154183D01*
X1097275Y154017D01*
X1097150Y155100D01*
X1096025D01*
G01X1106783Y140600D02*
Y143100D01*
X1105742D01*
X1105408Y142975D01*
X1105200Y142808D01*
X1105117Y142475D01*
X1105200Y142142D01*
X1105450Y141933D01*
X1105742Y141808D01*
X1106783D01*
G01X1105742D02*
X1105117Y140600D01*
G01X1102350D02*
Y143100D01*
X1103892Y141308D01*
X1101808D01*
G01X1100583Y140600D02*
Y143100D01*
X1099583D01*
X1099250Y142975D01*
X1099000Y142683D01*
X1098917Y142350D01*
X1099000Y142017D01*
X1099208Y141767D01*
X1099583Y141642D01*
X1100583D01*
G01X1096650Y140600D02*
X1096358Y140642D01*
X1096025Y140767D01*
X1095817Y140975D01*
X1095733Y141267D01*
X1095817Y141558D01*
X1096067Y141808D01*
X1096442Y141933D01*
X1096858D01*
X1097108Y142017D01*
X1097317Y142225D01*
X1097400Y142517D01*
X1097275Y142808D01*
X1096983Y143017D01*
X1096650Y143100D01*
X1096317Y143017D01*
X1096025Y142808D01*
X1095900Y142517D01*
X1095983Y142225D01*
X1096192Y142017D01*
X1096442Y141933D01*
X1096858D01*
X1097233Y141808D01*
X1097483Y141558D01*
X1097567Y141267D01*
X1097483Y140975D01*
X1097275Y140767D01*
X1096942Y140642D01*
X1096650Y140600D01*
G01X1132683Y116367D02*
Y118867D01*
X1131642D01*
X1131308Y118742D01*
X1131100Y118575D01*
X1131017Y118242D01*
X1131100Y117909D01*
X1131350Y117700D01*
X1131642Y117575D01*
X1132683D01*
G01X1131642D02*
X1131017Y116367D01*
G01X1128250D02*
Y118867D01*
X1129792Y117075D01*
X1127708D01*
G01X1126567Y118867D02*
Y117075D01*
X1126400Y116700D01*
X1126067Y116450D01*
X1125650Y116367D01*
X1125233Y116450D01*
X1124900Y116700D01*
X1124733Y117075D01*
Y118867D01*
G01X1123342Y117409D02*
X1123050Y117700D01*
X1122800Y117867D01*
X1122467Y117950D01*
X1122175Y117867D01*
X1121967Y117700D01*
X1121800Y117450D01*
X1121758Y117159D01*
X1121800Y116909D01*
X1121967Y116659D01*
X1122217Y116450D01*
X1122508Y116367D01*
X1122842Y116450D01*
X1123133Y116700D01*
X1123300Y117075D01*
X1123342Y117492D01*
X1123258Y118034D01*
X1123133Y118325D01*
X1122925Y118617D01*
X1122633Y118825D01*
X1122342Y118867D01*
X1122050Y118784D01*
X1121842Y118575D01*
G01X1112533Y112959D02*
X1112783Y113084D01*
X1113075Y113167D01*
X1113408D01*
X1113783Y113042D01*
X1114075Y112834D01*
X1114283Y112584D01*
X1114450Y112167D01*
X1114492Y111792D01*
X1114408Y111417D01*
X1114283Y111167D01*
X1114033Y110917D01*
X1113742Y110750D01*
X1113450Y110667D01*
X1113158D01*
X1112867Y110750D01*
X1112617Y110875D01*
X1112408Y111042D01*
G01X1111267D02*
X1111017Y110834D01*
X1110725Y110709D01*
X1110350Y110667D01*
X1109975Y110750D01*
X1109683Y110917D01*
X1109475Y111209D01*
X1109433Y111542D01*
X1109517Y111875D01*
X1109725Y112084D01*
X1110017Y112250D01*
X1110308Y112292D01*
X1110600Y112250D01*
X1110975Y112084D01*
X1110850Y113167D01*
X1109725D01*
G01X1107250D02*
Y110667D01*
G01X1108208Y113167D02*
X1106292D01*
G01X1103650Y110667D02*
Y113167D01*
X1105192Y111375D01*
X1103108D01*
G01X1118175Y117200D02*
X1117842Y116992D01*
X1117467Y116867D01*
X1117133D01*
X1116800Y116992D01*
X1116550Y117200D01*
X1116425Y117492D01*
X1116508Y117784D01*
X1116717Y118034D01*
X1117092Y118200D01*
X1117592Y118284D01*
X1117883Y118450D01*
X1118008Y118742D01*
X1117925Y119034D01*
X1117717Y119242D01*
X1117425Y119367D01*
X1117133D01*
X1116842Y119284D01*
X1116592Y119075D01*
G01X1115075Y116867D02*
Y119367D01*
G01X1113325D02*
Y116867D01*
G01Y118117D02*
X1115075D01*
G01X1110600Y116867D02*
Y119367D01*
X1112142Y117575D01*
X1110058D01*
G01X1108917Y119367D02*
Y117575D01*
X1108750Y117200D01*
X1108417Y116950D01*
X1108000Y116867D01*
X1107583Y116950D01*
X1107250Y117200D01*
X1107083Y117575D01*
Y119367D01*
G01X1105692Y118950D02*
X1105442Y119200D01*
X1105150Y119325D01*
X1104817Y119367D01*
X1104400Y119284D01*
X1104108Y119075D01*
X1104025Y118825D01*
X1104067Y118575D01*
X1104233Y118367D01*
X1105067Y117950D01*
X1105442Y117659D01*
X1105692Y117242D01*
X1105775Y116867D01*
X1104025D01*
G01X1149575Y116500D02*
X1149242Y116292D01*
X1148867Y116167D01*
X1148533D01*
X1148200Y116292D01*
X1147950Y116500D01*
X1147825Y116792D01*
X1147908Y117084D01*
X1148117Y117334D01*
X1148492Y117500D01*
X1148992Y117584D01*
X1149283Y117750D01*
X1149408Y118042D01*
X1149325Y118334D01*
X1149117Y118542D01*
X1148825Y118667D01*
X1148533D01*
X1148242Y118584D01*
X1147992Y118375D01*
G01X1146475Y116167D02*
Y118667D01*
G01X1144725D02*
Y116167D01*
G01Y117417D02*
X1146475D01*
G01X1142000Y116167D02*
Y118667D01*
X1143542Y116875D01*
X1141458D01*
G01X1140317Y118667D02*
Y116875D01*
X1140150Y116500D01*
X1139817Y116250D01*
X1139400Y116167D01*
X1138983Y116250D01*
X1138650Y116500D01*
X1138483Y116875D01*
Y118667D01*
G01X1136300Y116167D02*
Y118667D01*
X1136800Y118167D01*
G01Y116167D02*
X1135800D01*
G01X1106783Y164600D02*
Y167100D01*
X1105742D01*
X1105408Y166975D01*
X1105200Y166808D01*
X1105117Y166475D01*
X1105200Y166142D01*
X1105450Y165933D01*
X1105742Y165808D01*
X1106783D01*
G01X1105742D02*
X1105117Y164600D01*
G01X1102350D02*
Y167100D01*
X1103892Y165308D01*
X1101808D01*
G01X1100583Y164600D02*
Y167100D01*
X1099583D01*
X1099250Y166975D01*
X1099000Y166683D01*
X1098917Y166350D01*
X1099000Y166017D01*
X1099208Y165767D01*
X1099583Y165642D01*
X1100583D01*
G01X1097442Y166683D02*
X1097192Y166933D01*
X1096900Y167058D01*
X1096567Y167100D01*
X1096150Y167017D01*
X1095858Y166808D01*
X1095775Y166558D01*
X1095817Y166308D01*
X1095983Y166100D01*
X1096817Y165683D01*
X1097192Y165392D01*
X1097442Y164975D01*
X1097525Y164600D01*
X1095775D01*
G01X1106783Y160600D02*
Y163100D01*
X1105742D01*
X1105408Y162975D01*
X1105200Y162808D01*
X1105117Y162475D01*
X1105200Y162142D01*
X1105450Y161933D01*
X1105742Y161808D01*
X1106783D01*
G01X1105742D02*
X1105117Y160600D01*
G01X1102350D02*
Y163100D01*
X1103892Y161308D01*
X1101808D01*
G01X1100583Y160600D02*
Y163100D01*
X1099583D01*
X1099250Y162975D01*
X1099000Y162683D01*
X1098917Y162350D01*
X1099000Y162017D01*
X1099208Y161767D01*
X1099583Y161642D01*
X1100583D01*
G01X1097567Y161100D02*
X1097317Y160808D01*
X1096983Y160642D01*
X1096608Y160600D01*
X1096275Y160642D01*
X1095942Y160850D01*
X1095733Y161100D01*
X1095692Y161350D01*
X1095775Y161642D01*
X1096067Y161850D01*
X1096358Y161933D01*
X1096733D01*
G01X1096358D02*
X1096108Y162058D01*
X1095900Y162267D01*
X1095817Y162517D01*
X1095900Y162767D01*
X1096108Y162975D01*
X1096483Y163100D01*
X1096858Y163058D01*
X1097233Y162892D01*
G01X1113100Y277400D02*
X1117200D01*
Y284400D01*
G01X1117400Y294100D02*
Y289600D01*
G01X1131206Y441575D02*
Y444075D01*
X1130165D01*
X1129831Y443950D01*
X1129623Y443783D01*
X1129540Y443450D01*
X1129623Y443117D01*
X1129873Y442908D01*
X1130165Y442783D01*
X1131206D01*
G01X1130165D02*
X1129540Y441575D01*
G01X1128065Y443658D02*
X1127815Y443908D01*
X1127523Y444033D01*
X1127190Y444075D01*
X1126773Y443992D01*
X1126481Y443783D01*
X1126398Y443533D01*
X1126440Y443283D01*
X1126606Y443075D01*
X1127440Y442658D01*
X1127815Y442367D01*
X1128065Y441950D01*
X1128148Y441575D01*
X1126398D01*
G01X1125090Y441950D02*
X1124840Y441742D01*
X1124548Y441617D01*
X1124173Y441575D01*
X1123798Y441658D01*
X1123506Y441825D01*
X1123298Y442117D01*
X1123256Y442450D01*
X1123340Y442783D01*
X1123548Y442992D01*
X1123840Y443158D01*
X1124131Y443200D01*
X1124423Y443158D01*
X1124798Y442992D01*
X1124673Y444075D01*
X1123548D01*
G01X1122323D02*
X1121740Y441575D01*
X1121073Y444075D01*
X1120406Y441575D01*
X1119823Y444075D01*
G01X1117973Y441575D02*
Y444075D01*
X1118473Y443575D01*
G01Y441575D02*
X1117473D01*
G01X1115790Y442075D02*
X1115540Y441783D01*
X1115206Y441617D01*
X1114831Y441575D01*
X1114498Y441617D01*
X1114165Y441825D01*
X1113956Y442075D01*
X1113915Y442325D01*
X1113998Y442617D01*
X1114290Y442825D01*
X1114581Y442908D01*
X1114956D01*
G01X1114581D02*
X1114331Y443033D01*
X1114123Y443242D01*
X1114040Y443492D01*
X1114123Y443742D01*
X1114331Y443950D01*
X1114706Y444075D01*
X1115081Y444033D01*
X1115456Y443867D01*
G01X1112565Y443658D02*
X1112315Y443908D01*
X1112023Y444033D01*
X1111690Y444075D01*
X1111273Y443992D01*
X1110981Y443783D01*
X1110898Y443533D01*
X1110940Y443283D01*
X1111106Y443075D01*
X1111940Y442658D01*
X1112315Y442367D01*
X1112565Y441950D01*
X1112648Y441575D01*
X1110898D01*
G01X1131206Y438075D02*
Y440575D01*
X1130165D01*
X1129831Y440450D01*
X1129623Y440283D01*
X1129540Y439950D01*
X1129623Y439617D01*
X1129873Y439408D01*
X1130165Y439283D01*
X1131206D01*
G01X1130165D02*
X1129540Y438075D01*
G01X1128065Y440158D02*
X1127815Y440408D01*
X1127523Y440533D01*
X1127190Y440575D01*
X1126773Y440492D01*
X1126481Y440283D01*
X1126398Y440033D01*
X1126440Y439783D01*
X1126606Y439575D01*
X1127440Y439158D01*
X1127815Y438867D01*
X1128065Y438450D01*
X1128148Y438075D01*
X1126398D01*
G01X1125090Y438450D02*
X1124840Y438242D01*
X1124548Y438117D01*
X1124173Y438075D01*
X1123798Y438158D01*
X1123506Y438325D01*
X1123298Y438617D01*
X1123256Y438950D01*
X1123340Y439283D01*
X1123548Y439492D01*
X1123840Y439658D01*
X1124131Y439700D01*
X1124423Y439658D01*
X1124798Y439492D01*
X1124673Y440575D01*
X1123548D01*
G01X1122323D02*
X1121740Y438075D01*
X1121073Y440575D01*
X1120406Y438075D01*
X1119823Y440575D01*
G01X1117973Y438075D02*
Y440575D01*
X1118473Y440075D01*
G01Y438075D02*
X1117473D01*
G01X1115790Y438575D02*
X1115540Y438283D01*
X1115206Y438117D01*
X1114831Y438075D01*
X1114498Y438117D01*
X1114165Y438325D01*
X1113956Y438575D01*
X1113915Y438825D01*
X1113998Y439117D01*
X1114290Y439325D01*
X1114581Y439408D01*
X1114956D01*
G01X1114581D02*
X1114331Y439533D01*
X1114123Y439742D01*
X1114040Y439992D01*
X1114123Y440242D01*
X1114331Y440450D01*
X1114706Y440575D01*
X1115081Y440533D01*
X1115456Y440367D01*
G01X1112690Y438450D02*
X1112440Y438242D01*
X1112148Y438117D01*
X1111773Y438075D01*
X1111398Y438158D01*
X1111106Y438325D01*
X1110898Y438617D01*
X1110856Y438950D01*
X1110940Y439283D01*
X1111148Y439492D01*
X1111440Y439658D01*
X1111731Y439700D01*
X1112023Y439658D01*
X1112398Y439492D01*
X1112273Y440575D01*
X1111148D01*
G01X1120736Y411007D02*
X1120986Y411132D01*
X1121278Y411215D01*
X1121611D01*
X1121986Y411090D01*
X1122278Y410882D01*
X1122486Y410632D01*
X1122653Y410215D01*
X1122695Y409840D01*
X1122611Y409465D01*
X1122486Y409215D01*
X1122236Y408965D01*
X1121945Y408798D01*
X1121653Y408715D01*
X1121361D01*
X1121070Y408798D01*
X1120820Y408923D01*
X1120611Y409090D01*
G01X1118553Y408715D02*
Y411215D01*
X1119053Y410715D01*
G01Y408715D02*
X1118053D01*
G01X1115453Y411215D02*
Y408715D01*
G01X1116411Y411215D02*
X1114495D01*
G01X1112353Y408715D02*
Y411215D01*
X1112853Y410715D01*
G01Y408715D02*
X1111853D01*
G01X1109253Y411215D02*
X1109586Y411132D01*
X1109836Y410923D01*
X1110003Y410673D01*
X1110128Y410340D01*
X1110170Y409965D01*
X1110128Y409590D01*
X1110003Y409257D01*
X1109836Y409007D01*
X1109586Y408798D01*
X1109253Y408715D01*
X1108920Y408798D01*
X1108670Y409007D01*
X1108503Y409257D01*
X1108378Y409590D01*
X1108336Y409965D01*
X1108378Y410340D01*
X1108503Y410673D01*
X1108670Y410923D01*
X1108920Y411132D01*
X1109253Y411215D01*
G01X1133676Y429207D02*
X1133926Y429332D01*
X1134218Y429415D01*
X1134551D01*
X1134926Y429290D01*
X1135218Y429082D01*
X1135426Y428832D01*
X1135593Y428415D01*
X1135635Y428040D01*
X1135551Y427665D01*
X1135426Y427415D01*
X1135176Y427165D01*
X1134885Y426998D01*
X1134593Y426915D01*
X1134301D01*
X1134010Y426998D01*
X1133760Y427123D01*
X1133551Y427290D01*
G01X1132285Y428998D02*
X1132035Y429248D01*
X1131743Y429373D01*
X1131410Y429415D01*
X1130993Y429332D01*
X1130701Y429123D01*
X1130618Y428873D01*
X1130660Y428623D01*
X1130826Y428415D01*
X1131660Y427998D01*
X1132035Y427707D01*
X1132285Y427290D01*
X1132368Y426915D01*
X1130618D01*
G01X1129310Y427290D02*
X1129060Y427082D01*
X1128768Y426957D01*
X1128393Y426915D01*
X1128018Y426998D01*
X1127726Y427165D01*
X1127518Y427457D01*
X1127476Y427790D01*
X1127560Y428123D01*
X1127768Y428332D01*
X1128060Y428498D01*
X1128351Y428540D01*
X1128643Y428498D01*
X1129018Y428332D01*
X1128893Y429415D01*
X1127768D01*
G01X1126543D02*
X1125960Y426915D01*
X1125293Y429415D01*
X1124626Y426915D01*
X1124043Y429415D01*
G01X1122901Y427207D02*
X1122610Y426998D01*
X1122276Y426915D01*
X1121943Y426998D01*
X1121651Y427248D01*
X1121443Y427623D01*
X1121360Y427998D01*
Y428457D01*
X1121443Y428832D01*
X1121651Y429165D01*
X1121901Y429332D01*
X1122193Y429415D01*
X1122526Y429332D01*
X1122776Y429165D01*
X1122943Y428915D01*
X1123026Y428582D01*
X1122943Y428290D01*
X1122735Y427998D01*
X1122485Y427832D01*
X1122193Y427790D01*
X1121860Y427873D01*
X1121610Y428082D01*
X1121360Y428457D01*
G01X1119093Y429415D02*
X1119426Y429332D01*
X1119676Y429123D01*
X1119843Y428873D01*
X1119968Y428540D01*
X1120010Y428165D01*
X1119968Y427790D01*
X1119843Y427457D01*
X1119676Y427207D01*
X1119426Y426998D01*
X1119093Y426915D01*
X1118760Y426998D01*
X1118510Y427207D01*
X1118343Y427457D01*
X1118218Y427790D01*
X1118176Y428165D01*
X1118218Y428540D01*
X1118343Y428873D01*
X1118510Y429123D01*
X1118760Y429332D01*
X1119093Y429415D01*
G01X1113205Y414862D02*
X1113330Y414612D01*
X1113413Y414320D01*
Y413987D01*
X1113288Y413612D01*
X1113080Y413320D01*
X1112830Y413112D01*
X1112413Y412945D01*
X1112038Y412903D01*
X1111663Y412987D01*
X1111413Y413112D01*
X1111163Y413362D01*
X1110996Y413653D01*
X1110913Y413945D01*
Y414237D01*
X1110996Y414528D01*
X1111121Y414778D01*
X1111288Y414987D01*
G01X1112996Y416253D02*
X1113246Y416503D01*
X1113371Y416795D01*
X1113413Y417128D01*
X1113330Y417545D01*
X1113121Y417837D01*
X1112871Y417920D01*
X1112621Y417878D01*
X1112413Y417712D01*
X1111996Y416878D01*
X1111705Y416503D01*
X1111288Y416253D01*
X1110913Y416170D01*
Y417920D01*
G01X1111288Y419228D02*
X1111080Y419478D01*
X1110955Y419770D01*
X1110913Y420145D01*
X1110996Y420520D01*
X1111163Y420812D01*
X1111455Y421020D01*
X1111788Y421062D01*
X1112121Y420978D01*
X1112330Y420770D01*
X1112496Y420478D01*
X1112538Y420187D01*
X1112496Y419895D01*
X1112330Y419520D01*
X1113413Y419645D01*
Y420770D01*
G01X1110913Y422412D02*
X1113413D01*
Y423412D01*
X1113288Y423745D01*
X1112996Y423995D01*
X1112663Y424078D01*
X1112330Y423995D01*
X1112080Y423787D01*
X1111955Y423412D01*
Y422412D01*
G01X1110913Y426345D02*
X1110955Y426637D01*
X1111080Y426970D01*
X1111288Y427178D01*
X1111580Y427262D01*
X1111871Y427178D01*
X1112121Y426928D01*
X1112246Y426553D01*
Y426137D01*
X1112330Y425887D01*
X1112538Y425678D01*
X1112830Y425595D01*
X1113121Y425720D01*
X1113330Y426012D01*
X1113413Y426345D01*
X1113330Y426678D01*
X1113121Y426970D01*
X1112830Y427095D01*
X1112538Y427012D01*
X1112330Y426803D01*
X1112246Y426553D01*
Y426137D01*
X1112121Y425762D01*
X1111871Y425512D01*
X1111580Y425428D01*
X1111288Y425512D01*
X1111080Y425720D01*
X1110955Y426053D01*
X1110913Y426345D01*
G01X1113413Y429445D02*
X1113330Y429112D01*
X1113121Y428862D01*
X1112871Y428695D01*
X1112538Y428570D01*
X1112163Y428528D01*
X1111788Y428570D01*
X1111455Y428695D01*
X1111205Y428862D01*
X1110996Y429112D01*
X1110913Y429445D01*
X1110996Y429778D01*
X1111205Y430028D01*
X1111455Y430195D01*
X1111788Y430320D01*
X1112163Y430362D01*
X1112538Y430320D01*
X1112871Y430195D01*
X1113121Y430028D01*
X1113330Y429778D01*
X1113413Y429445D01*
G01X1113203Y466169D02*
X1113453Y466294D01*
X1113745Y466377D01*
X1114078D01*
X1114453Y466252D01*
X1114745Y466044D01*
X1114953Y465794D01*
X1115120Y465377D01*
X1115162Y465002D01*
X1115078Y464627D01*
X1114953Y464377D01*
X1114703Y464127D01*
X1114412Y463960D01*
X1114120Y463877D01*
X1113828D01*
X1113537Y463960D01*
X1113287Y464085D01*
X1113078Y464252D01*
G01X1111937D02*
X1111687Y464044D01*
X1111395Y463919D01*
X1111020Y463877D01*
X1110645Y463960D01*
X1110353Y464127D01*
X1110145Y464419D01*
X1110103Y464752D01*
X1110187Y465085D01*
X1110395Y465294D01*
X1110687Y465460D01*
X1110978Y465502D01*
X1111270Y465460D01*
X1111645Y465294D01*
X1111520Y466377D01*
X1110395D01*
G01X1109003Y463877D02*
Y466377D01*
X1107920Y464294D01*
X1106837Y466377D01*
Y463877D01*
G01X1105612Y465960D02*
X1105362Y466210D01*
X1105070Y466335D01*
X1104737Y466377D01*
X1104320Y466294D01*
X1104028Y466085D01*
X1103945Y465835D01*
X1103987Y465585D01*
X1104153Y465377D01*
X1104987Y464960D01*
X1105362Y464669D01*
X1105612Y464252D01*
X1105695Y463877D01*
X1103945D01*
G01X1129909Y465815D02*
X1130159Y465940D01*
X1130451Y466023D01*
X1130784D01*
X1131159Y465898D01*
X1131451Y465690D01*
X1131659Y465440D01*
X1131826Y465023D01*
X1131868Y464648D01*
X1131784Y464273D01*
X1131659Y464023D01*
X1131409Y463773D01*
X1131118Y463606D01*
X1130826Y463523D01*
X1130534D01*
X1130243Y463606D01*
X1129993Y463731D01*
X1129784Y463898D01*
G01X1128643D02*
X1128393Y463690D01*
X1128101Y463565D01*
X1127726Y463523D01*
X1127351Y463606D01*
X1127059Y463773D01*
X1126851Y464065D01*
X1126809Y464398D01*
X1126893Y464731D01*
X1127101Y464940D01*
X1127393Y465106D01*
X1127684Y465148D01*
X1127976Y465106D01*
X1128351Y464940D01*
X1128226Y466023D01*
X1127101D01*
G01X1125709Y463523D02*
Y466023D01*
X1124626Y463940D01*
X1123543Y466023D01*
Y463523D01*
G01X1121526D02*
Y466023D01*
X1122026Y465523D01*
G01Y463523D02*
X1121026D01*
G01X1146853Y465816D02*
X1147103Y465941D01*
X1147395Y466024D01*
X1147728D01*
X1148103Y465899D01*
X1148395Y465691D01*
X1148603Y465441D01*
X1148770Y465024D01*
X1148812Y464649D01*
X1148728Y464274D01*
X1148603Y464024D01*
X1148353Y463774D01*
X1148062Y463607D01*
X1147770Y463524D01*
X1147478D01*
X1147187Y463607D01*
X1146937Y463732D01*
X1146728Y463899D01*
G01X1144170Y463524D02*
Y466024D01*
X1145712Y464232D01*
X1143628D01*
G01X1142653Y463524D02*
Y466024D01*
X1141570Y463941D01*
X1140487Y466024D01*
Y463524D01*
G01X1139262Y465607D02*
X1139012Y465857D01*
X1138720Y465982D01*
X1138387Y466024D01*
X1137970Y465941D01*
X1137678Y465732D01*
X1137595Y465482D01*
X1137637Y465232D01*
X1137803Y465024D01*
X1138637Y464607D01*
X1139012Y464316D01*
X1139262Y463899D01*
X1139345Y463524D01*
X1137595D01*
G01X1135345Y432852D02*
X1135470Y432602D01*
X1135553Y432310D01*
Y431977D01*
X1135428Y431602D01*
X1135220Y431310D01*
X1134970Y431102D01*
X1134553Y430935D01*
X1134178Y430893D01*
X1133803Y430977D01*
X1133553Y431102D01*
X1133303Y431352D01*
X1133136Y431643D01*
X1133053Y431935D01*
Y432227D01*
X1133136Y432518D01*
X1133261Y432768D01*
X1133428Y432977D01*
G01X1133053Y434202D02*
X1135553D01*
Y435243D01*
X1135428Y435577D01*
X1135261Y435785D01*
X1134928Y435868D01*
X1134595Y435785D01*
X1134386Y435535D01*
X1134261Y435243D01*
Y434202D01*
G01Y435243D02*
X1133053Y435868D01*
G01X1135136Y437343D02*
X1135386Y437593D01*
X1135511Y437885D01*
X1135553Y438218D01*
X1135470Y438635D01*
X1135261Y438927D01*
X1135011Y439010D01*
X1134761Y438968D01*
X1134553Y438802D01*
X1134136Y437968D01*
X1133845Y437593D01*
X1133428Y437343D01*
X1133053Y437260D01*
Y439010D01*
G01X1133428Y440318D02*
X1133220Y440568D01*
X1133095Y440860D01*
X1133053Y441235D01*
X1133136Y441610D01*
X1133303Y441902D01*
X1133595Y442110D01*
X1133928Y442152D01*
X1134261Y442068D01*
X1134470Y441860D01*
X1134636Y441568D01*
X1134678Y441277D01*
X1134636Y440985D01*
X1134470Y440610D01*
X1135553Y440735D01*
Y441860D01*
G01Y443085D02*
X1133053Y443668D01*
X1135553Y444335D01*
X1133053Y445002D01*
X1135553Y445585D01*
G01X1135136Y446643D02*
X1135386Y446893D01*
X1135511Y447185D01*
X1135553Y447518D01*
X1135470Y447935D01*
X1135261Y448227D01*
X1135011Y448310D01*
X1134761Y448268D01*
X1134553Y448102D01*
X1134136Y447268D01*
X1133845Y446893D01*
X1133428Y446643D01*
X1133053Y446560D01*
Y448310D01*
G01X1109913Y413028D02*
X1108121D01*
X1107746Y413195D01*
X1107496Y413528D01*
X1107413Y413945D01*
X1107496Y414362D01*
X1107746Y414695D01*
X1108121Y414862D01*
X1109913D01*
G01X1109496Y416253D02*
X1109746Y416503D01*
X1109871Y416795D01*
X1109913Y417128D01*
X1109830Y417545D01*
X1109621Y417837D01*
X1109371Y417920D01*
X1109121Y417878D01*
X1108913Y417712D01*
X1108496Y416878D01*
X1108205Y416503D01*
X1107788Y416253D01*
X1107413Y416170D01*
Y417920D01*
G01X1107788Y419228D02*
X1107580Y419478D01*
X1107455Y419770D01*
X1107413Y420145D01*
X1107496Y420520D01*
X1107663Y420812D01*
X1107955Y421020D01*
X1108288Y421062D01*
X1108621Y420978D01*
X1108830Y420770D01*
X1108996Y420478D01*
X1109038Y420187D01*
X1108996Y419895D01*
X1108830Y419520D01*
X1109913Y419645D01*
Y420770D01*
G01Y421995D02*
X1107413Y422578D01*
X1109913Y423245D01*
X1107413Y423912D01*
X1109913Y424495D01*
G01X1107413Y426262D02*
X1107955Y426345D01*
X1108413Y426470D01*
X1108830Y426637D01*
X1109288Y426845D01*
X1109913Y427178D01*
Y425512D01*
G01X1116913Y413028D02*
X1115121D01*
X1114746Y413195D01*
X1114496Y413528D01*
X1114413Y413945D01*
X1114496Y414362D01*
X1114746Y414695D01*
X1115121Y414862D01*
X1116913D01*
G01X1116496Y416253D02*
X1116746Y416503D01*
X1116871Y416795D01*
X1116913Y417128D01*
X1116830Y417545D01*
X1116621Y417837D01*
X1116371Y417920D01*
X1116121Y417878D01*
X1115913Y417712D01*
X1115496Y416878D01*
X1115205Y416503D01*
X1114788Y416253D01*
X1114413Y416170D01*
Y417920D01*
G01X1114788Y419228D02*
X1114580Y419478D01*
X1114455Y419770D01*
X1114413Y420145D01*
X1114496Y420520D01*
X1114663Y420812D01*
X1114955Y421020D01*
X1115288Y421062D01*
X1115621Y420978D01*
X1115830Y420770D01*
X1115996Y420478D01*
X1116038Y420187D01*
X1115996Y419895D01*
X1115830Y419520D01*
X1116913Y419645D01*
Y420770D01*
G01Y421995D02*
X1114413Y422578D01*
X1116913Y423245D01*
X1114413Y423912D01*
X1116913Y424495D01*
G01X1114413Y426345D02*
X1114455Y426637D01*
X1114580Y426970D01*
X1114788Y427178D01*
X1115080Y427262D01*
X1115371Y427178D01*
X1115621Y426928D01*
X1115746Y426553D01*
Y426137D01*
X1115830Y425887D01*
X1116038Y425678D01*
X1116330Y425595D01*
X1116621Y425720D01*
X1116830Y426012D01*
X1116913Y426345D01*
X1116830Y426678D01*
X1116621Y426970D01*
X1116330Y427095D01*
X1116038Y427012D01*
X1115830Y426803D01*
X1115746Y426553D01*
Y426137D01*
X1115621Y425762D01*
X1115371Y425512D01*
X1115080Y425428D01*
X1114788Y425512D01*
X1114580Y425720D01*
X1114455Y426053D01*
X1114413Y426345D01*
G01X1146853Y469816D02*
X1147103Y469941D01*
X1147395Y470024D01*
X1147728D01*
X1148103Y469899D01*
X1148395Y469691D01*
X1148603Y469441D01*
X1148770Y469024D01*
X1148812Y468649D01*
X1148728Y468274D01*
X1148603Y468024D01*
X1148353Y467774D01*
X1148062Y467607D01*
X1147770Y467524D01*
X1147478D01*
X1147187Y467607D01*
X1146937Y467732D01*
X1146728Y467899D01*
G01X1145587D02*
X1145337Y467691D01*
X1145045Y467566D01*
X1144670Y467524D01*
X1144295Y467607D01*
X1144003Y467774D01*
X1143795Y468066D01*
X1143753Y468399D01*
X1143837Y468732D01*
X1144045Y468941D01*
X1144337Y469107D01*
X1144628Y469149D01*
X1144920Y469107D01*
X1145295Y468941D01*
X1145170Y470024D01*
X1144045D01*
G01X1141320Y468774D02*
X1140487D01*
Y468024D01*
X1140737Y467774D01*
X1141028Y467607D01*
X1141445Y467524D01*
X1141862Y467607D01*
X1142153Y467774D01*
X1142403Y468024D01*
X1142570Y468316D01*
X1142653Y468649D01*
Y468941D01*
X1142570Y469191D01*
X1142403Y469482D01*
X1142153Y469732D01*
X1141903Y469899D01*
X1141570Y470024D01*
X1141278D01*
X1140945Y469941D01*
X1140695Y469774D01*
G01X1138553Y467524D02*
X1138470Y468066D01*
X1138345Y468524D01*
X1138178Y468941D01*
X1137970Y469399D01*
X1137637Y470024D01*
X1139303D01*
G01X1136162Y468566D02*
X1135870Y468857D01*
X1135620Y469024D01*
X1135287Y469107D01*
X1134995Y469024D01*
X1134787Y468857D01*
X1134620Y468607D01*
X1134578Y468316D01*
X1134620Y468066D01*
X1134787Y467816D01*
X1135037Y467607D01*
X1135328Y467524D01*
X1135662Y467607D01*
X1135953Y467857D01*
X1136120Y468232D01*
X1136162Y468649D01*
X1136078Y469191D01*
X1135953Y469482D01*
X1135745Y469774D01*
X1135453Y469982D01*
X1135162Y470024D01*
X1134870Y469941D01*
X1134662Y469732D01*
G01X1129909Y469815D02*
X1130159Y469940D01*
X1130451Y470023D01*
X1130784D01*
X1131159Y469898D01*
X1131451Y469690D01*
X1131659Y469440D01*
X1131826Y469023D01*
X1131868Y468648D01*
X1131784Y468273D01*
X1131659Y468023D01*
X1131409Y467773D01*
X1131118Y467606D01*
X1130826Y467523D01*
X1130534D01*
X1130243Y467606D01*
X1129993Y467731D01*
X1129784Y467898D01*
G01X1128643D02*
X1128393Y467690D01*
X1128101Y467565D01*
X1127726Y467523D01*
X1127351Y467606D01*
X1127059Y467773D01*
X1126851Y468065D01*
X1126809Y468398D01*
X1126893Y468731D01*
X1127101Y468940D01*
X1127393Y469106D01*
X1127684Y469148D01*
X1127976Y469106D01*
X1128351Y468940D01*
X1128226Y470023D01*
X1127101D01*
G01X1124376Y468773D02*
X1123543D01*
Y468023D01*
X1123793Y467773D01*
X1124084Y467606D01*
X1124501Y467523D01*
X1124918Y467606D01*
X1125209Y467773D01*
X1125459Y468023D01*
X1125626Y468315D01*
X1125709Y468648D01*
Y468940D01*
X1125626Y469190D01*
X1125459Y469481D01*
X1125209Y469731D01*
X1124959Y469898D01*
X1124626Y470023D01*
X1124334D01*
X1124001Y469940D01*
X1123751Y469773D01*
G01X1121609Y467523D02*
X1121526Y468065D01*
X1121401Y468523D01*
X1121234Y468940D01*
X1121026Y469398D01*
X1120693Y470023D01*
X1122359D01*
G01X1119343Y467898D02*
X1119093Y467690D01*
X1118801Y467565D01*
X1118426Y467523D01*
X1118051Y467606D01*
X1117759Y467773D01*
X1117551Y468065D01*
X1117509Y468398D01*
X1117593Y468731D01*
X1117801Y468940D01*
X1118093Y469106D01*
X1118384Y469148D01*
X1118676Y469106D01*
X1119051Y468940D01*
X1118926Y470023D01*
X1117801D01*
G01X1129909Y477815D02*
X1130159Y477940D01*
X1130451Y478023D01*
X1130784D01*
X1131159Y477898D01*
X1131451Y477690D01*
X1131659Y477440D01*
X1131826Y477023D01*
X1131868Y476648D01*
X1131784Y476273D01*
X1131659Y476023D01*
X1131409Y475773D01*
X1131118Y475606D01*
X1130826Y475523D01*
X1130534D01*
X1130243Y475606D01*
X1129993Y475731D01*
X1129784Y475898D01*
G01X1128643D02*
X1128393Y475690D01*
X1128101Y475565D01*
X1127726Y475523D01*
X1127351Y475606D01*
X1127059Y475773D01*
X1126851Y476065D01*
X1126809Y476398D01*
X1126893Y476731D01*
X1127101Y476940D01*
X1127393Y477106D01*
X1127684Y477148D01*
X1127976Y477106D01*
X1128351Y476940D01*
X1128226Y478023D01*
X1127101D01*
G01X1124376Y476773D02*
X1123543D01*
Y476023D01*
X1123793Y475773D01*
X1124084Y475606D01*
X1124501Y475523D01*
X1124918Y475606D01*
X1125209Y475773D01*
X1125459Y476023D01*
X1125626Y476315D01*
X1125709Y476648D01*
Y476940D01*
X1125626Y477190D01*
X1125459Y477481D01*
X1125209Y477731D01*
X1124959Y477898D01*
X1124626Y478023D01*
X1124334D01*
X1124001Y477940D01*
X1123751Y477773D01*
G01X1121609Y475523D02*
X1121526Y476065D01*
X1121401Y476523D01*
X1121234Y476940D01*
X1121026Y477398D01*
X1120693Y478023D01*
X1122359D01*
G01X1118426Y475523D02*
Y478023D01*
X1118926Y477523D01*
G01Y475523D02*
X1117926D01*
G01X1146853Y477816D02*
X1147103Y477941D01*
X1147395Y478024D01*
X1147728D01*
X1148103Y477899D01*
X1148395Y477691D01*
X1148603Y477441D01*
X1148770Y477024D01*
X1148812Y476649D01*
X1148728Y476274D01*
X1148603Y476024D01*
X1148353Y475774D01*
X1148062Y475607D01*
X1147770Y475524D01*
X1147478D01*
X1147187Y475607D01*
X1146937Y475732D01*
X1146728Y475899D01*
G01X1145587D02*
X1145337Y475691D01*
X1145045Y475566D01*
X1144670Y475524D01*
X1144295Y475607D01*
X1144003Y475774D01*
X1143795Y476066D01*
X1143753Y476399D01*
X1143837Y476732D01*
X1144045Y476941D01*
X1144337Y477107D01*
X1144628Y477149D01*
X1144920Y477107D01*
X1145295Y476941D01*
X1145170Y478024D01*
X1144045D01*
G01X1141320Y476774D02*
X1140487D01*
Y476024D01*
X1140737Y475774D01*
X1141028Y475607D01*
X1141445Y475524D01*
X1141862Y475607D01*
X1142153Y475774D01*
X1142403Y476024D01*
X1142570Y476316D01*
X1142653Y476649D01*
Y476941D01*
X1142570Y477191D01*
X1142403Y477482D01*
X1142153Y477732D01*
X1141903Y477899D01*
X1141570Y478024D01*
X1141278D01*
X1140945Y477941D01*
X1140695Y477774D01*
G01X1138553Y475524D02*
X1138470Y476066D01*
X1138345Y476524D01*
X1138178Y476941D01*
X1137970Y477399D01*
X1137637Y478024D01*
X1139303D01*
G01X1136162Y477607D02*
X1135912Y477857D01*
X1135620Y477982D01*
X1135287Y478024D01*
X1134870Y477941D01*
X1134578Y477732D01*
X1134495Y477482D01*
X1134537Y477232D01*
X1134703Y477024D01*
X1135537Y476607D01*
X1135912Y476316D01*
X1136162Y475899D01*
X1136245Y475524D01*
X1134495D01*
G01X1113203Y470169D02*
X1113453Y470294D01*
X1113745Y470377D01*
X1114078D01*
X1114453Y470252D01*
X1114745Y470044D01*
X1114953Y469794D01*
X1115120Y469377D01*
X1115162Y469002D01*
X1115078Y468627D01*
X1114953Y468377D01*
X1114703Y468127D01*
X1114412Y467960D01*
X1114120Y467877D01*
X1113828D01*
X1113537Y467960D01*
X1113287Y468085D01*
X1113078Y468252D01*
G01X1111937D02*
X1111687Y468044D01*
X1111395Y467919D01*
X1111020Y467877D01*
X1110645Y467960D01*
X1110353Y468127D01*
X1110145Y468419D01*
X1110103Y468752D01*
X1110187Y469085D01*
X1110395Y469294D01*
X1110687Y469460D01*
X1110978Y469502D01*
X1111270Y469460D01*
X1111645Y469294D01*
X1111520Y470377D01*
X1110395D01*
G01X1107670Y469127D02*
X1106837D01*
Y468377D01*
X1107087Y468127D01*
X1107378Y467960D01*
X1107795Y467877D01*
X1108212Y467960D01*
X1108503Y468127D01*
X1108753Y468377D01*
X1108920Y468669D01*
X1109003Y469002D01*
Y469294D01*
X1108920Y469544D01*
X1108753Y469835D01*
X1108503Y470085D01*
X1108253Y470252D01*
X1107920Y470377D01*
X1107628D01*
X1107295Y470294D01*
X1107045Y470127D01*
G01X1104903Y467877D02*
X1104820Y468419D01*
X1104695Y468877D01*
X1104528Y469294D01*
X1104320Y469752D01*
X1103987Y470377D01*
X1105653D01*
G01X1101220Y467877D02*
Y470377D01*
X1102762Y468585D01*
X1100678D01*
G01X1113203Y478169D02*
X1113453Y478294D01*
X1113745Y478377D01*
X1114078D01*
X1114453Y478252D01*
X1114745Y478044D01*
X1114953Y477794D01*
X1115120Y477377D01*
X1115162Y477002D01*
X1115078Y476627D01*
X1114953Y476377D01*
X1114703Y476127D01*
X1114412Y475960D01*
X1114120Y475877D01*
X1113828D01*
X1113537Y475960D01*
X1113287Y476085D01*
X1113078Y476252D01*
G01X1111937D02*
X1111687Y476044D01*
X1111395Y475919D01*
X1111020Y475877D01*
X1110645Y475960D01*
X1110353Y476127D01*
X1110145Y476419D01*
X1110103Y476752D01*
X1110187Y477085D01*
X1110395Y477294D01*
X1110687Y477460D01*
X1110978Y477502D01*
X1111270Y477460D01*
X1111645Y477294D01*
X1111520Y478377D01*
X1110395D01*
G01X1107670Y477127D02*
X1106837D01*
Y476377D01*
X1107087Y476127D01*
X1107378Y475960D01*
X1107795Y475877D01*
X1108212Y475960D01*
X1108503Y476127D01*
X1108753Y476377D01*
X1108920Y476669D01*
X1109003Y477002D01*
Y477294D01*
X1108920Y477544D01*
X1108753Y477835D01*
X1108503Y478085D01*
X1108253Y478252D01*
X1107920Y478377D01*
X1107628D01*
X1107295Y478294D01*
X1107045Y478127D01*
G01X1104903Y475877D02*
X1104820Y476419D01*
X1104695Y476877D01*
X1104528Y477294D01*
X1104320Y477752D01*
X1103987Y478377D01*
X1105653D01*
G01X1101720D02*
X1102053Y478294D01*
X1102303Y478085D01*
X1102470Y477835D01*
X1102595Y477502D01*
X1102637Y477127D01*
X1102595Y476752D01*
X1102470Y476419D01*
X1102303Y476169D01*
X1102053Y475960D01*
X1101720Y475877D01*
X1101387Y475960D01*
X1101137Y476169D01*
X1100970Y476419D01*
X1100845Y476752D01*
X1100803Y477127D01*
X1100845Y477502D01*
X1100970Y477835D01*
X1101137Y478085D01*
X1101387Y478294D01*
X1101720Y478377D01*
G01X1108733Y495959D02*
X1108983Y496084D01*
X1109275Y496167D01*
X1109608D01*
X1109983Y496042D01*
X1110275Y495834D01*
X1110483Y495584D01*
X1110650Y495167D01*
X1110692Y494792D01*
X1110608Y494417D01*
X1110483Y494167D01*
X1110233Y493917D01*
X1109942Y493750D01*
X1109650Y493667D01*
X1109358D01*
X1109067Y493750D01*
X1108817Y493875D01*
X1108608Y494042D01*
G01X1106050Y493667D02*
Y496167D01*
X1107592Y494375D01*
X1105508D01*
G01X1104533Y493667D02*
Y496167D01*
X1103450Y494084D01*
X1102367Y496167D01*
Y493667D01*
G01X1101267Y494042D02*
X1101017Y493834D01*
X1100725Y493709D01*
X1100350Y493667D01*
X1099975Y493750D01*
X1099683Y493917D01*
X1099475Y494209D01*
X1099433Y494542D01*
X1099517Y494875D01*
X1099725Y495084D01*
X1100017Y495250D01*
X1100308Y495292D01*
X1100600Y495250D01*
X1100975Y495084D01*
X1100850Y496167D01*
X1099725D01*
G01X1113203Y474169D02*
X1113453Y474294D01*
X1113745Y474377D01*
X1114078D01*
X1114453Y474252D01*
X1114745Y474044D01*
X1114953Y473794D01*
X1115120Y473377D01*
X1115162Y473002D01*
X1115078Y472627D01*
X1114953Y472377D01*
X1114703Y472127D01*
X1114412Y471960D01*
X1114120Y471877D01*
X1113828D01*
X1113537Y471960D01*
X1113287Y472085D01*
X1113078Y472252D01*
G01X1111937D02*
X1111687Y472044D01*
X1111395Y471919D01*
X1111020Y471877D01*
X1110645Y471960D01*
X1110353Y472127D01*
X1110145Y472419D01*
X1110103Y472752D01*
X1110187Y473085D01*
X1110395Y473294D01*
X1110687Y473460D01*
X1110978Y473502D01*
X1111270Y473460D01*
X1111645Y473294D01*
X1111520Y474377D01*
X1110395D01*
G01X1108753D02*
Y471877D01*
X1107087D01*
G01X1104820D02*
X1104528Y471919D01*
X1104195Y472044D01*
X1103987Y472252D01*
X1103903Y472544D01*
X1103987Y472835D01*
X1104237Y473085D01*
X1104612Y473210D01*
X1105028D01*
X1105278Y473294D01*
X1105487Y473502D01*
X1105570Y473794D01*
X1105445Y474085D01*
X1105153Y474294D01*
X1104820Y474377D01*
X1104487Y474294D01*
X1104195Y474085D01*
X1104070Y473794D01*
X1104153Y473502D01*
X1104362Y473294D01*
X1104612Y473210D01*
X1105028D01*
X1105403Y473085D01*
X1105653Y472835D01*
X1105737Y472544D01*
X1105653Y472252D01*
X1105445Y472044D01*
X1105112Y471919D01*
X1104820Y471877D01*
G01X1129909Y473815D02*
X1130159Y473940D01*
X1130451Y474023D01*
X1130784D01*
X1131159Y473898D01*
X1131451Y473690D01*
X1131659Y473440D01*
X1131826Y473023D01*
X1131868Y472648D01*
X1131784Y472273D01*
X1131659Y472023D01*
X1131409Y471773D01*
X1131118Y471606D01*
X1130826Y471523D01*
X1130534D01*
X1130243Y471606D01*
X1129993Y471731D01*
X1129784Y471898D01*
G01X1128643D02*
X1128393Y471690D01*
X1128101Y471565D01*
X1127726Y471523D01*
X1127351Y471606D01*
X1127059Y471773D01*
X1126851Y472065D01*
X1126809Y472398D01*
X1126893Y472731D01*
X1127101Y472940D01*
X1127393Y473106D01*
X1127684Y473148D01*
X1127976Y473106D01*
X1128351Y472940D01*
X1128226Y474023D01*
X1127101D01*
G01X1125459D02*
Y471523D01*
X1123793D01*
G01X1121609D02*
X1121526Y472065D01*
X1121401Y472523D01*
X1121234Y472940D01*
X1121026Y473398D01*
X1120693Y474023D01*
X1122359D01*
G01X1146853Y473816D02*
X1147103Y473941D01*
X1147395Y474024D01*
X1147728D01*
X1148103Y473899D01*
X1148395Y473691D01*
X1148603Y473441D01*
X1148770Y473024D01*
X1148812Y472649D01*
X1148728Y472274D01*
X1148603Y472024D01*
X1148353Y471774D01*
X1148062Y471607D01*
X1147770Y471524D01*
X1147478D01*
X1147187Y471607D01*
X1146937Y471732D01*
X1146728Y471899D01*
G01X1145587D02*
X1145337Y471691D01*
X1145045Y471566D01*
X1144670Y471524D01*
X1144295Y471607D01*
X1144003Y471774D01*
X1143795Y472066D01*
X1143753Y472399D01*
X1143837Y472732D01*
X1144045Y472941D01*
X1144337Y473107D01*
X1144628Y473149D01*
X1144920Y473107D01*
X1145295Y472941D01*
X1145170Y474024D01*
X1144045D01*
G01X1142403D02*
Y471524D01*
X1140737D01*
G01X1139262Y472566D02*
X1138970Y472857D01*
X1138720Y473024D01*
X1138387Y473107D01*
X1138095Y473024D01*
X1137887Y472857D01*
X1137720Y472607D01*
X1137678Y472316D01*
X1137720Y472066D01*
X1137887Y471816D01*
X1138137Y471607D01*
X1138428Y471524D01*
X1138762Y471607D01*
X1139053Y471857D01*
X1139220Y472232D01*
X1139262Y472649D01*
X1139178Y473191D01*
X1139053Y473482D01*
X1138845Y473774D01*
X1138553Y473982D01*
X1138262Y474024D01*
X1137970Y473941D01*
X1137762Y473732D01*
G01X1116381Y616974D02*
X1116631Y617099D01*
X1116923Y617182D01*
X1117256D01*
X1117631Y617057D01*
X1117923Y616849D01*
X1118131Y616599D01*
X1118298Y616182D01*
X1118340Y615807D01*
X1118256Y615432D01*
X1118131Y615182D01*
X1117881Y614932D01*
X1117590Y614765D01*
X1117298Y614682D01*
X1117006D01*
X1116715Y614765D01*
X1116465Y614890D01*
X1116256Y615057D01*
G01X1115115D02*
X1114865Y614849D01*
X1114573Y614724D01*
X1114198Y614682D01*
X1113823Y614765D01*
X1113531Y614932D01*
X1113323Y615224D01*
X1113281Y615557D01*
X1113365Y615890D01*
X1113573Y616099D01*
X1113865Y616265D01*
X1114156Y616307D01*
X1114448Y616265D01*
X1114823Y616099D01*
X1114698Y617182D01*
X1113573D01*
G01X1111931D02*
Y614682D01*
X1110265D01*
G01X1107998D02*
Y617182D01*
X1108498Y616682D01*
G01Y614682D02*
X1107498D01*
G01X1108911Y620343D02*
X1109161Y620468D01*
X1109453Y620551D01*
X1109786D01*
X1110161Y620426D01*
X1110453Y620218D01*
X1110661Y619968D01*
X1110828Y619551D01*
X1110870Y619176D01*
X1110786Y618801D01*
X1110661Y618551D01*
X1110411Y618301D01*
X1110120Y618134D01*
X1109828Y618051D01*
X1109536D01*
X1109245Y618134D01*
X1108995Y618259D01*
X1108786Y618426D01*
G01X1107645D02*
X1107395Y618218D01*
X1107103Y618093D01*
X1106728Y618051D01*
X1106353Y618134D01*
X1106061Y618301D01*
X1105853Y618593D01*
X1105811Y618926D01*
X1105895Y619259D01*
X1106103Y619468D01*
X1106395Y619634D01*
X1106686Y619676D01*
X1106978Y619634D01*
X1107353Y619468D01*
X1107228Y620551D01*
X1106103D01*
G01X1104461D02*
Y618051D01*
X1102795D01*
G01X1101320Y620134D02*
X1101070Y620384D01*
X1100778Y620509D01*
X1100445Y620551D01*
X1100028Y620468D01*
X1099736Y620259D01*
X1099653Y620009D01*
X1099695Y619759D01*
X1099861Y619551D01*
X1100695Y619134D01*
X1101070Y618843D01*
X1101320Y618426D01*
X1101403Y618051D01*
X1099653D01*
G01X1215149Y33100D02*
X1215399Y33225D01*
X1215691Y33308D01*
X1216024D01*
X1216399Y33183D01*
X1216691Y32975D01*
X1216899Y32725D01*
X1217066Y32308D01*
X1217108Y31933D01*
X1217024Y31558D01*
X1216899Y31308D01*
X1216649Y31058D01*
X1216358Y30891D01*
X1216066Y30808D01*
X1215774D01*
X1215483Y30891D01*
X1215233Y31016D01*
X1215024Y31183D01*
G01X1212466Y30808D02*
Y33308D01*
X1214008Y31516D01*
X1211924D01*
G01X1210783Y33308D02*
Y31516D01*
X1210616Y31141D01*
X1210283Y30891D01*
X1209866Y30808D01*
X1209449Y30891D01*
X1209116Y31141D01*
X1208949Y31516D01*
Y33308D01*
G01X1207558Y32891D02*
X1207308Y33141D01*
X1207016Y33266D01*
X1206683Y33308D01*
X1206266Y33225D01*
X1205974Y33016D01*
X1205891Y32766D01*
X1205933Y32516D01*
X1206099Y32308D01*
X1206933Y31891D01*
X1207308Y31600D01*
X1207558Y31183D01*
X1207641Y30808D01*
X1205891D01*
G01X1221509Y70636D02*
X1221759Y70761D01*
X1222051Y70844D01*
X1222384D01*
X1222759Y70719D01*
X1223051Y70511D01*
X1223259Y70261D01*
X1223426Y69844D01*
X1223468Y69469D01*
X1223384Y69094D01*
X1223259Y68844D01*
X1223009Y68594D01*
X1222718Y68427D01*
X1222426Y68344D01*
X1222134D01*
X1221843Y68427D01*
X1221593Y68552D01*
X1221384Y68719D01*
G01X1218826Y68344D02*
Y70844D01*
X1220368Y69052D01*
X1218284D01*
G01X1216226Y70844D02*
Y68344D01*
G01X1217184Y70844D02*
X1215268D01*
G01X1213918Y69386D02*
X1213626Y69677D01*
X1213376Y69844D01*
X1213043Y69927D01*
X1212751Y69844D01*
X1212543Y69677D01*
X1212376Y69427D01*
X1212334Y69136D01*
X1212376Y68886D01*
X1212543Y68636D01*
X1212793Y68427D01*
X1213084Y68344D01*
X1213418Y68427D01*
X1213709Y68677D01*
X1213876Y69052D01*
X1213918Y69469D01*
X1213834Y70011D01*
X1213709Y70302D01*
X1213501Y70594D01*
X1213209Y70802D01*
X1212918Y70844D01*
X1212626Y70761D01*
X1212418Y70552D01*
G01X1211824Y127650D02*
Y121506D01*
X1184730D01*
G01X1172177Y133520D02*
Y207606D01*
X1198977D01*
Y210406D01*
X1222877D01*
Y150806D01*
X1211824D01*
Y140210D01*
G01X1213766Y109356D02*
X1216266D01*
Y110397D01*
X1216141Y110731D01*
X1215974Y110939D01*
X1215641Y111022D01*
X1215308Y110939D01*
X1215099Y110689D01*
X1214974Y110397D01*
Y109356D01*
G01Y110397D02*
X1213766Y111022D01*
G01Y113289D02*
X1213808Y113581D01*
X1213933Y113914D01*
X1214141Y114122D01*
X1214433Y114206D01*
X1214724Y114122D01*
X1214974Y113872D01*
X1215099Y113497D01*
Y113081D01*
X1215183Y112831D01*
X1215391Y112622D01*
X1215683Y112539D01*
X1215974Y112664D01*
X1216183Y112956D01*
X1216266Y113289D01*
X1216183Y113622D01*
X1215974Y113914D01*
X1215683Y114039D01*
X1215391Y113956D01*
X1215183Y113747D01*
X1215099Y113497D01*
Y113081D01*
X1214974Y112706D01*
X1214724Y112456D01*
X1214433Y112372D01*
X1214141Y112456D01*
X1213933Y112664D01*
X1213808Y112997D01*
X1213766Y113289D01*
G01Y115472D02*
X1216266D01*
Y116306D01*
X1216141Y116639D01*
X1215974Y116889D01*
X1215724Y117097D01*
X1215433Y117264D01*
X1215016Y117306D01*
X1214599Y117264D01*
X1214308Y117097D01*
X1214058Y116889D01*
X1213891Y116639D01*
X1213766Y116306D01*
Y115472D01*
G01X1214266Y118572D02*
X1213974Y118822D01*
X1213808Y119156D01*
X1213766Y119531D01*
X1213808Y119864D01*
X1214016Y120197D01*
X1214266Y120406D01*
X1214516Y120447D01*
X1214808Y120364D01*
X1215016Y120072D01*
X1215099Y119781D01*
Y119406D01*
G01Y119781D02*
X1215224Y120031D01*
X1215433Y120239D01*
X1215683Y120322D01*
X1215933Y120239D01*
X1216141Y120031D01*
X1216266Y119656D01*
X1216224Y119281D01*
X1216058Y118906D01*
G01X1213766Y122589D02*
X1216266D01*
X1215766Y122089D01*
G01X1213766D02*
Y123089D01*
G01X1182779Y142634D02*
X1185279D01*
Y143675D01*
X1185154Y144009D01*
X1184987Y144217D01*
X1184654Y144300D01*
X1184321Y144217D01*
X1184112Y143967D01*
X1183987Y143675D01*
Y142634D01*
G01Y143675D02*
X1182779Y144300D01*
G01X1184862Y145775D02*
X1185112Y146025D01*
X1185237Y146317D01*
X1185279Y146650D01*
X1185196Y147067D01*
X1184987Y147359D01*
X1184737Y147442D01*
X1184487Y147400D01*
X1184279Y147234D01*
X1183862Y146400D01*
X1183571Y146025D01*
X1183154Y145775D01*
X1182779Y145692D01*
Y147442D01*
G01X1185279Y149667D02*
X1182779D01*
G01X1185279Y148709D02*
Y150625D01*
G01X1183279Y151850D02*
X1182987Y152100D01*
X1182821Y152434D01*
X1182779Y152809D01*
X1182821Y153142D01*
X1183029Y153475D01*
X1183279Y153684D01*
X1183529Y153725D01*
X1183821Y153642D01*
X1184029Y153350D01*
X1184112Y153059D01*
Y152684D01*
G01Y153059D02*
X1184237Y153309D01*
X1184446Y153517D01*
X1184696Y153600D01*
X1184946Y153517D01*
X1185154Y153309D01*
X1185279Y152934D01*
X1185237Y152559D01*
X1185071Y152184D01*
G01X1182779Y155867D02*
X1185279D01*
X1184779Y155367D01*
G01X1182779D02*
Y156367D01*
G01X1191919Y136144D02*
X1194419D01*
Y137185D01*
X1194294Y137519D01*
X1194127Y137727D01*
X1193794Y137810D01*
X1193461Y137727D01*
X1193252Y137477D01*
X1193127Y137185D01*
Y136144D01*
G01Y137185D02*
X1191919Y137810D01*
G01X1194002Y139285D02*
X1194252Y139535D01*
X1194377Y139827D01*
X1194419Y140160D01*
X1194336Y140577D01*
X1194127Y140869D01*
X1193877Y140952D01*
X1193627Y140910D01*
X1193419Y140744D01*
X1193002Y139910D01*
X1192711Y139535D01*
X1192294Y139285D01*
X1191919Y139202D01*
Y140952D01*
G01X1194419Y143177D02*
X1191919D01*
G01X1194419Y142219D02*
Y144135D01*
G01X1194002Y145485D02*
X1194252Y145735D01*
X1194377Y146027D01*
X1194419Y146360D01*
X1194336Y146777D01*
X1194127Y147069D01*
X1193877Y147152D01*
X1193627Y147110D01*
X1193419Y146944D01*
X1193002Y146110D01*
X1192711Y145735D01*
X1192294Y145485D01*
X1191919Y145402D01*
Y147152D01*
G01X1192961Y148585D02*
X1193252Y148877D01*
X1193419Y149127D01*
X1193502Y149460D01*
X1193419Y149752D01*
X1193252Y149960D01*
X1193002Y150127D01*
X1192711Y150169D01*
X1192461Y150127D01*
X1192211Y149960D01*
X1192002Y149710D01*
X1191919Y149419D01*
X1192002Y149085D01*
X1192252Y148794D01*
X1192627Y148627D01*
X1193044Y148585D01*
X1193586Y148669D01*
X1193877Y148794D01*
X1194169Y149002D01*
X1194377Y149294D01*
X1194419Y149585D01*
X1194336Y149877D01*
X1194127Y150085D01*
G01X1203919Y136144D02*
X1206419D01*
Y137185D01*
X1206294Y137519D01*
X1206127Y137727D01*
X1205794Y137810D01*
X1205461Y137727D01*
X1205252Y137477D01*
X1205127Y137185D01*
Y136144D01*
G01Y137185D02*
X1203919Y137810D01*
G01X1206002Y139285D02*
X1206252Y139535D01*
X1206377Y139827D01*
X1206419Y140160D01*
X1206336Y140577D01*
X1206127Y140869D01*
X1205877Y140952D01*
X1205627Y140910D01*
X1205419Y140744D01*
X1205002Y139910D01*
X1204711Y139535D01*
X1204294Y139285D01*
X1203919Y139202D01*
Y140952D01*
G01X1206419Y143177D02*
X1203919D01*
G01X1206419Y142219D02*
Y144135D01*
G01X1204961Y145485D02*
X1205252Y145777D01*
X1205419Y146027D01*
X1205502Y146360D01*
X1205419Y146652D01*
X1205252Y146860D01*
X1205002Y147027D01*
X1204711Y147069D01*
X1204461Y147027D01*
X1204211Y146860D01*
X1204002Y146610D01*
X1203919Y146319D01*
X1204002Y145985D01*
X1204252Y145694D01*
X1204627Y145527D01*
X1205044Y145485D01*
X1205586Y145569D01*
X1205877Y145694D01*
X1206169Y145902D01*
X1206377Y146194D01*
X1206419Y146485D01*
X1206336Y146777D01*
X1206127Y146985D01*
G01X1203919Y149377D02*
X1206419D01*
X1205919Y148877D01*
G01X1203919D02*
Y149877D01*
G01X1199919Y136144D02*
X1202419D01*
Y137185D01*
X1202294Y137519D01*
X1202127Y137727D01*
X1201794Y137810D01*
X1201461Y137727D01*
X1201252Y137477D01*
X1201127Y137185D01*
Y136144D01*
G01Y137185D02*
X1199919Y137810D01*
G01X1202002Y139285D02*
X1202252Y139535D01*
X1202377Y139827D01*
X1202419Y140160D01*
X1202336Y140577D01*
X1202127Y140869D01*
X1201877Y140952D01*
X1201627Y140910D01*
X1201419Y140744D01*
X1201002Y139910D01*
X1200711Y139535D01*
X1200294Y139285D01*
X1199919Y139202D01*
Y140952D01*
G01X1202419Y143177D02*
X1199919D01*
G01X1202419Y142219D02*
Y144135D01*
G01X1200419Y145360D02*
X1200127Y145610D01*
X1199961Y145944D01*
X1199919Y146319D01*
X1199961Y146652D01*
X1200169Y146985D01*
X1200419Y147194D01*
X1200669Y147235D01*
X1200961Y147152D01*
X1201169Y146860D01*
X1201252Y146569D01*
Y146194D01*
G01Y146569D02*
X1201377Y146819D01*
X1201586Y147027D01*
X1201836Y147110D01*
X1202086Y147027D01*
X1202294Y146819D01*
X1202419Y146444D01*
X1202377Y146069D01*
X1202211Y145694D01*
G01X1202002Y148585D02*
X1202252Y148835D01*
X1202377Y149127D01*
X1202419Y149460D01*
X1202336Y149877D01*
X1202127Y150169D01*
X1201877Y150252D01*
X1201627Y150210D01*
X1201419Y150044D01*
X1201002Y149210D01*
X1200711Y148835D01*
X1200294Y148585D01*
X1199919Y148502D01*
Y150252D01*
G01X1178654Y143803D02*
X1181154D01*
Y144844D01*
X1181029Y145178D01*
X1180862Y145386D01*
X1180529Y145469D01*
X1180196Y145386D01*
X1179987Y145136D01*
X1179862Y144844D01*
Y143803D01*
G01Y144844D02*
X1178654Y145469D01*
G01X1180737Y146944D02*
X1180987Y147194D01*
X1181112Y147486D01*
X1181154Y147819D01*
X1181071Y148236D01*
X1180862Y148528D01*
X1180612Y148611D01*
X1180362Y148569D01*
X1180154Y148403D01*
X1179737Y147569D01*
X1179446Y147194D01*
X1179029Y146944D01*
X1178654Y146861D01*
Y148611D01*
G01X1181154Y150836D02*
X1178654D01*
G01X1181154Y149878D02*
Y151794D01*
G01X1179696Y153144D02*
X1179987Y153436D01*
X1180154Y153686D01*
X1180237Y154019D01*
X1180154Y154311D01*
X1179987Y154519D01*
X1179737Y154686D01*
X1179446Y154728D01*
X1179196Y154686D01*
X1178946Y154519D01*
X1178737Y154269D01*
X1178654Y153978D01*
X1178737Y153644D01*
X1178987Y153353D01*
X1179362Y153186D01*
X1179779Y153144D01*
X1180321Y153228D01*
X1180612Y153353D01*
X1180904Y153561D01*
X1181112Y153853D01*
X1181154Y154144D01*
X1181071Y154436D01*
X1180862Y154644D01*
G01X1178654Y157036D02*
X1178696Y157328D01*
X1178821Y157661D01*
X1179029Y157869D01*
X1179321Y157953D01*
X1179612Y157869D01*
X1179862Y157619D01*
X1179987Y157244D01*
Y156828D01*
X1180071Y156578D01*
X1180279Y156369D01*
X1180571Y156286D01*
X1180862Y156411D01*
X1181071Y156703D01*
X1181154Y157036D01*
X1181071Y157369D01*
X1180862Y157661D01*
X1180571Y157786D01*
X1180279Y157703D01*
X1180071Y157494D01*
X1179987Y157244D01*
Y156828D01*
X1179862Y156453D01*
X1179612Y156203D01*
X1179321Y156119D01*
X1179029Y156203D01*
X1178821Y156411D01*
X1178696Y156744D01*
X1178654Y157036D01*
G01X1200476Y156620D02*
Y159120D01*
X1199435D01*
X1199101Y158995D01*
X1198893Y158828D01*
X1198810Y158495D01*
X1198893Y158162D01*
X1199143Y157953D01*
X1199435Y157828D01*
X1200476D01*
G01X1199435D02*
X1198810Y156620D01*
G01X1197335Y158703D02*
X1197085Y158953D01*
X1196793Y159078D01*
X1196460Y159120D01*
X1196043Y159037D01*
X1195751Y158828D01*
X1195668Y158578D01*
X1195710Y158328D01*
X1195876Y158120D01*
X1196710Y157703D01*
X1197085Y157412D01*
X1197335Y156995D01*
X1197418Y156620D01*
X1195668D01*
G01X1193443Y159120D02*
Y156620D01*
G01X1194401Y159120D02*
X1192485D01*
G01X1191135Y157662D02*
X1190843Y157953D01*
X1190593Y158120D01*
X1190260Y158203D01*
X1189968Y158120D01*
X1189760Y157953D01*
X1189593Y157703D01*
X1189551Y157412D01*
X1189593Y157162D01*
X1189760Y156912D01*
X1190010Y156703D01*
X1190301Y156620D01*
X1190635Y156703D01*
X1190926Y156953D01*
X1191093Y157328D01*
X1191135Y157745D01*
X1191051Y158287D01*
X1190926Y158578D01*
X1190718Y158870D01*
X1190426Y159078D01*
X1190135Y159120D01*
X1189843Y159037D01*
X1189635Y158828D01*
G01X1187243Y159120D02*
X1187576Y159037D01*
X1187826Y158828D01*
X1187993Y158578D01*
X1188118Y158245D01*
X1188160Y157870D01*
X1188118Y157495D01*
X1187993Y157162D01*
X1187826Y156912D01*
X1187576Y156703D01*
X1187243Y156620D01*
X1186910Y156703D01*
X1186660Y156912D01*
X1186493Y157162D01*
X1186368Y157495D01*
X1186326Y157870D01*
X1186368Y158245D01*
X1186493Y158578D01*
X1186660Y158828D01*
X1186910Y159037D01*
X1187243Y159120D01*
G01X1195919Y136144D02*
X1198419D01*
Y137185D01*
X1198294Y137519D01*
X1198127Y137727D01*
X1197794Y137810D01*
X1197461Y137727D01*
X1197252Y137477D01*
X1197127Y137185D01*
Y136144D01*
G01Y137185D02*
X1195919Y137810D01*
G01X1198002Y139285D02*
X1198252Y139535D01*
X1198377Y139827D01*
X1198419Y140160D01*
X1198336Y140577D01*
X1198127Y140869D01*
X1197877Y140952D01*
X1197627Y140910D01*
X1197419Y140744D01*
X1197002Y139910D01*
X1196711Y139535D01*
X1196294Y139285D01*
X1195919Y139202D01*
Y140952D01*
G01X1198419Y143177D02*
X1195919D01*
G01X1198419Y142219D02*
Y144135D01*
G01X1198002Y145485D02*
X1198252Y145735D01*
X1198377Y146027D01*
X1198419Y146360D01*
X1198336Y146777D01*
X1198127Y147069D01*
X1197877Y147152D01*
X1197627Y147110D01*
X1197419Y146944D01*
X1197002Y146110D01*
X1196711Y145735D01*
X1196294Y145485D01*
X1195919Y145402D01*
Y147152D01*
G01Y149294D02*
X1196461Y149377D01*
X1196919Y149502D01*
X1197336Y149669D01*
X1197794Y149877D01*
X1198419Y150210D01*
Y148544D01*
G01X1205741Y122573D02*
Y125073D01*
X1204700D01*
X1204366Y124948D01*
X1204158Y124781D01*
X1204075Y124448D01*
X1204158Y124115D01*
X1204408Y123906D01*
X1204700Y123781D01*
X1205741D01*
G01X1204700D02*
X1204075Y122573D01*
G01X1202600Y124656D02*
X1202350Y124906D01*
X1202058Y125031D01*
X1201725Y125073D01*
X1201308Y124990D01*
X1201016Y124781D01*
X1200933Y124531D01*
X1200975Y124281D01*
X1201141Y124073D01*
X1201975Y123656D01*
X1202350Y123365D01*
X1202600Y122948D01*
X1202683Y122573D01*
X1200933D01*
G01X1198708Y125073D02*
Y122573D01*
G01X1199666Y125073D02*
X1197750D01*
G01X1195608Y122573D02*
Y125073D01*
X1196108Y124573D01*
G01Y122573D02*
X1195108D01*
G01X1193216Y122865D02*
X1192925Y122656D01*
X1192591Y122573D01*
X1192258Y122656D01*
X1191966Y122906D01*
X1191758Y123281D01*
X1191675Y123656D01*
Y124115D01*
X1191758Y124490D01*
X1191966Y124823D01*
X1192216Y124990D01*
X1192508Y125073D01*
X1192841Y124990D01*
X1193091Y124823D01*
X1193258Y124573D01*
X1193341Y124240D01*
X1193258Y123948D01*
X1193050Y123656D01*
X1192800Y123490D01*
X1192508Y123448D01*
X1192175Y123531D01*
X1191925Y123740D01*
X1191675Y124115D01*
G01X1189273Y137003D02*
Y139503D01*
X1188232D01*
X1187898Y139378D01*
X1187690Y139211D01*
X1187607Y138878D01*
X1187690Y138545D01*
X1187940Y138336D01*
X1188232Y138211D01*
X1189273D01*
G01X1188232D02*
X1187607Y137003D01*
G01X1186132Y139086D02*
X1185882Y139336D01*
X1185590Y139461D01*
X1185257Y139503D01*
X1184840Y139420D01*
X1184548Y139211D01*
X1184465Y138961D01*
X1184507Y138711D01*
X1184673Y138503D01*
X1185507Y138086D01*
X1185882Y137795D01*
X1186132Y137378D01*
X1186215Y137003D01*
X1184465D01*
G01X1182240Y139503D02*
Y137003D01*
G01X1183198Y139503D02*
X1181282D01*
G01X1179140Y137003D02*
Y139503D01*
X1179640Y139003D01*
G01Y137003D02*
X1178640D01*
G01X1176832Y138045D02*
X1176540Y138336D01*
X1176290Y138503D01*
X1175957Y138586D01*
X1175665Y138503D01*
X1175457Y138336D01*
X1175290Y138086D01*
X1175248Y137795D01*
X1175290Y137545D01*
X1175457Y137295D01*
X1175707Y137086D01*
X1175998Y137003D01*
X1176332Y137086D01*
X1176623Y137336D01*
X1176790Y137711D01*
X1176832Y138128D01*
X1176748Y138670D01*
X1176623Y138961D01*
X1176415Y139253D01*
X1176123Y139461D01*
X1175832Y139503D01*
X1175540Y139420D01*
X1175332Y139211D01*
G01X1174243Y148562D02*
X1176743D01*
Y149603D01*
X1176618Y149937D01*
X1176451Y150145D01*
X1176118Y150228D01*
X1175785Y150145D01*
X1175576Y149895D01*
X1175451Y149603D01*
Y148562D01*
G01Y149603D02*
X1174243Y150228D01*
G01X1176326Y151703D02*
X1176576Y151953D01*
X1176701Y152245D01*
X1176743Y152578D01*
X1176660Y152995D01*
X1176451Y153287D01*
X1176201Y153370D01*
X1175951Y153328D01*
X1175743Y153162D01*
X1175326Y152328D01*
X1175035Y151953D01*
X1174618Y151703D01*
X1174243Y151620D01*
Y153370D01*
G01X1176743Y155595D02*
X1174243D01*
G01X1176743Y154637D02*
Y156553D01*
G01X1175285Y157903D02*
X1175576Y158195D01*
X1175743Y158445D01*
X1175826Y158778D01*
X1175743Y159070D01*
X1175576Y159278D01*
X1175326Y159445D01*
X1175035Y159487D01*
X1174785Y159445D01*
X1174535Y159278D01*
X1174326Y159028D01*
X1174243Y158737D01*
X1174326Y158403D01*
X1174576Y158112D01*
X1174951Y157945D01*
X1175368Y157903D01*
X1175910Y157987D01*
X1176201Y158112D01*
X1176493Y158320D01*
X1176701Y158612D01*
X1176743Y158903D01*
X1176660Y159195D01*
X1176451Y159403D01*
G01X1174535Y161087D02*
X1174326Y161378D01*
X1174243Y161712D01*
X1174326Y162045D01*
X1174576Y162337D01*
X1174951Y162545D01*
X1175326Y162628D01*
X1175785D01*
X1176160Y162545D01*
X1176493Y162337D01*
X1176660Y162087D01*
X1176743Y161795D01*
X1176660Y161462D01*
X1176493Y161212D01*
X1176243Y161045D01*
X1175910Y160962D01*
X1175618Y161045D01*
X1175326Y161253D01*
X1175160Y161503D01*
X1175118Y161795D01*
X1175201Y162128D01*
X1175410Y162378D01*
X1175785Y162628D01*
G01X1189273Y133003D02*
Y135503D01*
X1188232D01*
X1187898Y135378D01*
X1187690Y135211D01*
X1187607Y134878D01*
X1187690Y134545D01*
X1187940Y134336D01*
X1188232Y134211D01*
X1189273D01*
G01X1188232D02*
X1187607Y133003D01*
G01X1186132Y135086D02*
X1185882Y135336D01*
X1185590Y135461D01*
X1185257Y135503D01*
X1184840Y135420D01*
X1184548Y135211D01*
X1184465Y134961D01*
X1184507Y134711D01*
X1184673Y134503D01*
X1185507Y134086D01*
X1185882Y133795D01*
X1186132Y133378D01*
X1186215Y133003D01*
X1184465D01*
G01X1182240Y135503D02*
Y133003D01*
G01X1183198Y135503D02*
X1181282D01*
G01X1180057Y133378D02*
X1179807Y133170D01*
X1179515Y133045D01*
X1179140Y133003D01*
X1178765Y133086D01*
X1178473Y133253D01*
X1178265Y133545D01*
X1178223Y133878D01*
X1178307Y134211D01*
X1178515Y134420D01*
X1178807Y134586D01*
X1179098Y134628D01*
X1179390Y134586D01*
X1179765Y134420D01*
X1179640Y135503D01*
X1178515D01*
G01X1176123Y133003D02*
X1176040Y133545D01*
X1175915Y134003D01*
X1175748Y134420D01*
X1175540Y134878D01*
X1175207Y135503D01*
X1176873D01*
G01X1206041Y130773D02*
Y133273D01*
X1205000D01*
X1204666Y133148D01*
X1204458Y132981D01*
X1204375Y132648D01*
X1204458Y132315D01*
X1204708Y132106D01*
X1205000Y131981D01*
X1206041D01*
G01X1205000D02*
X1204375Y130773D01*
G01X1202900Y132856D02*
X1202650Y133106D01*
X1202358Y133231D01*
X1202025Y133273D01*
X1201608Y133190D01*
X1201316Y132981D01*
X1201233Y132731D01*
X1201275Y132481D01*
X1201441Y132273D01*
X1202275Y131856D01*
X1202650Y131565D01*
X1202900Y131148D01*
X1202983Y130773D01*
X1201233D01*
G01X1199008Y133273D02*
Y130773D01*
G01X1199966Y133273D02*
X1198050D01*
G01X1195908Y130773D02*
Y133273D01*
X1196408Y132773D01*
G01Y130773D02*
X1195408D01*
G01X1192891D02*
X1192808Y131315D01*
X1192683Y131773D01*
X1192516Y132190D01*
X1192308Y132648D01*
X1191975Y133273D01*
X1193641D01*
G01X1206041Y126773D02*
Y129273D01*
X1205000D01*
X1204666Y129148D01*
X1204458Y128981D01*
X1204375Y128648D01*
X1204458Y128315D01*
X1204708Y128106D01*
X1205000Y127981D01*
X1206041D01*
G01X1205000D02*
X1204375Y126773D01*
G01X1202900Y128856D02*
X1202650Y129106D01*
X1202358Y129231D01*
X1202025Y129273D01*
X1201608Y129190D01*
X1201316Y128981D01*
X1201233Y128731D01*
X1201275Y128481D01*
X1201441Y128273D01*
X1202275Y127856D01*
X1202650Y127565D01*
X1202900Y127148D01*
X1202983Y126773D01*
X1201233D01*
G01X1199008Y129273D02*
Y126773D01*
G01X1199966Y129273D02*
X1198050D01*
G01X1196700Y128856D02*
X1196450Y129106D01*
X1196158Y129231D01*
X1195825Y129273D01*
X1195408Y129190D01*
X1195116Y128981D01*
X1195033Y128731D01*
X1195075Y128481D01*
X1195241Y128273D01*
X1196075Y127856D01*
X1196450Y127565D01*
X1196700Y127148D01*
X1196783Y126773D01*
X1195033D01*
G01X1192808Y129273D02*
X1193141Y129190D01*
X1193391Y128981D01*
X1193558Y128731D01*
X1193683Y128398D01*
X1193725Y128023D01*
X1193683Y127648D01*
X1193558Y127315D01*
X1193391Y127065D01*
X1193141Y126856D01*
X1192808Y126773D01*
X1192475Y126856D01*
X1192225Y127065D01*
X1192058Y127315D01*
X1191933Y127648D01*
X1191891Y128023D01*
X1191933Y128398D01*
X1192058Y128731D01*
X1192225Y128981D01*
X1192475Y129190D01*
X1192808Y129273D01*
G01X1209778Y107161D02*
X1212278D01*
Y108202D01*
X1212153Y108536D01*
X1211986Y108744D01*
X1211653Y108827D01*
X1211320Y108744D01*
X1211111Y108494D01*
X1210986Y108202D01*
Y107161D01*
G01Y108202D02*
X1209778Y108827D01*
G01Y111094D02*
X1209820Y111386D01*
X1209945Y111719D01*
X1210153Y111927D01*
X1210445Y112011D01*
X1210736Y111927D01*
X1210986Y111677D01*
X1211111Y111302D01*
Y110886D01*
X1211195Y110636D01*
X1211403Y110427D01*
X1211695Y110344D01*
X1211986Y110469D01*
X1212195Y110761D01*
X1212278Y111094D01*
X1212195Y111427D01*
X1211986Y111719D01*
X1211695Y111844D01*
X1211403Y111761D01*
X1211195Y111552D01*
X1211111Y111302D01*
Y110886D01*
X1210986Y110511D01*
X1210736Y110261D01*
X1210445Y110177D01*
X1210153Y110261D01*
X1209945Y110469D01*
X1209820Y110802D01*
X1209778Y111094D01*
G01X1212278Y112944D02*
X1209778Y113527D01*
X1212278Y114194D01*
X1209778Y114861D01*
X1212278Y115444D01*
G01X1210070Y116586D02*
X1209861Y116877D01*
X1209778Y117211D01*
X1209861Y117544D01*
X1210111Y117836D01*
X1210486Y118044D01*
X1210861Y118127D01*
X1211320D01*
X1211695Y118044D01*
X1212028Y117836D01*
X1212195Y117586D01*
X1212278Y117294D01*
X1212195Y116961D01*
X1212028Y116711D01*
X1211778Y116544D01*
X1211445Y116461D01*
X1211153Y116544D01*
X1210861Y116752D01*
X1210695Y117002D01*
X1210653Y117294D01*
X1210736Y117627D01*
X1210945Y117877D01*
X1211320Y118127D01*
G01X1219290Y152657D02*
X1221790D01*
Y153698D01*
X1221665Y154032D01*
X1221498Y154240D01*
X1221165Y154323D01*
X1220832Y154240D01*
X1220623Y153990D01*
X1220498Y153698D01*
Y152657D01*
G01Y153698D02*
X1219290Y154323D01*
G01X1221373Y155798D02*
X1221623Y156048D01*
X1221748Y156340D01*
X1221790Y156673D01*
X1221707Y157090D01*
X1221498Y157382D01*
X1221248Y157465D01*
X1220998Y157423D01*
X1220790Y157257D01*
X1220373Y156423D01*
X1220082Y156048D01*
X1219665Y155798D01*
X1219290Y155715D01*
Y157465D01*
G01X1221790Y158440D02*
X1219290Y159023D01*
X1221790Y159690D01*
X1219290Y160357D01*
X1221790Y160940D01*
G01X1221373Y161998D02*
X1221623Y162248D01*
X1221748Y162540D01*
X1221790Y162873D01*
X1221707Y163290D01*
X1221498Y163582D01*
X1221248Y163665D01*
X1220998Y163623D01*
X1220790Y163457D01*
X1220373Y162623D01*
X1220082Y162248D01*
X1219665Y161998D01*
X1219290Y161915D01*
Y163665D01*
G01X1214962Y157034D02*
X1215212Y157159D01*
X1215504Y157242D01*
X1215837D01*
X1216212Y157117D01*
X1216504Y156909D01*
X1216712Y156659D01*
X1216879Y156242D01*
X1216921Y155867D01*
X1216837Y155492D01*
X1216712Y155242D01*
X1216462Y154992D01*
X1216171Y154825D01*
X1215879Y154742D01*
X1215587D01*
X1215296Y154825D01*
X1215046Y154950D01*
X1214837Y155117D01*
G01X1213571Y156825D02*
X1213321Y157075D01*
X1213029Y157200D01*
X1212696Y157242D01*
X1212279Y157159D01*
X1211987Y156950D01*
X1211904Y156700D01*
X1211946Y156450D01*
X1212112Y156242D01*
X1212946Y155825D01*
X1213321Y155534D01*
X1213571Y155117D01*
X1213654Y154742D01*
X1211904D01*
G01X1209679Y157242D02*
Y154742D01*
G01X1210637Y157242D02*
X1208721D01*
G01X1207496Y155242D02*
X1207246Y154950D01*
X1206912Y154784D01*
X1206537Y154742D01*
X1206204Y154784D01*
X1205871Y154992D01*
X1205662Y155242D01*
X1205621Y155492D01*
X1205704Y155784D01*
X1205996Y155992D01*
X1206287Y156075D01*
X1206662D01*
G01X1206287D02*
X1206037Y156200D01*
X1205829Y156409D01*
X1205746Y156659D01*
X1205829Y156909D01*
X1206037Y157117D01*
X1206412Y157242D01*
X1206787Y157200D01*
X1207162Y157034D01*
G01X1204271Y156825D02*
X1204021Y157075D01*
X1203729Y157200D01*
X1203396Y157242D01*
X1202979Y157159D01*
X1202687Y156950D01*
X1202604Y156700D01*
X1202646Y156450D01*
X1202812Y156242D01*
X1203646Y155825D01*
X1204021Y155534D01*
X1204271Y155117D01*
X1204354Y154742D01*
X1202604D01*
G01X1200588Y152490D02*
Y154990D01*
X1199547D01*
X1199213Y154865D01*
X1199005Y154698D01*
X1198922Y154365D01*
X1199005Y154032D01*
X1199255Y153823D01*
X1199547Y153698D01*
X1200588D01*
G01X1199547D02*
X1198922Y152490D01*
G01X1197447Y154573D02*
X1197197Y154823D01*
X1196905Y154948D01*
X1196572Y154990D01*
X1196155Y154907D01*
X1195863Y154698D01*
X1195780Y154448D01*
X1195822Y154198D01*
X1195988Y153990D01*
X1196822Y153573D01*
X1197197Y153282D01*
X1197447Y152865D01*
X1197530Y152490D01*
X1195780D01*
G01X1193555Y154990D02*
Y152490D01*
G01X1194513Y154990D02*
X1192597D01*
G01X1191372Y152990D02*
X1191122Y152698D01*
X1190788Y152532D01*
X1190413Y152490D01*
X1190080Y152532D01*
X1189747Y152740D01*
X1189538Y152990D01*
X1189497Y153240D01*
X1189580Y153532D01*
X1189872Y153740D01*
X1190163Y153823D01*
X1190538D01*
G01X1190163D02*
X1189913Y153948D01*
X1189705Y154157D01*
X1189622Y154407D01*
X1189705Y154657D01*
X1189913Y154865D01*
X1190288Y154990D01*
X1190663Y154948D01*
X1191038Y154782D01*
G01X1188147Y153532D02*
X1187855Y153823D01*
X1187605Y153990D01*
X1187272Y154073D01*
X1186980Y153990D01*
X1186772Y153823D01*
X1186605Y153573D01*
X1186563Y153282D01*
X1186605Y153032D01*
X1186772Y152782D01*
X1187022Y152573D01*
X1187313Y152490D01*
X1187647Y152573D01*
X1187938Y152823D01*
X1188105Y153198D01*
X1188147Y153615D01*
X1188063Y154157D01*
X1187938Y154448D01*
X1187730Y154740D01*
X1187438Y154948D01*
X1187147Y154990D01*
X1186855Y154907D01*
X1186647Y154698D01*
G01X1177877Y192791D02*
X1175210D01*
Y190691D01*
X1176010Y189991D01*
X1176944Y189524D01*
X1178277Y189291D01*
X1179610Y189524D01*
X1180544Y189991D01*
X1181344Y190691D01*
X1181877Y191508D01*
X1182144Y192441D01*
Y193258D01*
X1181877Y193958D01*
X1181344Y194774D01*
X1180544Y195474D01*
X1179744Y195941D01*
X1178677Y196291D01*
X1177744D01*
X1176677Y196058D01*
X1175877Y195591D01*
G01X1184861Y201227D02*
Y203727D01*
X1183820D01*
X1183486Y203602D01*
X1183278Y203435D01*
X1183195Y203102D01*
X1183278Y202769D01*
X1183528Y202560D01*
X1183820Y202435D01*
X1184861D01*
G01X1183820D02*
X1183195Y201227D01*
G01X1181845Y201727D02*
X1181595Y201435D01*
X1181261Y201269D01*
X1180886Y201227D01*
X1180553Y201269D01*
X1180220Y201477D01*
X1180011Y201727D01*
X1179970Y201977D01*
X1180053Y202269D01*
X1180345Y202477D01*
X1180636Y202560D01*
X1181011D01*
G01X1180636D02*
X1180386Y202685D01*
X1180178Y202894D01*
X1180095Y203144D01*
X1180178Y203394D01*
X1180386Y203602D01*
X1180761Y203727D01*
X1181136Y203685D01*
X1181511Y203519D01*
G01X1178661Y201227D02*
Y203727D01*
X1177620D01*
X1177286Y203602D01*
X1177078Y203435D01*
X1176995Y203102D01*
X1177078Y202769D01*
X1177328Y202560D01*
X1177620Y202435D01*
X1178661D01*
G01X1177620D02*
X1176995Y201227D01*
G01X1174728D02*
Y203727D01*
X1175228Y203227D01*
G01Y201227D02*
X1174228D01*
G01X1175254Y164603D02*
X1177754D01*
Y165644D01*
X1177629Y165978D01*
X1177462Y166186D01*
X1177129Y166269D01*
X1176796Y166186D01*
X1176587Y165936D01*
X1176462Y165644D01*
Y164603D01*
G01Y165644D02*
X1175254Y166269D01*
G01X1175754Y167619D02*
X1175462Y167869D01*
X1175296Y168203D01*
X1175254Y168578D01*
X1175296Y168911D01*
X1175504Y169244D01*
X1175754Y169453D01*
X1176004Y169494D01*
X1176296Y169411D01*
X1176504Y169119D01*
X1176587Y168828D01*
Y168453D01*
G01Y168828D02*
X1176712Y169078D01*
X1176921Y169286D01*
X1177171Y169369D01*
X1177421Y169286D01*
X1177629Y169078D01*
X1177754Y168703D01*
X1177712Y168328D01*
X1177546Y167953D01*
G01X1175254Y170803D02*
X1177754D01*
Y171803D01*
X1177629Y172136D01*
X1177337Y172386D01*
X1177004Y172469D01*
X1176671Y172386D01*
X1176421Y172178D01*
X1176296Y171803D01*
Y170803D01*
G01X1175754Y173819D02*
X1175462Y174069D01*
X1175296Y174403D01*
X1175254Y174778D01*
X1175296Y175111D01*
X1175504Y175444D01*
X1175754Y175653D01*
X1176004Y175694D01*
X1176296Y175611D01*
X1176504Y175319D01*
X1176587Y175028D01*
Y174653D01*
G01Y175028D02*
X1176712Y175278D01*
X1176921Y175486D01*
X1177171Y175569D01*
X1177421Y175486D01*
X1177629Y175278D01*
X1177754Y174903D01*
X1177712Y174528D01*
X1177546Y174153D01*
G01X1177337Y177044D02*
X1177587Y177294D01*
X1177712Y177586D01*
X1177754Y177919D01*
X1177671Y178336D01*
X1177462Y178628D01*
X1177212Y178711D01*
X1176962Y178669D01*
X1176754Y178503D01*
X1176337Y177669D01*
X1176046Y177294D01*
X1175629Y177044D01*
X1175254Y176961D01*
Y178711D01*
G01X1205904Y172640D02*
X1208404D01*
Y173681D01*
X1208279Y174015D01*
X1208112Y174223D01*
X1207779Y174306D01*
X1207446Y174223D01*
X1207237Y173973D01*
X1207112Y173681D01*
Y172640D01*
G01Y173681D02*
X1205904Y174306D01*
G01Y176573D02*
X1205946Y176865D01*
X1206071Y177198D01*
X1206279Y177406D01*
X1206571Y177490D01*
X1206862Y177406D01*
X1207112Y177156D01*
X1207237Y176781D01*
Y176365D01*
X1207321Y176115D01*
X1207529Y175906D01*
X1207821Y175823D01*
X1208112Y175948D01*
X1208321Y176240D01*
X1208404Y176573D01*
X1208321Y176906D01*
X1208112Y177198D01*
X1207821Y177323D01*
X1207529Y177240D01*
X1207321Y177031D01*
X1207237Y176781D01*
Y176365D01*
X1207112Y175990D01*
X1206862Y175740D01*
X1206571Y175656D01*
X1206279Y175740D01*
X1206071Y175948D01*
X1205946Y176281D01*
X1205904Y176573D01*
G01Y178881D02*
X1208404D01*
Y180465D01*
G01X1207196Y179881D02*
Y178881D01*
G01X1206946Y181981D02*
X1207237Y182273D01*
X1207404Y182523D01*
X1207487Y182856D01*
X1207404Y183148D01*
X1207237Y183356D01*
X1206987Y183523D01*
X1206696Y183565D01*
X1206446Y183523D01*
X1206196Y183356D01*
X1205987Y183106D01*
X1205904Y182815D01*
X1205987Y182481D01*
X1206237Y182190D01*
X1206612Y182023D01*
X1207029Y181981D01*
X1207571Y182065D01*
X1207862Y182190D01*
X1208154Y182398D01*
X1208362Y182690D01*
X1208404Y182981D01*
X1208321Y183273D01*
X1208112Y183481D01*
G01X1196635Y178295D02*
Y180795D01*
X1195594D01*
X1195260Y180670D01*
X1195052Y180503D01*
X1194969Y180170D01*
X1195052Y179837D01*
X1195302Y179628D01*
X1195594Y179503D01*
X1196635D01*
G01X1195594D02*
X1194969Y178295D01*
G01X1193619Y178795D02*
X1193369Y178503D01*
X1193035Y178337D01*
X1192660Y178295D01*
X1192327Y178337D01*
X1191994Y178545D01*
X1191785Y178795D01*
X1191744Y179045D01*
X1191827Y179337D01*
X1192119Y179545D01*
X1192410Y179628D01*
X1192785D01*
G01X1192410D02*
X1192160Y179753D01*
X1191952Y179962D01*
X1191869Y180212D01*
X1191952Y180462D01*
X1192160Y180670D01*
X1192535Y180795D01*
X1192910Y180753D01*
X1193285Y180587D01*
G01X1190435Y178295D02*
Y180795D01*
X1189435D01*
X1189102Y180670D01*
X1188852Y180378D01*
X1188769Y180045D01*
X1188852Y179712D01*
X1189060Y179462D01*
X1189435Y179337D01*
X1190435D01*
G01X1186002Y178295D02*
Y180795D01*
X1187544Y179003D01*
X1185460D01*
G01X1183402Y178295D02*
Y180795D01*
X1183902Y180295D01*
G01Y178295D02*
X1182902D01*
G01X1196635Y182295D02*
Y184795D01*
X1195594D01*
X1195260Y184670D01*
X1195052Y184503D01*
X1194969Y184170D01*
X1195052Y183837D01*
X1195302Y183628D01*
X1195594Y183503D01*
X1196635D01*
G01X1195594D02*
X1194969Y182295D01*
G01X1193619Y182795D02*
X1193369Y182503D01*
X1193035Y182337D01*
X1192660Y182295D01*
X1192327Y182337D01*
X1191994Y182545D01*
X1191785Y182795D01*
X1191744Y183045D01*
X1191827Y183337D01*
X1192119Y183545D01*
X1192410Y183628D01*
X1192785D01*
G01X1192410D02*
X1192160Y183753D01*
X1191952Y183962D01*
X1191869Y184212D01*
X1191952Y184462D01*
X1192160Y184670D01*
X1192535Y184795D01*
X1192910Y184753D01*
X1193285Y184587D01*
G01X1190435Y182295D02*
Y184795D01*
X1189435D01*
X1189102Y184670D01*
X1188852Y184378D01*
X1188769Y184045D01*
X1188852Y183712D01*
X1189060Y183462D01*
X1189435Y183337D01*
X1190435D01*
G01X1187419Y182670D02*
X1187169Y182462D01*
X1186877Y182337D01*
X1186502Y182295D01*
X1186127Y182378D01*
X1185835Y182545D01*
X1185627Y182837D01*
X1185585Y183170D01*
X1185669Y183503D01*
X1185877Y183712D01*
X1186169Y183878D01*
X1186460Y183920D01*
X1186752Y183878D01*
X1187127Y183712D01*
X1187002Y184795D01*
X1185877D01*
G01X1184110Y182587D02*
X1183819Y182378D01*
X1183485Y182295D01*
X1183152Y182378D01*
X1182860Y182628D01*
X1182652Y183003D01*
X1182569Y183378D01*
Y183837D01*
X1182652Y184212D01*
X1182860Y184545D01*
X1183110Y184712D01*
X1183402Y184795D01*
X1183735Y184712D01*
X1183985Y184545D01*
X1184152Y184295D01*
X1184235Y183962D01*
X1184152Y183670D01*
X1183944Y183378D01*
X1183694Y183212D01*
X1183402Y183170D01*
X1183069Y183253D01*
X1182819Y183462D01*
X1182569Y183837D01*
G01X1196635Y186295D02*
Y188795D01*
X1195594D01*
X1195260Y188670D01*
X1195052Y188503D01*
X1194969Y188170D01*
X1195052Y187837D01*
X1195302Y187628D01*
X1195594Y187503D01*
X1196635D01*
G01X1195594D02*
X1194969Y186295D01*
G01X1193619Y186795D02*
X1193369Y186503D01*
X1193035Y186337D01*
X1192660Y186295D01*
X1192327Y186337D01*
X1191994Y186545D01*
X1191785Y186795D01*
X1191744Y187045D01*
X1191827Y187337D01*
X1192119Y187545D01*
X1192410Y187628D01*
X1192785D01*
G01X1192410D02*
X1192160Y187753D01*
X1191952Y187962D01*
X1191869Y188212D01*
X1191952Y188462D01*
X1192160Y188670D01*
X1192535Y188795D01*
X1192910Y188753D01*
X1193285Y188587D01*
G01X1190435Y186295D02*
Y188795D01*
X1189435D01*
X1189102Y188670D01*
X1188852Y188378D01*
X1188769Y188045D01*
X1188852Y187712D01*
X1189060Y187462D01*
X1189435Y187337D01*
X1190435D01*
G01X1187419Y186670D02*
X1187169Y186462D01*
X1186877Y186337D01*
X1186502Y186295D01*
X1186127Y186378D01*
X1185835Y186545D01*
X1185627Y186837D01*
X1185585Y187170D01*
X1185669Y187503D01*
X1185877Y187712D01*
X1186169Y187878D01*
X1186460Y187920D01*
X1186752Y187878D01*
X1187127Y187712D01*
X1187002Y188795D01*
X1185877D01*
G01X1183402Y186295D02*
X1183110Y186337D01*
X1182777Y186462D01*
X1182569Y186670D01*
X1182485Y186962D01*
X1182569Y187253D01*
X1182819Y187503D01*
X1183194Y187628D01*
X1183610D01*
X1183860Y187712D01*
X1184069Y187920D01*
X1184152Y188212D01*
X1184027Y188503D01*
X1183735Y188712D01*
X1183402Y188795D01*
X1183069Y188712D01*
X1182777Y188503D01*
X1182652Y188212D01*
X1182735Y187920D01*
X1182944Y187712D01*
X1183194Y187628D01*
X1183610D01*
X1183985Y187503D01*
X1184235Y187253D01*
X1184319Y186962D01*
X1184235Y186670D01*
X1184027Y186462D01*
X1183694Y186337D01*
X1183402Y186295D01*
G01X1180237Y160719D02*
X1182737D01*
Y161760D01*
X1182612Y162094D01*
X1182445Y162302D01*
X1182112Y162385D01*
X1181779Y162302D01*
X1181570Y162052D01*
X1181445Y161760D01*
Y160719D01*
G01Y161760D02*
X1180237Y162385D01*
G01X1180737Y163735D02*
X1180445Y163985D01*
X1180279Y164319D01*
X1180237Y164694D01*
X1180279Y165027D01*
X1180487Y165360D01*
X1180737Y165569D01*
X1180987Y165610D01*
X1181279Y165527D01*
X1181487Y165235D01*
X1181570Y164944D01*
Y164569D01*
G01Y164944D02*
X1181695Y165194D01*
X1181904Y165402D01*
X1182154Y165485D01*
X1182404Y165402D01*
X1182612Y165194D01*
X1182737Y164819D01*
X1182695Y164444D01*
X1182529Y164069D01*
G01X1180237Y166919D02*
X1182737D01*
Y167919D01*
X1182612Y168252D01*
X1182320Y168502D01*
X1181987Y168585D01*
X1181654Y168502D01*
X1181404Y168294D01*
X1181279Y167919D01*
Y166919D01*
G01X1180737Y169935D02*
X1180445Y170185D01*
X1180279Y170519D01*
X1180237Y170894D01*
X1180279Y171227D01*
X1180487Y171560D01*
X1180737Y171769D01*
X1180987Y171810D01*
X1181279Y171727D01*
X1181487Y171435D01*
X1181570Y171144D01*
Y170769D01*
G01Y171144D02*
X1181695Y171394D01*
X1181904Y171602D01*
X1182154Y171685D01*
X1182404Y171602D01*
X1182612Y171394D01*
X1182737Y171019D01*
X1182695Y170644D01*
X1182529Y170269D01*
G01X1180237Y173952D02*
X1180279Y174244D01*
X1180404Y174577D01*
X1180612Y174785D01*
X1180904Y174869D01*
X1181195Y174785D01*
X1181445Y174535D01*
X1181570Y174160D01*
Y173744D01*
X1181654Y173494D01*
X1181862Y173285D01*
X1182154Y173202D01*
X1182445Y173327D01*
X1182654Y173619D01*
X1182737Y173952D01*
X1182654Y174285D01*
X1182445Y174577D01*
X1182154Y174702D01*
X1181862Y174619D01*
X1181654Y174410D01*
X1181570Y174160D01*
Y173744D01*
X1181445Y173369D01*
X1181195Y173119D01*
X1180904Y173035D01*
X1180612Y173119D01*
X1180404Y173327D01*
X1180279Y173660D01*
X1180237Y173952D01*
G01X1216570Y158155D02*
Y160655D01*
X1215529D01*
X1215195Y160530D01*
X1214987Y160363D01*
X1214904Y160030D01*
X1214987Y159697D01*
X1215237Y159488D01*
X1215529Y159363D01*
X1216570D01*
G01X1215529D02*
X1214904Y158155D01*
G01X1213429Y160238D02*
X1213179Y160488D01*
X1212887Y160613D01*
X1212554Y160655D01*
X1212137Y160572D01*
X1211845Y160363D01*
X1211762Y160113D01*
X1211804Y159863D01*
X1211970Y159655D01*
X1212804Y159238D01*
X1213179Y158947D01*
X1213429Y158530D01*
X1213512Y158155D01*
X1211762D01*
G01X1209537Y160655D02*
Y158155D01*
G01X1210495Y160655D02*
X1208579D01*
G01X1207354Y158655D02*
X1207104Y158363D01*
X1206770Y158197D01*
X1206395Y158155D01*
X1206062Y158197D01*
X1205729Y158405D01*
X1205520Y158655D01*
X1205479Y158905D01*
X1205562Y159197D01*
X1205854Y159405D01*
X1206145Y159488D01*
X1206520D01*
G01X1206145D02*
X1205895Y159613D01*
X1205687Y159822D01*
X1205604Y160072D01*
X1205687Y160322D01*
X1205895Y160530D01*
X1206270Y160655D01*
X1206645Y160613D01*
X1207020Y160447D01*
G01X1204045Y158447D02*
X1203754Y158238D01*
X1203420Y158155D01*
X1203087Y158238D01*
X1202795Y158488D01*
X1202587Y158863D01*
X1202504Y159238D01*
Y159697D01*
X1202587Y160072D01*
X1202795Y160405D01*
X1203045Y160572D01*
X1203337Y160655D01*
X1203670Y160572D01*
X1203920Y160405D01*
X1204087Y160155D01*
X1204170Y159822D01*
X1204087Y159530D01*
X1203879Y159238D01*
X1203629Y159072D01*
X1203337Y159030D01*
X1203004Y159113D01*
X1202754Y159322D01*
X1202504Y159697D01*
G01X1200046Y170071D02*
Y172571D01*
X1199005D01*
X1198671Y172446D01*
X1198463Y172279D01*
X1198380Y171946D01*
X1198463Y171613D01*
X1198713Y171404D01*
X1199005Y171279D01*
X1200046D01*
G01X1199005D02*
X1198380Y170071D01*
G01X1196905Y172154D02*
X1196655Y172404D01*
X1196363Y172529D01*
X1196030Y172571D01*
X1195613Y172488D01*
X1195321Y172279D01*
X1195238Y172029D01*
X1195280Y171779D01*
X1195446Y171571D01*
X1196280Y171154D01*
X1196655Y170863D01*
X1196905Y170446D01*
X1196988Y170071D01*
X1195238D01*
G01X1193013Y172571D02*
Y170071D01*
G01X1193971Y172571D02*
X1192055D01*
G01X1190830Y170446D02*
X1190580Y170238D01*
X1190288Y170113D01*
X1189913Y170071D01*
X1189538Y170154D01*
X1189246Y170321D01*
X1189038Y170613D01*
X1188996Y170946D01*
X1189080Y171279D01*
X1189288Y171488D01*
X1189580Y171654D01*
X1189871Y171696D01*
X1190163Y171654D01*
X1190538Y171488D01*
X1190413Y172571D01*
X1189288D01*
G01X1187521Y170363D02*
X1187230Y170154D01*
X1186896Y170071D01*
X1186563Y170154D01*
X1186271Y170404D01*
X1186063Y170779D01*
X1185980Y171154D01*
Y171613D01*
X1186063Y171988D01*
X1186271Y172321D01*
X1186521Y172488D01*
X1186813Y172571D01*
X1187146Y172488D01*
X1187396Y172321D01*
X1187563Y172071D01*
X1187646Y171738D01*
X1187563Y171446D01*
X1187355Y171154D01*
X1187105Y170988D01*
X1186813Y170946D01*
X1186480Y171029D01*
X1186230Y171238D01*
X1185980Y171613D01*
G01X1200046Y166071D02*
Y168571D01*
X1199005D01*
X1198671Y168446D01*
X1198463Y168279D01*
X1198380Y167946D01*
X1198463Y167613D01*
X1198713Y167404D01*
X1199005Y167279D01*
X1200046D01*
G01X1199005D02*
X1198380Y166071D01*
G01X1196905Y168154D02*
X1196655Y168404D01*
X1196363Y168529D01*
X1196030Y168571D01*
X1195613Y168488D01*
X1195321Y168279D01*
X1195238Y168029D01*
X1195280Y167779D01*
X1195446Y167571D01*
X1196280Y167154D01*
X1196655Y166863D01*
X1196905Y166446D01*
X1196988Y166071D01*
X1195238D01*
G01X1193013Y168571D02*
Y166071D01*
G01X1193971Y168571D02*
X1192055D01*
G01X1189996Y166071D02*
X1189913Y166613D01*
X1189788Y167071D01*
X1189621Y167488D01*
X1189413Y167946D01*
X1189080Y168571D01*
X1190746D01*
G01X1187605Y168154D02*
X1187355Y168404D01*
X1187063Y168529D01*
X1186730Y168571D01*
X1186313Y168488D01*
X1186021Y168279D01*
X1185938Y168029D01*
X1185980Y167779D01*
X1186146Y167571D01*
X1186980Y167154D01*
X1187355Y166863D01*
X1187605Y166446D01*
X1187688Y166071D01*
X1185938D01*
G01X1202027Y183673D02*
X1204527D01*
Y184714D01*
X1204402Y185048D01*
X1204235Y185256D01*
X1203902Y185339D01*
X1203569Y185256D01*
X1203360Y185006D01*
X1203235Y184714D01*
Y183673D01*
G01Y184714D02*
X1202027Y185339D01*
G01X1202527Y186689D02*
X1202235Y186939D01*
X1202069Y187273D01*
X1202027Y187648D01*
X1202069Y187981D01*
X1202277Y188314D01*
X1202527Y188523D01*
X1202777Y188564D01*
X1203069Y188481D01*
X1203277Y188189D01*
X1203360Y187898D01*
Y187523D01*
G01Y187898D02*
X1203485Y188148D01*
X1203694Y188356D01*
X1203944Y188439D01*
X1204194Y188356D01*
X1204402Y188148D01*
X1204527Y187773D01*
X1204485Y187398D01*
X1204319Y187023D01*
G01X1204527Y189456D02*
X1202027Y190039D01*
X1204527Y190706D01*
X1202027Y191373D01*
X1204527Y191956D01*
G01X1202027Y193806D02*
X1204527D01*
X1204027Y193306D01*
G01X1202027D02*
Y194306D01*
G01X1204527Y196906D02*
X1204444Y196573D01*
X1204235Y196323D01*
X1203985Y196156D01*
X1203652Y196031D01*
X1203277Y195989D01*
X1202902Y196031D01*
X1202569Y196156D01*
X1202319Y196323D01*
X1202110Y196573D01*
X1202027Y196906D01*
X1202110Y197239D01*
X1202319Y197489D01*
X1202569Y197656D01*
X1202902Y197781D01*
X1203277Y197823D01*
X1203652Y197781D01*
X1203985Y197656D01*
X1204235Y197489D01*
X1204444Y197239D01*
X1204527Y196906D01*
G01X1192462Y192328D02*
X1194962D01*
Y193369D01*
X1194837Y193703D01*
X1194670Y193911D01*
X1194337Y193994D01*
X1194004Y193911D01*
X1193795Y193661D01*
X1193670Y193369D01*
Y192328D01*
G01Y193369D02*
X1192462Y193994D01*
G01X1192962Y195344D02*
X1192670Y195594D01*
X1192504Y195928D01*
X1192462Y196303D01*
X1192504Y196636D01*
X1192712Y196969D01*
X1192962Y197178D01*
X1193212Y197219D01*
X1193504Y197136D01*
X1193712Y196844D01*
X1193795Y196553D01*
Y196178D01*
G01Y196553D02*
X1193920Y196803D01*
X1194129Y197011D01*
X1194379Y197094D01*
X1194629Y197011D01*
X1194837Y196803D01*
X1194962Y196428D01*
X1194920Y196053D01*
X1194754Y195678D01*
G01X1192462Y198528D02*
X1194962D01*
Y199528D01*
X1194837Y199861D01*
X1194545Y200111D01*
X1194212Y200194D01*
X1193879Y200111D01*
X1193629Y199903D01*
X1193504Y199528D01*
Y198528D01*
G01X1192462Y202961D02*
X1194962D01*
X1193170Y201419D01*
Y203503D01*
G01X1192754Y204853D02*
X1192545Y205144D01*
X1192462Y205478D01*
X1192545Y205811D01*
X1192795Y206103D01*
X1193170Y206311D01*
X1193545Y206394D01*
X1194004D01*
X1194379Y206311D01*
X1194712Y206103D01*
X1194879Y205853D01*
X1194962Y205561D01*
X1194879Y205228D01*
X1194712Y204978D01*
X1194462Y204811D01*
X1194129Y204728D01*
X1193837Y204811D01*
X1193545Y205019D01*
X1193379Y205269D01*
X1193337Y205561D01*
X1193420Y205894D01*
X1193629Y206144D01*
X1194004Y206394D01*
G01X1199828Y174268D02*
Y176768D01*
X1198787D01*
X1198453Y176643D01*
X1198245Y176476D01*
X1198162Y176143D01*
X1198245Y175810D01*
X1198495Y175601D01*
X1198787Y175476D01*
X1199828D01*
G01X1198787D02*
X1198162Y174268D01*
G01X1196812Y174768D02*
X1196562Y174476D01*
X1196228Y174310D01*
X1195853Y174268D01*
X1195520Y174310D01*
X1195187Y174518D01*
X1194978Y174768D01*
X1194937Y175018D01*
X1195020Y175310D01*
X1195312Y175518D01*
X1195603Y175601D01*
X1195978D01*
G01X1195603D02*
X1195353Y175726D01*
X1195145Y175935D01*
X1195062Y176185D01*
X1195145Y176435D01*
X1195353Y176643D01*
X1195728Y176768D01*
X1196103Y176726D01*
X1196478Y176560D01*
G01X1193628Y174268D02*
Y176768D01*
X1192628D01*
X1192295Y176643D01*
X1192045Y176351D01*
X1191962Y176018D01*
X1192045Y175685D01*
X1192253Y175435D01*
X1192628Y175310D01*
X1193628D01*
G01X1190612Y174768D02*
X1190362Y174476D01*
X1190028Y174310D01*
X1189653Y174268D01*
X1189320Y174310D01*
X1188987Y174518D01*
X1188778Y174768D01*
X1188737Y175018D01*
X1188820Y175310D01*
X1189112Y175518D01*
X1189403Y175601D01*
X1189778D01*
G01X1189403D02*
X1189153Y175726D01*
X1188945Y175935D01*
X1188862Y176185D01*
X1188945Y176435D01*
X1189153Y176643D01*
X1189528Y176768D01*
X1189903Y176726D01*
X1190278Y176560D01*
G01X1187387Y175310D02*
X1187095Y175601D01*
X1186845Y175768D01*
X1186512Y175851D01*
X1186220Y175768D01*
X1186012Y175601D01*
X1185845Y175351D01*
X1185803Y175060D01*
X1185845Y174810D01*
X1186012Y174560D01*
X1186262Y174351D01*
X1186553Y174268D01*
X1186887Y174351D01*
X1187178Y174601D01*
X1187345Y174976D01*
X1187387Y175393D01*
X1187303Y175935D01*
X1187178Y176226D01*
X1186970Y176518D01*
X1186678Y176726D01*
X1186387Y176768D01*
X1186095Y176685D01*
X1185887Y176476D01*
G01X1200504Y160498D02*
Y162998D01*
X1199463D01*
X1199129Y162873D01*
X1198921Y162706D01*
X1198838Y162373D01*
X1198921Y162040D01*
X1199171Y161831D01*
X1199463Y161706D01*
X1200504D01*
G01X1199463D02*
X1198838Y160498D01*
G01X1197363Y162581D02*
X1197113Y162831D01*
X1196821Y162956D01*
X1196488Y162998D01*
X1196071Y162915D01*
X1195779Y162706D01*
X1195696Y162456D01*
X1195738Y162206D01*
X1195904Y161998D01*
X1196738Y161581D01*
X1197113Y161290D01*
X1197363Y160873D01*
X1197446Y160498D01*
X1195696D01*
G01X1193471Y162998D02*
Y160498D01*
G01X1194429Y162998D02*
X1192513D01*
G01X1190454Y160498D02*
X1190371Y161040D01*
X1190246Y161498D01*
X1190079Y161915D01*
X1189871Y162373D01*
X1189538Y162998D01*
X1191204D01*
G01X1188188Y160998D02*
X1187938Y160706D01*
X1187604Y160540D01*
X1187229Y160498D01*
X1186896Y160540D01*
X1186563Y160748D01*
X1186354Y160998D01*
X1186313Y161248D01*
X1186396Y161540D01*
X1186688Y161748D01*
X1186979Y161831D01*
X1187354D01*
G01X1186979D02*
X1186729Y161956D01*
X1186521Y162165D01*
X1186438Y162415D01*
X1186521Y162665D01*
X1186729Y162873D01*
X1187104Y162998D01*
X1187479Y162956D01*
X1187854Y162790D01*
G01X1216564Y170644D02*
Y168852D01*
X1216397Y168477D01*
X1216064Y168227D01*
X1215647Y168144D01*
X1215230Y168227D01*
X1214897Y168477D01*
X1214730Y168852D01*
Y170644D01*
G01X1212630Y168144D02*
X1212547Y168686D01*
X1212422Y169144D01*
X1212255Y169561D01*
X1212047Y170019D01*
X1211714Y170644D01*
X1213380D01*
G01X1208614Y168144D02*
X1210280D01*
Y170644D01*
X1208614D01*
G01X1209280Y169436D02*
X1210280D01*
G01X1207264Y168644D02*
X1207014Y168352D01*
X1206680Y168186D01*
X1206305Y168144D01*
X1205972Y168186D01*
X1205639Y168394D01*
X1205430Y168644D01*
X1205389Y168894D01*
X1205472Y169186D01*
X1205764Y169394D01*
X1206055Y169477D01*
X1206430D01*
G01X1206055D02*
X1205805Y169602D01*
X1205597Y169811D01*
X1205514Y170061D01*
X1205597Y170311D01*
X1205805Y170519D01*
X1206180Y170644D01*
X1206555Y170602D01*
X1206930Y170436D01*
G01X1221352Y167807D02*
X1221477Y167557D01*
X1221560Y167265D01*
Y166932D01*
X1221435Y166557D01*
X1221227Y166265D01*
X1220977Y166057D01*
X1220560Y165890D01*
X1220185Y165848D01*
X1219810Y165932D01*
X1219560Y166057D01*
X1219310Y166307D01*
X1219143Y166598D01*
X1219060Y166890D01*
Y167182D01*
X1219143Y167473D01*
X1219268Y167723D01*
X1219435Y167932D01*
G01X1219060Y169907D02*
X1219602Y169990D01*
X1220060Y170115D01*
X1220477Y170282D01*
X1220935Y170490D01*
X1221560Y170823D01*
Y169157D01*
G01X1219060Y173923D02*
Y172257D01*
X1221560D01*
Y173923D01*
G01X1220352Y173257D02*
Y172257D01*
G01X1219060Y176690D02*
X1221560D01*
X1219768Y175148D01*
Y177232D01*
G01X1208729Y200477D02*
X1208854Y200227D01*
X1208937Y199935D01*
Y199602D01*
X1208812Y199227D01*
X1208604Y198935D01*
X1208354Y198727D01*
X1207937Y198560D01*
X1207562Y198518D01*
X1207187Y198602D01*
X1206937Y198727D01*
X1206687Y198977D01*
X1206520Y199268D01*
X1206437Y199560D01*
Y199852D01*
X1206520Y200143D01*
X1206645Y200393D01*
X1206812Y200602D01*
G01X1208520Y201868D02*
X1208770Y202118D01*
X1208895Y202410D01*
X1208937Y202743D01*
X1208854Y203160D01*
X1208645Y203452D01*
X1208395Y203535D01*
X1208145Y203493D01*
X1207937Y203327D01*
X1207520Y202493D01*
X1207229Y202118D01*
X1206812Y201868D01*
X1206437Y201785D01*
Y203535D01*
G01X1208937Y205760D02*
X1206437D01*
G01X1208937Y204802D02*
Y206718D01*
G01X1206437Y208860D02*
X1208937D01*
X1208437Y208360D01*
G01X1206437D02*
Y209360D01*
G01X1190754Y194078D02*
X1190879Y193828D01*
X1190962Y193536D01*
Y193203D01*
X1190837Y192828D01*
X1190629Y192536D01*
X1190379Y192328D01*
X1189962Y192161D01*
X1189587Y192119D01*
X1189212Y192203D01*
X1188962Y192328D01*
X1188712Y192578D01*
X1188545Y192869D01*
X1188462Y193161D01*
Y193453D01*
X1188545Y193744D01*
X1188670Y193994D01*
X1188837Y194203D01*
G01X1188962Y195344D02*
X1188670Y195594D01*
X1188504Y195928D01*
X1188462Y196303D01*
X1188504Y196636D01*
X1188712Y196969D01*
X1188962Y197178D01*
X1189212Y197219D01*
X1189504Y197136D01*
X1189712Y196844D01*
X1189795Y196553D01*
Y196178D01*
G01Y196553D02*
X1189920Y196803D01*
X1190129Y197011D01*
X1190379Y197094D01*
X1190629Y197011D01*
X1190837Y196803D01*
X1190962Y196428D01*
X1190920Y196053D01*
X1190754Y195678D01*
G01X1188462Y198528D02*
X1190962D01*
Y199528D01*
X1190837Y199861D01*
X1190545Y200111D01*
X1190212Y200194D01*
X1189879Y200111D01*
X1189629Y199903D01*
X1189504Y199528D01*
Y198528D01*
G01X1188462Y202961D02*
X1190962D01*
X1189170Y201419D01*
Y203503D01*
G01X1188754Y204853D02*
X1188545Y205144D01*
X1188462Y205478D01*
X1188545Y205811D01*
X1188795Y206103D01*
X1189170Y206311D01*
X1189545Y206394D01*
X1190004D01*
X1190379Y206311D01*
X1190712Y206103D01*
X1190879Y205853D01*
X1190962Y205561D01*
X1190879Y205228D01*
X1190712Y204978D01*
X1190462Y204811D01*
X1190129Y204728D01*
X1189837Y204811D01*
X1189545Y205019D01*
X1189379Y205269D01*
X1189337Y205561D01*
X1189420Y205894D01*
X1189629Y206144D01*
X1190004Y206394D01*
G01X1198105Y189550D02*
X1200605D01*
Y190591D01*
X1200480Y190925D01*
X1200313Y191133D01*
X1199980Y191216D01*
X1199647Y191133D01*
X1199438Y190883D01*
X1199313Y190591D01*
Y189550D01*
G01Y190591D02*
X1198105Y191216D01*
G01X1198605Y192566D02*
X1198313Y192816D01*
X1198147Y193150D01*
X1198105Y193525D01*
X1198147Y193858D01*
X1198355Y194191D01*
X1198605Y194400D01*
X1198855Y194441D01*
X1199147Y194358D01*
X1199355Y194066D01*
X1199438Y193775D01*
Y193400D01*
G01Y193775D02*
X1199563Y194025D01*
X1199772Y194233D01*
X1200022Y194316D01*
X1200272Y194233D01*
X1200480Y194025D01*
X1200605Y193650D01*
X1200563Y193275D01*
X1200397Y192900D01*
G01X1198105Y195750D02*
X1200605D01*
Y196750D01*
X1200480Y197083D01*
X1200188Y197333D01*
X1199855Y197416D01*
X1199522Y197333D01*
X1199272Y197125D01*
X1199147Y196750D01*
Y195750D01*
G01X1198105Y200183D02*
X1200605D01*
X1198813Y198641D01*
Y200725D01*
G01X1198480Y201866D02*
X1198272Y202116D01*
X1198147Y202408D01*
X1198105Y202783D01*
X1198188Y203158D01*
X1198355Y203450D01*
X1198647Y203658D01*
X1198980Y203700D01*
X1199313Y203616D01*
X1199522Y203408D01*
X1199688Y203116D01*
X1199730Y202825D01*
X1199688Y202533D01*
X1199522Y202158D01*
X1200605Y202283D01*
Y203408D01*
G01X1239100Y387542D02*
X1192400D01*
Y391700D01*
X1186700D01*
Y390100D01*
X1183100D01*
Y391200D01*
X1179800D01*
Y389900D01*
X1176600D01*
Y391500D01*
X1172808D01*
Y469030D01*
X1178056D01*
G01X1186139Y392549D02*
Y395049D01*
X1185098D01*
X1184764Y394924D01*
X1184556Y394757D01*
X1184473Y394424D01*
X1184556Y394091D01*
X1184806Y393882D01*
X1185098Y393757D01*
X1186139D01*
G01X1185098D02*
X1184473Y392549D01*
G01X1183123Y393049D02*
X1182873Y392757D01*
X1182539Y392591D01*
X1182164Y392549D01*
X1181831Y392591D01*
X1181498Y392799D01*
X1181289Y393049D01*
X1181248Y393299D01*
X1181331Y393591D01*
X1181623Y393799D01*
X1181914Y393882D01*
X1182289D01*
G01X1181914D02*
X1181664Y394007D01*
X1181456Y394216D01*
X1181373Y394466D01*
X1181456Y394716D01*
X1181664Y394924D01*
X1182039Y395049D01*
X1182414Y395007D01*
X1182789Y394841D01*
G01X1180064Y392549D02*
Y395049D01*
X1178148Y392549D01*
Y395049D01*
G01X1176798Y394632D02*
X1176548Y394882D01*
X1176256Y395007D01*
X1175923Y395049D01*
X1175506Y394966D01*
X1175214Y394757D01*
X1175131Y394507D01*
X1175173Y394257D01*
X1175339Y394049D01*
X1176173Y393632D01*
X1176548Y393341D01*
X1176798Y392924D01*
X1176881Y392549D01*
X1175131D01*
G01X1216943Y403732D02*
X1217193Y403857D01*
X1217485Y403940D01*
X1217818D01*
X1218193Y403815D01*
X1218485Y403607D01*
X1218693Y403357D01*
X1218860Y402940D01*
X1218902Y402565D01*
X1218818Y402190D01*
X1218693Y401940D01*
X1218443Y401690D01*
X1218152Y401523D01*
X1217860Y401440D01*
X1217568D01*
X1217277Y401523D01*
X1217027Y401648D01*
X1216818Y401815D01*
G01X1215677Y401940D02*
X1215427Y401648D01*
X1215093Y401482D01*
X1214718Y401440D01*
X1214385Y401482D01*
X1214052Y401690D01*
X1213843Y401940D01*
X1213802Y402190D01*
X1213885Y402482D01*
X1214177Y402690D01*
X1214468Y402773D01*
X1214843D01*
G01X1214468D02*
X1214218Y402898D01*
X1214010Y403107D01*
X1213927Y403357D01*
X1214010Y403607D01*
X1214218Y403815D01*
X1214593Y403940D01*
X1214968Y403898D01*
X1215343Y403732D01*
G01X1212618Y401440D02*
Y403940D01*
X1210702Y401440D01*
Y403940D01*
G01X1209352Y403523D02*
X1209102Y403773D01*
X1208810Y403898D01*
X1208477Y403940D01*
X1208060Y403857D01*
X1207768Y403648D01*
X1207685Y403398D01*
X1207727Y403148D01*
X1207893Y402940D01*
X1208727Y402523D01*
X1209102Y402232D01*
X1209352Y401815D01*
X1209435Y401440D01*
X1207685D01*
G01X1206252Y403523D02*
X1206002Y403773D01*
X1205710Y403898D01*
X1205377Y403940D01*
X1204960Y403857D01*
X1204668Y403648D01*
X1204585Y403398D01*
X1204627Y403148D01*
X1204793Y402940D01*
X1205627Y402523D01*
X1206002Y402232D01*
X1206252Y401815D01*
X1206335Y401440D01*
X1204585D01*
G01X1214121Y395288D02*
X1214371Y395413D01*
X1214663Y395496D01*
X1214996D01*
X1215371Y395371D01*
X1215663Y395163D01*
X1215871Y394913D01*
X1216038Y394496D01*
X1216080Y394121D01*
X1215996Y393746D01*
X1215871Y393496D01*
X1215621Y393246D01*
X1215330Y393079D01*
X1215038Y392996D01*
X1214746D01*
X1214455Y393079D01*
X1214205Y393204D01*
X1213996Y393371D01*
G01X1212855Y393496D02*
X1212605Y393204D01*
X1212271Y393038D01*
X1211896Y392996D01*
X1211563Y393038D01*
X1211230Y393246D01*
X1211021Y393496D01*
X1210980Y393746D01*
X1211063Y394038D01*
X1211355Y394246D01*
X1211646Y394329D01*
X1212021D01*
G01X1211646D02*
X1211396Y394454D01*
X1211188Y394663D01*
X1211105Y394913D01*
X1211188Y395163D01*
X1211396Y395371D01*
X1211771Y395496D01*
X1212146Y395454D01*
X1212521Y395288D01*
G01X1209796Y392996D02*
Y395496D01*
X1207880Y392996D01*
Y395496D01*
G01X1206530Y395079D02*
X1206280Y395329D01*
X1205988Y395454D01*
X1205655Y395496D01*
X1205238Y395413D01*
X1204946Y395204D01*
X1204863Y394954D01*
X1204905Y394704D01*
X1205071Y394496D01*
X1205905Y394079D01*
X1206280Y393788D01*
X1206530Y393371D01*
X1206613Y392996D01*
X1204863D01*
G01X1203346Y393288D02*
X1203055Y393079D01*
X1202721Y392996D01*
X1202388Y393079D01*
X1202096Y393329D01*
X1201888Y393704D01*
X1201805Y394079D01*
Y394538D01*
X1201888Y394913D01*
X1202096Y395246D01*
X1202346Y395413D01*
X1202638Y395496D01*
X1202971Y395413D01*
X1203221Y395246D01*
X1203388Y394996D01*
X1203471Y394663D01*
X1203388Y394371D01*
X1203180Y394079D01*
X1202930Y393913D01*
X1202638Y393871D01*
X1202305Y393954D01*
X1202055Y394163D01*
X1201805Y394538D01*
G01X1214630Y399243D02*
X1214880Y399368D01*
X1215172Y399451D01*
X1215505D01*
X1215880Y399326D01*
X1216172Y399118D01*
X1216380Y398868D01*
X1216547Y398451D01*
X1216589Y398076D01*
X1216505Y397701D01*
X1216380Y397451D01*
X1216130Y397201D01*
X1215839Y397034D01*
X1215547Y396951D01*
X1215255D01*
X1214964Y397034D01*
X1214714Y397159D01*
X1214505Y397326D01*
G01X1213364Y397451D02*
X1213114Y397159D01*
X1212780Y396993D01*
X1212405Y396951D01*
X1212072Y396993D01*
X1211739Y397201D01*
X1211530Y397451D01*
X1211489Y397701D01*
X1211572Y397993D01*
X1211864Y398201D01*
X1212155Y398284D01*
X1212530D01*
G01X1212155D02*
X1211905Y398409D01*
X1211697Y398618D01*
X1211614Y398868D01*
X1211697Y399118D01*
X1211905Y399326D01*
X1212280Y399451D01*
X1212655Y399409D01*
X1213030Y399243D01*
G01X1210305Y396951D02*
Y399451D01*
X1208389Y396951D01*
Y399451D01*
G01X1207039Y399034D02*
X1206789Y399284D01*
X1206497Y399409D01*
X1206164Y399451D01*
X1205747Y399368D01*
X1205455Y399159D01*
X1205372Y398909D01*
X1205414Y398659D01*
X1205580Y398451D01*
X1206414Y398034D01*
X1206789Y397743D01*
X1207039Y397326D01*
X1207122Y396951D01*
X1205372D01*
G01X1204064Y397326D02*
X1203814Y397118D01*
X1203522Y396993D01*
X1203147Y396951D01*
X1202772Y397034D01*
X1202480Y397201D01*
X1202272Y397493D01*
X1202230Y397826D01*
X1202314Y398159D01*
X1202522Y398368D01*
X1202814Y398534D01*
X1203105Y398576D01*
X1203397Y398534D01*
X1203772Y398368D01*
X1203647Y399451D01*
X1202522D01*
G01X1230733Y398682D02*
X1230983Y398807D01*
X1231275Y398890D01*
X1231608D01*
X1231983Y398765D01*
X1232275Y398557D01*
X1232483Y398307D01*
X1232650Y397890D01*
X1232692Y397515D01*
X1232608Y397140D01*
X1232483Y396890D01*
X1232233Y396640D01*
X1231942Y396473D01*
X1231650Y396390D01*
X1231358D01*
X1231067Y396473D01*
X1230817Y396598D01*
X1230608Y396765D01*
G01X1229342Y398473D02*
X1229092Y398723D01*
X1228800Y398848D01*
X1228467Y398890D01*
X1228050Y398807D01*
X1227758Y398598D01*
X1227675Y398348D01*
X1227717Y398098D01*
X1227883Y397890D01*
X1228717Y397473D01*
X1229092Y397182D01*
X1229342Y396765D01*
X1229425Y396390D01*
X1227675D01*
G01X1226408D02*
Y398890D01*
X1224492Y396390D01*
Y398890D01*
G01X1223142Y398473D02*
X1222892Y398723D01*
X1222600Y398848D01*
X1222267Y398890D01*
X1221850Y398807D01*
X1221558Y398598D01*
X1221475Y398348D01*
X1221517Y398098D01*
X1221683Y397890D01*
X1222517Y397473D01*
X1222892Y397182D01*
X1223142Y396765D01*
X1223225Y396390D01*
X1221475D01*
G01X1219250Y398890D02*
X1219583Y398807D01*
X1219833Y398598D01*
X1220000Y398348D01*
X1220125Y398015D01*
X1220167Y397640D01*
X1220125Y397265D01*
X1220000Y396932D01*
X1219833Y396682D01*
X1219583Y396473D01*
X1219250Y396390D01*
X1218917Y396473D01*
X1218667Y396682D01*
X1218500Y396932D01*
X1218375Y397265D01*
X1218333Y397640D01*
X1218375Y398015D01*
X1218500Y398348D01*
X1218667Y398598D01*
X1218917Y398807D01*
X1219250Y398890D01*
G01X1191535Y398598D02*
X1191660Y398348D01*
X1191743Y398056D01*
Y397723D01*
X1191618Y397348D01*
X1191410Y397056D01*
X1191160Y396848D01*
X1190743Y396681D01*
X1190368Y396639D01*
X1189993Y396723D01*
X1189743Y396848D01*
X1189493Y397098D01*
X1189326Y397389D01*
X1189243Y397681D01*
Y397973D01*
X1189326Y398264D01*
X1189451Y398514D01*
X1189618Y398723D01*
G01X1189743Y399864D02*
X1189451Y400114D01*
X1189285Y400448D01*
X1189243Y400823D01*
X1189285Y401156D01*
X1189493Y401489D01*
X1189743Y401698D01*
X1189993Y401739D01*
X1190285Y401656D01*
X1190493Y401364D01*
X1190576Y401073D01*
Y400698D01*
G01Y401073D02*
X1190701Y401323D01*
X1190910Y401531D01*
X1191160Y401614D01*
X1191410Y401531D01*
X1191618Y401323D01*
X1191743Y400948D01*
X1191701Y400573D01*
X1191535Y400198D01*
G01X1189243Y402923D02*
X1191743D01*
X1189243Y404839D01*
X1191743D01*
G01X1189243Y406981D02*
X1191743D01*
X1191243Y406481D01*
G01X1189243D02*
Y407481D01*
G01X1189535Y409373D02*
X1189326Y409664D01*
X1189243Y409998D01*
X1189326Y410331D01*
X1189576Y410623D01*
X1189951Y410831D01*
X1190326Y410914D01*
X1190785D01*
X1191160Y410831D01*
X1191493Y410623D01*
X1191660Y410373D01*
X1191743Y410081D01*
X1191660Y409748D01*
X1191493Y409498D01*
X1191243Y409331D01*
X1190910Y409248D01*
X1190618Y409331D01*
X1190326Y409539D01*
X1190160Y409789D01*
X1190118Y410081D01*
X1190201Y410414D01*
X1190410Y410664D01*
X1190785Y410914D01*
G01X1187535Y398598D02*
X1187660Y398348D01*
X1187743Y398056D01*
Y397723D01*
X1187618Y397348D01*
X1187410Y397056D01*
X1187160Y396848D01*
X1186743Y396681D01*
X1186368Y396639D01*
X1185993Y396723D01*
X1185743Y396848D01*
X1185493Y397098D01*
X1185326Y397389D01*
X1185243Y397681D01*
Y397973D01*
X1185326Y398264D01*
X1185451Y398514D01*
X1185618Y398723D01*
G01X1185743Y399864D02*
X1185451Y400114D01*
X1185285Y400448D01*
X1185243Y400823D01*
X1185285Y401156D01*
X1185493Y401489D01*
X1185743Y401698D01*
X1185993Y401739D01*
X1186285Y401656D01*
X1186493Y401364D01*
X1186576Y401073D01*
Y400698D01*
G01Y401073D02*
X1186701Y401323D01*
X1186910Y401531D01*
X1187160Y401614D01*
X1187410Y401531D01*
X1187618Y401323D01*
X1187743Y400948D01*
X1187701Y400573D01*
X1187535Y400198D01*
G01X1185243Y402923D02*
X1187743D01*
X1185243Y404839D01*
X1187743D01*
G01X1187326Y406189D02*
X1187576Y406439D01*
X1187701Y406731D01*
X1187743Y407064D01*
X1187660Y407481D01*
X1187451Y407773D01*
X1187201Y407856D01*
X1186951Y407814D01*
X1186743Y407648D01*
X1186326Y406814D01*
X1186035Y406439D01*
X1185618Y406189D01*
X1185243Y406106D01*
Y407856D01*
G01X1187743Y410081D02*
X1187660Y409748D01*
X1187451Y409498D01*
X1187201Y409331D01*
X1186868Y409206D01*
X1186493Y409164D01*
X1186118Y409206D01*
X1185785Y409331D01*
X1185535Y409498D01*
X1185326Y409748D01*
X1185243Y410081D01*
X1185326Y410414D01*
X1185535Y410664D01*
X1185785Y410831D01*
X1186118Y410956D01*
X1186493Y410998D01*
X1186868Y410956D01*
X1187201Y410831D01*
X1187451Y410664D01*
X1187660Y410414D01*
X1187743Y410081D01*
G01X1183535Y398598D02*
X1183660Y398348D01*
X1183743Y398056D01*
Y397723D01*
X1183618Y397348D01*
X1183410Y397056D01*
X1183160Y396848D01*
X1182743Y396681D01*
X1182368Y396639D01*
X1181993Y396723D01*
X1181743Y396848D01*
X1181493Y397098D01*
X1181326Y397389D01*
X1181243Y397681D01*
Y397973D01*
X1181326Y398264D01*
X1181451Y398514D01*
X1181618Y398723D01*
G01X1181743Y399864D02*
X1181451Y400114D01*
X1181285Y400448D01*
X1181243Y400823D01*
X1181285Y401156D01*
X1181493Y401489D01*
X1181743Y401698D01*
X1181993Y401739D01*
X1182285Y401656D01*
X1182493Y401364D01*
X1182576Y401073D01*
Y400698D01*
G01Y401073D02*
X1182701Y401323D01*
X1182910Y401531D01*
X1183160Y401614D01*
X1183410Y401531D01*
X1183618Y401323D01*
X1183743Y400948D01*
X1183701Y400573D01*
X1183535Y400198D01*
G01X1181243Y402923D02*
X1183743D01*
X1181243Y404839D01*
X1183743D01*
G01X1183326Y406189D02*
X1183576Y406439D01*
X1183701Y406731D01*
X1183743Y407064D01*
X1183660Y407481D01*
X1183451Y407773D01*
X1183201Y407856D01*
X1182951Y407814D01*
X1182743Y407648D01*
X1182326Y406814D01*
X1182035Y406439D01*
X1181618Y406189D01*
X1181243Y406106D01*
Y407856D01*
G01X1181743Y409164D02*
X1181451Y409414D01*
X1181285Y409748D01*
X1181243Y410123D01*
X1181285Y410456D01*
X1181493Y410789D01*
X1181743Y410998D01*
X1181993Y411039D01*
X1182285Y410956D01*
X1182493Y410664D01*
X1182576Y410373D01*
Y409998D01*
G01Y410373D02*
X1182701Y410623D01*
X1182910Y410831D01*
X1183160Y410914D01*
X1183410Y410831D01*
X1183618Y410623D01*
X1183743Y410248D01*
X1183701Y409873D01*
X1183535Y409498D01*
G01X1185680Y450951D02*
X1182347Y457951D01*
X1179014Y450951D01*
G01X1180214Y453401D02*
X1184480D01*
G01X1204213Y443655D02*
X1204463Y443780D01*
X1204755Y443863D01*
X1205088D01*
X1205463Y443738D01*
X1205755Y443530D01*
X1205963Y443280D01*
X1206130Y442863D01*
X1206172Y442488D01*
X1206088Y442113D01*
X1205963Y441863D01*
X1205713Y441613D01*
X1205422Y441446D01*
X1205130Y441363D01*
X1204838D01*
X1204547Y441446D01*
X1204297Y441571D01*
X1204088Y441738D01*
G01X1202947Y441863D02*
X1202697Y441571D01*
X1202363Y441405D01*
X1201988Y441363D01*
X1201655Y441405D01*
X1201322Y441613D01*
X1201113Y441863D01*
X1201072Y442113D01*
X1201155Y442405D01*
X1201447Y442613D01*
X1201738Y442696D01*
X1202113D01*
G01X1201738D02*
X1201488Y442821D01*
X1201280Y443030D01*
X1201197Y443280D01*
X1201280Y443530D01*
X1201488Y443738D01*
X1201863Y443863D01*
X1202238Y443821D01*
X1202613Y443655D01*
G01X1199888Y441363D02*
Y443863D01*
X1197972Y441363D01*
Y443863D01*
G01X1195830Y441363D02*
Y443863D01*
X1196330Y443363D01*
G01Y441363D02*
X1195330D01*
G01X1193522Y443446D02*
X1193272Y443696D01*
X1192980Y443821D01*
X1192647Y443863D01*
X1192230Y443780D01*
X1191938Y443571D01*
X1191855Y443321D01*
X1191897Y443071D01*
X1192063Y442863D01*
X1192897Y442446D01*
X1193272Y442155D01*
X1193522Y441738D01*
X1193605Y441363D01*
X1191855D01*
G01X1228548Y456905D02*
X1228798Y457030D01*
X1229090Y457113D01*
X1229423D01*
X1229798Y456988D01*
X1230090Y456780D01*
X1230298Y456530D01*
X1230465Y456113D01*
X1230507Y455738D01*
X1230423Y455363D01*
X1230298Y455113D01*
X1230048Y454863D01*
X1229757Y454696D01*
X1229465Y454613D01*
X1229173D01*
X1228882Y454696D01*
X1228632Y454821D01*
X1228423Y454988D01*
G01X1227157Y456696D02*
X1226907Y456946D01*
X1226615Y457071D01*
X1226282Y457113D01*
X1225865Y457030D01*
X1225573Y456821D01*
X1225490Y456571D01*
X1225532Y456321D01*
X1225698Y456113D01*
X1226532Y455696D01*
X1226907Y455405D01*
X1227157Y454988D01*
X1227240Y454613D01*
X1225490D01*
G01X1224348D02*
Y457113D01*
X1223265Y455030D01*
X1222182Y457113D01*
Y454613D01*
G01X1220957Y456696D02*
X1220707Y456946D01*
X1220415Y457071D01*
X1220082Y457113D01*
X1219665Y457030D01*
X1219373Y456821D01*
X1219290Y456571D01*
X1219332Y456321D01*
X1219498Y456113D01*
X1220332Y455696D01*
X1220707Y455405D01*
X1220957Y454988D01*
X1221040Y454613D01*
X1219290D01*
G01X1217065Y457113D02*
X1217398Y457030D01*
X1217648Y456821D01*
X1217815Y456571D01*
X1217940Y456238D01*
X1217982Y455863D01*
X1217940Y455488D01*
X1217815Y455155D01*
X1217648Y454905D01*
X1217398Y454696D01*
X1217065Y454613D01*
X1216732Y454696D01*
X1216482Y454905D01*
X1216315Y455155D01*
X1216190Y455488D01*
X1216148Y455863D01*
X1216190Y456238D01*
X1216315Y456571D01*
X1216482Y456821D01*
X1216732Y457030D01*
X1217065Y457113D01*
G01X1228548Y460905D02*
X1228798Y461030D01*
X1229090Y461113D01*
X1229423D01*
X1229798Y460988D01*
X1230090Y460780D01*
X1230298Y460530D01*
X1230465Y460113D01*
X1230507Y459738D01*
X1230423Y459363D01*
X1230298Y459113D01*
X1230048Y458863D01*
X1229757Y458696D01*
X1229465Y458613D01*
X1229173D01*
X1228882Y458696D01*
X1228632Y458821D01*
X1228423Y458988D01*
G01X1227157Y460696D02*
X1226907Y460946D01*
X1226615Y461071D01*
X1226282Y461113D01*
X1225865Y461030D01*
X1225573Y460821D01*
X1225490Y460571D01*
X1225532Y460321D01*
X1225698Y460113D01*
X1226532Y459696D01*
X1226907Y459405D01*
X1227157Y458988D01*
X1227240Y458613D01*
X1225490D01*
G01X1224348D02*
Y461113D01*
X1223265Y459030D01*
X1222182Y461113D01*
Y458613D01*
G01X1220165D02*
Y461113D01*
X1220665Y460613D01*
G01Y458613D02*
X1219665D01*
G01X1217857Y459655D02*
X1217565Y459946D01*
X1217315Y460113D01*
X1216982Y460196D01*
X1216690Y460113D01*
X1216482Y459946D01*
X1216315Y459696D01*
X1216273Y459405D01*
X1216315Y459155D01*
X1216482Y458905D01*
X1216732Y458696D01*
X1217023Y458613D01*
X1217357Y458696D01*
X1217648Y458946D01*
X1217815Y459321D01*
X1217857Y459738D01*
X1217773Y460280D01*
X1217648Y460571D01*
X1217440Y460863D01*
X1217148Y461071D01*
X1216857Y461113D01*
X1216565Y461030D01*
X1216357Y460821D01*
G01X1194051Y448039D02*
X1194176Y447789D01*
X1194259Y447497D01*
Y447164D01*
X1194134Y446789D01*
X1193926Y446497D01*
X1193676Y446289D01*
X1193259Y446122D01*
X1192884Y446080D01*
X1192509Y446164D01*
X1192259Y446289D01*
X1192009Y446539D01*
X1191842Y446830D01*
X1191759Y447122D01*
Y447414D01*
X1191842Y447705D01*
X1191967Y447955D01*
X1192134Y448164D01*
G01X1192259Y449305D02*
X1191967Y449555D01*
X1191801Y449889D01*
X1191759Y450264D01*
X1191801Y450597D01*
X1192009Y450930D01*
X1192259Y451139D01*
X1192509Y451180D01*
X1192801Y451097D01*
X1193009Y450805D01*
X1193092Y450514D01*
Y450139D01*
G01Y450514D02*
X1193217Y450764D01*
X1193426Y450972D01*
X1193676Y451055D01*
X1193926Y450972D01*
X1194134Y450764D01*
X1194259Y450389D01*
X1194217Y450014D01*
X1194051Y449639D01*
G01X1191759Y452239D02*
X1194259D01*
X1192176Y453322D01*
X1194259Y454405D01*
X1191759D01*
G01Y456922D02*
X1194259D01*
X1192467Y455380D01*
Y457464D01*
G01X1193842Y458730D02*
X1194092Y458980D01*
X1194217Y459272D01*
X1194259Y459605D01*
X1194176Y460022D01*
X1193967Y460314D01*
X1193717Y460397D01*
X1193467Y460355D01*
X1193259Y460189D01*
X1192842Y459355D01*
X1192551Y458980D01*
X1192134Y458730D01*
X1191759Y458647D01*
Y460397D01*
G01X1204213Y439655D02*
X1204463Y439780D01*
X1204755Y439863D01*
X1205088D01*
X1205463Y439738D01*
X1205755Y439530D01*
X1205963Y439280D01*
X1206130Y438863D01*
X1206172Y438488D01*
X1206088Y438113D01*
X1205963Y437863D01*
X1205713Y437613D01*
X1205422Y437446D01*
X1205130Y437363D01*
X1204838D01*
X1204547Y437446D01*
X1204297Y437571D01*
X1204088Y437738D01*
G01X1202947Y437863D02*
X1202697Y437571D01*
X1202363Y437405D01*
X1201988Y437363D01*
X1201655Y437405D01*
X1201322Y437613D01*
X1201113Y437863D01*
X1201072Y438113D01*
X1201155Y438405D01*
X1201447Y438613D01*
X1201738Y438696D01*
X1202113D01*
G01X1201738D02*
X1201488Y438821D01*
X1201280Y439030D01*
X1201197Y439280D01*
X1201280Y439530D01*
X1201488Y439738D01*
X1201863Y439863D01*
X1202238Y439821D01*
X1202613Y439655D01*
G01X1199888Y437363D02*
Y439863D01*
X1197972Y437363D01*
Y439863D01*
G01X1196622Y439446D02*
X1196372Y439696D01*
X1196080Y439821D01*
X1195747Y439863D01*
X1195330Y439780D01*
X1195038Y439571D01*
X1194955Y439321D01*
X1194997Y439071D01*
X1195163Y438863D01*
X1195997Y438446D01*
X1196372Y438155D01*
X1196622Y437738D01*
X1196705Y437363D01*
X1194955D01*
G01X1192730D02*
Y439863D01*
X1193230Y439363D01*
G01Y437363D02*
X1192230D01*
G01X1177508Y441805D02*
X1177633Y441555D01*
X1177716Y441263D01*
Y440930D01*
X1177591Y440555D01*
X1177383Y440263D01*
X1177133Y440055D01*
X1176716Y439888D01*
X1176341Y439846D01*
X1175966Y439930D01*
X1175716Y440055D01*
X1175466Y440305D01*
X1175299Y440596D01*
X1175216Y440888D01*
Y441180D01*
X1175299Y441471D01*
X1175424Y441721D01*
X1175591Y441930D01*
G01X1175716Y443071D02*
X1175424Y443321D01*
X1175258Y443655D01*
X1175216Y444030D01*
X1175258Y444363D01*
X1175466Y444696D01*
X1175716Y444905D01*
X1175966Y444946D01*
X1176258Y444863D01*
X1176466Y444571D01*
X1176549Y444280D01*
Y443905D01*
G01Y444280D02*
X1176674Y444530D01*
X1176883Y444738D01*
X1177133Y444821D01*
X1177383Y444738D01*
X1177591Y444530D01*
X1177716Y444155D01*
X1177674Y443780D01*
X1177508Y443405D01*
G01X1175216Y446005D02*
X1177716D01*
X1175633Y447088D01*
X1177716Y448171D01*
X1175216D01*
G01X1175716Y449271D02*
X1175424Y449521D01*
X1175258Y449855D01*
X1175216Y450230D01*
X1175258Y450563D01*
X1175466Y450896D01*
X1175716Y451105D01*
X1175966Y451146D01*
X1176258Y451063D01*
X1176466Y450771D01*
X1176549Y450480D01*
Y450105D01*
G01Y450480D02*
X1176674Y450730D01*
X1176883Y450938D01*
X1177133Y451021D01*
X1177383Y450938D01*
X1177591Y450730D01*
X1177716Y450355D01*
X1177674Y449980D01*
X1177508Y449605D01*
G01X1175508Y452580D02*
X1175299Y452871D01*
X1175216Y453205D01*
X1175299Y453538D01*
X1175549Y453830D01*
X1175924Y454038D01*
X1176299Y454121D01*
X1176758D01*
X1177133Y454038D01*
X1177466Y453830D01*
X1177633Y453580D01*
X1177716Y453288D01*
X1177633Y452955D01*
X1177466Y452705D01*
X1177216Y452538D01*
X1176883Y452455D01*
X1176591Y452538D01*
X1176299Y452746D01*
X1176133Y452996D01*
X1176091Y453288D01*
X1176174Y453621D01*
X1176383Y453871D01*
X1176758Y454121D01*
G01X1216569Y439009D02*
X1216694Y438759D01*
X1216777Y438467D01*
Y438134D01*
X1216652Y437759D01*
X1216444Y437467D01*
X1216194Y437259D01*
X1215777Y437092D01*
X1215402Y437050D01*
X1215027Y437134D01*
X1214777Y437259D01*
X1214527Y437509D01*
X1214360Y437800D01*
X1214277Y438092D01*
Y438384D01*
X1214360Y438675D01*
X1214485Y438925D01*
X1214652Y439134D01*
G01X1216360Y440400D02*
X1216610Y440650D01*
X1216735Y440942D01*
X1216777Y441275D01*
X1216694Y441692D01*
X1216485Y441984D01*
X1216235Y442067D01*
X1215985Y442025D01*
X1215777Y441859D01*
X1215360Y441025D01*
X1215069Y440650D01*
X1214652Y440400D01*
X1214277Y440317D01*
Y442067D01*
G01Y443209D02*
X1216777D01*
X1214694Y444292D01*
X1216777Y445375D01*
X1214277D01*
G01X1216360Y446600D02*
X1216610Y446850D01*
X1216735Y447142D01*
X1216777Y447475D01*
X1216694Y447892D01*
X1216485Y448184D01*
X1216235Y448267D01*
X1215985Y448225D01*
X1215777Y448059D01*
X1215360Y447225D01*
X1215069Y446850D01*
X1214652Y446600D01*
X1214277Y446517D01*
Y448267D01*
G01Y450492D02*
X1216777D01*
X1216277Y449992D01*
G01X1214277D02*
Y450992D01*
G01X1212569Y439009D02*
X1212694Y438759D01*
X1212777Y438467D01*
Y438134D01*
X1212652Y437759D01*
X1212444Y437467D01*
X1212194Y437259D01*
X1211777Y437092D01*
X1211402Y437050D01*
X1211027Y437134D01*
X1210777Y437259D01*
X1210527Y437509D01*
X1210360Y437800D01*
X1210277Y438092D01*
Y438384D01*
X1210360Y438675D01*
X1210485Y438925D01*
X1210652Y439134D01*
G01X1212360Y440400D02*
X1212610Y440650D01*
X1212735Y440942D01*
X1212777Y441275D01*
X1212694Y441692D01*
X1212485Y441984D01*
X1212235Y442067D01*
X1211985Y442025D01*
X1211777Y441859D01*
X1211360Y441025D01*
X1211069Y440650D01*
X1210652Y440400D01*
X1210277Y440317D01*
Y442067D01*
G01Y443209D02*
X1212777D01*
X1210694Y444292D01*
X1212777Y445375D01*
X1210277D01*
G01X1212360Y446600D02*
X1212610Y446850D01*
X1212735Y447142D01*
X1212777Y447475D01*
X1212694Y447892D01*
X1212485Y448184D01*
X1212235Y448267D01*
X1211985Y448225D01*
X1211777Y448059D01*
X1211360Y447225D01*
X1211069Y446850D01*
X1210652Y446600D01*
X1210277Y446517D01*
Y448267D01*
G01X1212360Y449700D02*
X1212610Y449950D01*
X1212735Y450242D01*
X1212777Y450575D01*
X1212694Y450992D01*
X1212485Y451284D01*
X1212235Y451367D01*
X1211985Y451325D01*
X1211777Y451159D01*
X1211360Y450325D01*
X1211069Y449950D01*
X1210652Y449700D01*
X1210277Y449617D01*
Y451367D01*
G01X1204063Y455427D02*
X1204188Y455177D01*
X1204271Y454885D01*
Y454552D01*
X1204146Y454177D01*
X1203938Y453885D01*
X1203688Y453677D01*
X1203271Y453510D01*
X1202896Y453468D01*
X1202521Y453552D01*
X1202271Y453677D01*
X1202021Y453927D01*
X1201854Y454218D01*
X1201771Y454510D01*
Y454802D01*
X1201854Y455093D01*
X1201979Y455343D01*
X1202146Y455552D01*
G01X1203854Y456818D02*
X1204104Y457068D01*
X1204229Y457360D01*
X1204271Y457693D01*
X1204188Y458110D01*
X1203979Y458402D01*
X1203729Y458485D01*
X1203479Y458443D01*
X1203271Y458277D01*
X1202854Y457443D01*
X1202563Y457068D01*
X1202146Y456818D01*
X1201771Y456735D01*
Y458485D01*
G01Y459627D02*
X1204271D01*
X1202188Y460710D01*
X1204271Y461793D01*
X1201771D01*
G01Y463810D02*
X1204271D01*
X1203771Y463310D01*
G01X1201771D02*
Y464310D01*
G01X1202063Y466202D02*
X1201854Y466493D01*
X1201771Y466827D01*
X1201854Y467160D01*
X1202104Y467452D01*
X1202479Y467660D01*
X1202854Y467743D01*
X1203313D01*
X1203688Y467660D01*
X1204021Y467452D01*
X1204188Y467202D01*
X1204271Y466910D01*
X1204188Y466577D01*
X1204021Y466327D01*
X1203771Y466160D01*
X1203438Y466077D01*
X1203146Y466160D01*
X1202854Y466368D01*
X1202688Y466618D01*
X1202646Y466910D01*
X1202729Y467243D01*
X1202938Y467493D01*
X1203313Y467743D01*
G01X1212494Y455261D02*
X1212619Y455011D01*
X1212702Y454719D01*
Y454386D01*
X1212577Y454011D01*
X1212369Y453719D01*
X1212119Y453511D01*
X1211702Y453344D01*
X1211327Y453302D01*
X1210952Y453386D01*
X1210702Y453511D01*
X1210452Y453761D01*
X1210285Y454052D01*
X1210202Y454344D01*
Y454636D01*
X1210285Y454927D01*
X1210410Y455177D01*
X1210577Y455386D01*
G01X1212285Y456652D02*
X1212535Y456902D01*
X1212660Y457194D01*
X1212702Y457527D01*
X1212619Y457944D01*
X1212410Y458236D01*
X1212160Y458319D01*
X1211910Y458277D01*
X1211702Y458111D01*
X1211285Y457277D01*
X1210994Y456902D01*
X1210577Y456652D01*
X1210202Y456569D01*
Y458319D01*
G01Y459461D02*
X1212702D01*
X1210619Y460544D01*
X1212702Y461627D01*
X1210202D01*
G01Y463644D02*
X1212702D01*
X1212202Y463144D01*
G01X1210202D02*
Y464144D01*
G01Y466744D02*
X1210244Y467036D01*
X1210369Y467369D01*
X1210577Y467577D01*
X1210869Y467661D01*
X1211160Y467577D01*
X1211410Y467327D01*
X1211535Y466952D01*
Y466536D01*
X1211619Y466286D01*
X1211827Y466077D01*
X1212119Y465994D01*
X1212410Y466119D01*
X1212619Y466411D01*
X1212702Y466744D01*
X1212619Y467077D01*
X1212410Y467369D01*
X1212119Y467494D01*
X1211827Y467411D01*
X1211619Y467202D01*
X1211535Y466952D01*
Y466536D01*
X1211410Y466161D01*
X1211160Y465911D01*
X1210869Y465827D01*
X1210577Y465911D01*
X1210369Y466119D01*
X1210244Y466452D01*
X1210202Y466744D01*
G01X1196364Y464814D02*
X1196614Y464939D01*
X1196906Y465022D01*
X1197239D01*
X1197614Y464897D01*
X1197906Y464689D01*
X1198114Y464439D01*
X1198281Y464022D01*
X1198323Y463647D01*
X1198239Y463272D01*
X1198114Y463022D01*
X1197864Y462772D01*
X1197573Y462605D01*
X1197281Y462522D01*
X1196989D01*
X1196698Y462605D01*
X1196448Y462730D01*
X1196239Y462897D01*
G01X1195098Y463022D02*
X1194848Y462730D01*
X1194514Y462564D01*
X1194139Y462522D01*
X1193806Y462564D01*
X1193473Y462772D01*
X1193264Y463022D01*
X1193223Y463272D01*
X1193306Y463564D01*
X1193598Y463772D01*
X1193889Y463855D01*
X1194264D01*
G01X1193889D02*
X1193639Y463980D01*
X1193431Y464189D01*
X1193348Y464439D01*
X1193431Y464689D01*
X1193639Y464897D01*
X1194014Y465022D01*
X1194389Y464980D01*
X1194764Y464814D01*
G01X1192164Y462522D02*
Y465022D01*
X1191081Y462939D01*
X1189998Y465022D01*
Y462522D01*
G01X1188898Y463022D02*
X1188648Y462730D01*
X1188314Y462564D01*
X1187939Y462522D01*
X1187606Y462564D01*
X1187273Y462772D01*
X1187064Y463022D01*
X1187023Y463272D01*
X1187106Y463564D01*
X1187398Y463772D01*
X1187689Y463855D01*
X1188064D01*
G01X1187689D02*
X1187439Y463980D01*
X1187231Y464189D01*
X1187148Y464439D01*
X1187231Y464689D01*
X1187439Y464897D01*
X1187814Y465022D01*
X1188189Y464980D01*
X1188564Y464814D01*
G01X1184881Y462522D02*
X1184589Y462564D01*
X1184256Y462689D01*
X1184048Y462897D01*
X1183964Y463189D01*
X1184048Y463480D01*
X1184298Y463730D01*
X1184673Y463855D01*
X1185089D01*
X1185339Y463939D01*
X1185548Y464147D01*
X1185631Y464439D01*
X1185506Y464730D01*
X1185214Y464939D01*
X1184881Y465022D01*
X1184548Y464939D01*
X1184256Y464730D01*
X1184131Y464439D01*
X1184214Y464147D01*
X1184423Y463939D01*
X1184673Y463855D01*
X1185089D01*
X1185464Y463730D01*
X1185714Y463480D01*
X1185798Y463189D01*
X1185714Y462897D01*
X1185506Y462689D01*
X1185173Y462564D01*
X1184881Y462522D01*
G01X1216782Y426048D02*
X1216907Y425798D01*
X1216990Y425506D01*
Y425173D01*
X1216865Y424798D01*
X1216657Y424506D01*
X1216407Y424298D01*
X1215990Y424131D01*
X1215615Y424089D01*
X1215240Y424173D01*
X1214990Y424298D01*
X1214740Y424548D01*
X1214573Y424839D01*
X1214490Y425131D01*
Y425423D01*
X1214573Y425714D01*
X1214698Y425964D01*
X1214865Y426173D01*
G01X1216573Y427439D02*
X1216823Y427689D01*
X1216948Y427981D01*
X1216990Y428314D01*
X1216907Y428731D01*
X1216698Y429023D01*
X1216448Y429106D01*
X1216198Y429064D01*
X1215990Y428898D01*
X1215573Y428064D01*
X1215282Y427689D01*
X1214865Y427439D01*
X1214490Y427356D01*
Y429106D01*
G01Y430373D02*
X1216990D01*
X1214490Y432289D01*
X1216990D01*
G01X1216573Y433639D02*
X1216823Y433889D01*
X1216948Y434181D01*
X1216990Y434514D01*
X1216907Y434931D01*
X1216698Y435223D01*
X1216448Y435306D01*
X1216198Y435264D01*
X1215990Y435098D01*
X1215573Y434264D01*
X1215282Y433889D01*
X1214865Y433639D01*
X1214490Y433556D01*
Y435306D01*
G01X1193765Y425525D02*
X1193890Y425275D01*
X1193973Y424983D01*
Y424650D01*
X1193848Y424275D01*
X1193640Y423983D01*
X1193390Y423775D01*
X1192973Y423608D01*
X1192598Y423566D01*
X1192223Y423650D01*
X1191973Y423775D01*
X1191723Y424025D01*
X1191556Y424316D01*
X1191473Y424608D01*
Y424900D01*
X1191556Y425191D01*
X1191681Y425441D01*
X1191848Y425650D01*
G01X1191973Y426791D02*
X1191681Y427041D01*
X1191515Y427375D01*
X1191473Y427750D01*
X1191515Y428083D01*
X1191723Y428416D01*
X1191973Y428625D01*
X1192223Y428666D01*
X1192515Y428583D01*
X1192723Y428291D01*
X1192806Y428000D01*
Y427625D01*
G01Y428000D02*
X1192931Y428250D01*
X1193140Y428458D01*
X1193390Y428541D01*
X1193640Y428458D01*
X1193848Y428250D01*
X1193973Y427875D01*
X1193931Y427500D01*
X1193765Y427125D01*
G01X1191473Y429850D02*
X1193973D01*
X1191473Y431766D01*
X1193973D01*
G01X1192515Y433116D02*
X1192806Y433408D01*
X1192973Y433658D01*
X1193056Y433991D01*
X1192973Y434283D01*
X1192806Y434491D01*
X1192556Y434658D01*
X1192265Y434700D01*
X1192015Y434658D01*
X1191765Y434491D01*
X1191556Y434241D01*
X1191473Y433950D01*
X1191556Y433616D01*
X1191806Y433325D01*
X1192181Y433158D01*
X1192598Y433116D01*
X1193140Y433200D01*
X1193431Y433325D01*
X1193723Y433533D01*
X1193931Y433825D01*
X1193973Y434116D01*
X1193890Y434408D01*
X1193681Y434616D01*
G01X1189521Y434117D02*
X1189646Y433867D01*
X1189729Y433575D01*
Y433242D01*
X1189604Y432867D01*
X1189396Y432575D01*
X1189146Y432367D01*
X1188729Y432200D01*
X1188354Y432158D01*
X1187979Y432242D01*
X1187729Y432367D01*
X1187479Y432617D01*
X1187312Y432908D01*
X1187229Y433200D01*
Y433492D01*
X1187312Y433783D01*
X1187437Y434033D01*
X1187604Y434242D01*
G01X1187729Y435383D02*
X1187437Y435633D01*
X1187271Y435967D01*
X1187229Y436342D01*
X1187271Y436675D01*
X1187479Y437008D01*
X1187729Y437217D01*
X1187979Y437258D01*
X1188271Y437175D01*
X1188479Y436883D01*
X1188562Y436592D01*
Y436217D01*
G01Y436592D02*
X1188687Y436842D01*
X1188896Y437050D01*
X1189146Y437133D01*
X1189396Y437050D01*
X1189604Y436842D01*
X1189729Y436467D01*
X1189687Y436092D01*
X1189521Y435717D01*
G01X1187229Y438442D02*
X1189729D01*
X1187229Y440358D01*
X1189729D01*
G01X1187229Y442500D02*
X1189729D01*
X1189229Y442000D01*
G01X1187229D02*
Y443000D01*
G01X1197765Y425525D02*
X1197890Y425275D01*
X1197973Y424983D01*
Y424650D01*
X1197848Y424275D01*
X1197640Y423983D01*
X1197390Y423775D01*
X1196973Y423608D01*
X1196598Y423566D01*
X1196223Y423650D01*
X1195973Y423775D01*
X1195723Y424025D01*
X1195556Y424316D01*
X1195473Y424608D01*
Y424900D01*
X1195556Y425191D01*
X1195681Y425441D01*
X1195848Y425650D01*
G01X1195973Y426791D02*
X1195681Y427041D01*
X1195515Y427375D01*
X1195473Y427750D01*
X1195515Y428083D01*
X1195723Y428416D01*
X1195973Y428625D01*
X1196223Y428666D01*
X1196515Y428583D01*
X1196723Y428291D01*
X1196806Y428000D01*
Y427625D01*
G01Y428000D02*
X1196931Y428250D01*
X1197140Y428458D01*
X1197390Y428541D01*
X1197640Y428458D01*
X1197848Y428250D01*
X1197973Y427875D01*
X1197931Y427500D01*
X1197765Y427125D01*
G01X1195473Y429850D02*
X1197973D01*
X1195473Y431766D01*
X1197973D01*
G01X1195848Y432991D02*
X1195640Y433241D01*
X1195515Y433533D01*
X1195473Y433908D01*
X1195556Y434283D01*
X1195723Y434575D01*
X1196015Y434783D01*
X1196348Y434825D01*
X1196681Y434741D01*
X1196890Y434533D01*
X1197056Y434241D01*
X1197098Y433950D01*
X1197056Y433658D01*
X1196890Y433283D01*
X1197973Y433408D01*
Y434533D01*
G01X1190051Y448039D02*
X1190176Y447789D01*
X1190259Y447497D01*
Y447164D01*
X1190134Y446789D01*
X1189926Y446497D01*
X1189676Y446289D01*
X1189259Y446122D01*
X1188884Y446080D01*
X1188509Y446164D01*
X1188259Y446289D01*
X1188009Y446539D01*
X1187842Y446830D01*
X1187759Y447122D01*
Y447414D01*
X1187842Y447705D01*
X1187967Y447955D01*
X1188134Y448164D01*
G01X1188259Y449305D02*
X1187967Y449555D01*
X1187801Y449889D01*
X1187759Y450264D01*
X1187801Y450597D01*
X1188009Y450930D01*
X1188259Y451139D01*
X1188509Y451180D01*
X1188801Y451097D01*
X1189009Y450805D01*
X1189092Y450514D01*
Y450139D01*
G01Y450514D02*
X1189217Y450764D01*
X1189426Y450972D01*
X1189676Y451055D01*
X1189926Y450972D01*
X1190134Y450764D01*
X1190259Y450389D01*
X1190217Y450014D01*
X1190051Y449639D01*
G01X1187759Y452239D02*
X1190259D01*
X1188176Y453322D01*
X1190259Y454405D01*
X1187759D01*
G01Y456922D02*
X1190259D01*
X1188467Y455380D01*
Y457464D01*
G01X1188259Y458605D02*
X1187967Y458855D01*
X1187801Y459189D01*
X1187759Y459564D01*
X1187801Y459897D01*
X1188009Y460230D01*
X1188259Y460439D01*
X1188509Y460480D01*
X1188801Y460397D01*
X1189009Y460105D01*
X1189092Y459814D01*
Y459439D01*
G01Y459814D02*
X1189217Y460064D01*
X1189426Y460272D01*
X1189676Y460355D01*
X1189926Y460272D01*
X1190134Y460064D01*
X1190259Y459689D01*
X1190217Y459314D01*
X1190051Y458939D01*
G01X1212782Y426048D02*
X1212907Y425798D01*
X1212990Y425506D01*
Y425173D01*
X1212865Y424798D01*
X1212657Y424506D01*
X1212407Y424298D01*
X1211990Y424131D01*
X1211615Y424089D01*
X1211240Y424173D01*
X1210990Y424298D01*
X1210740Y424548D01*
X1210573Y424839D01*
X1210490Y425131D01*
Y425423D01*
X1210573Y425714D01*
X1210698Y425964D01*
X1210865Y426173D01*
G01X1212573Y427439D02*
X1212823Y427689D01*
X1212948Y427981D01*
X1212990Y428314D01*
X1212907Y428731D01*
X1212698Y429023D01*
X1212448Y429106D01*
X1212198Y429064D01*
X1211990Y428898D01*
X1211573Y428064D01*
X1211282Y427689D01*
X1210865Y427439D01*
X1210490Y427356D01*
Y429106D01*
G01Y430373D02*
X1212990D01*
X1210490Y432289D01*
X1212990D01*
G01X1210990Y433514D02*
X1210698Y433764D01*
X1210532Y434098D01*
X1210490Y434473D01*
X1210532Y434806D01*
X1210740Y435139D01*
X1210990Y435348D01*
X1211240Y435389D01*
X1211532Y435306D01*
X1211740Y435014D01*
X1211823Y434723D01*
Y434348D01*
G01Y434723D02*
X1211948Y434973D01*
X1212157Y435181D01*
X1212407Y435264D01*
X1212657Y435181D01*
X1212865Y434973D01*
X1212990Y434598D01*
X1212948Y434223D01*
X1212782Y433848D01*
G01X1208782Y426048D02*
X1208907Y425798D01*
X1208990Y425506D01*
Y425173D01*
X1208865Y424798D01*
X1208657Y424506D01*
X1208407Y424298D01*
X1207990Y424131D01*
X1207615Y424089D01*
X1207240Y424173D01*
X1206990Y424298D01*
X1206740Y424548D01*
X1206573Y424839D01*
X1206490Y425131D01*
Y425423D01*
X1206573Y425714D01*
X1206698Y425964D01*
X1206865Y426173D01*
G01X1208573Y427439D02*
X1208823Y427689D01*
X1208948Y427981D01*
X1208990Y428314D01*
X1208907Y428731D01*
X1208698Y429023D01*
X1208448Y429106D01*
X1208198Y429064D01*
X1207990Y428898D01*
X1207573Y428064D01*
X1207282Y427689D01*
X1206865Y427439D01*
X1206490Y427356D01*
Y429106D01*
G01Y430373D02*
X1208990D01*
X1206490Y432289D01*
X1208990D01*
G01X1206490Y434931D02*
X1208990D01*
X1207198Y433389D01*
Y435473D01*
G01X1201765Y425525D02*
X1201890Y425275D01*
X1201973Y424983D01*
Y424650D01*
X1201848Y424275D01*
X1201640Y423983D01*
X1201390Y423775D01*
X1200973Y423608D01*
X1200598Y423566D01*
X1200223Y423650D01*
X1199973Y423775D01*
X1199723Y424025D01*
X1199556Y424316D01*
X1199473Y424608D01*
Y424900D01*
X1199556Y425191D01*
X1199681Y425441D01*
X1199848Y425650D01*
G01X1199973Y426791D02*
X1199681Y427041D01*
X1199515Y427375D01*
X1199473Y427750D01*
X1199515Y428083D01*
X1199723Y428416D01*
X1199973Y428625D01*
X1200223Y428666D01*
X1200515Y428583D01*
X1200723Y428291D01*
X1200806Y428000D01*
Y427625D01*
G01Y428000D02*
X1200931Y428250D01*
X1201140Y428458D01*
X1201390Y428541D01*
X1201640Y428458D01*
X1201848Y428250D01*
X1201973Y427875D01*
X1201931Y427500D01*
X1201765Y427125D01*
G01X1199473Y429850D02*
X1201973D01*
X1199473Y431766D01*
X1201973D01*
G01X1199473Y434408D02*
X1201973D01*
X1200181Y432866D01*
Y434950D01*
G01X1214150Y413190D02*
X1214400Y413315D01*
X1214692Y413398D01*
X1215025D01*
X1215400Y413273D01*
X1215692Y413065D01*
X1215900Y412815D01*
X1216067Y412398D01*
X1216109Y412023D01*
X1216025Y411648D01*
X1215900Y411398D01*
X1215650Y411148D01*
X1215359Y410981D01*
X1215067Y410898D01*
X1214775D01*
X1214484Y410981D01*
X1214234Y411106D01*
X1214025Y411273D01*
G01X1212884Y411398D02*
X1212634Y411106D01*
X1212300Y410940D01*
X1211925Y410898D01*
X1211592Y410940D01*
X1211259Y411148D01*
X1211050Y411398D01*
X1211009Y411648D01*
X1211092Y411940D01*
X1211384Y412148D01*
X1211675Y412231D01*
X1212050D01*
G01X1211675D02*
X1211425Y412356D01*
X1211217Y412565D01*
X1211134Y412815D01*
X1211217Y413065D01*
X1211425Y413273D01*
X1211800Y413398D01*
X1212175Y413356D01*
X1212550Y413190D01*
G01X1209825Y410898D02*
Y413398D01*
X1207909Y410898D01*
Y413398D01*
G01X1205767Y410898D02*
Y413398D01*
X1206267Y412898D01*
G01Y410898D02*
X1205267D01*
G01X1202750D02*
X1202667Y411440D01*
X1202542Y411898D01*
X1202375Y412315D01*
X1202167Y412773D01*
X1201834Y413398D01*
X1203500D01*
G01X1214150Y417190D02*
X1214400Y417315D01*
X1214692Y417398D01*
X1215025D01*
X1215400Y417273D01*
X1215692Y417065D01*
X1215900Y416815D01*
X1216067Y416398D01*
X1216109Y416023D01*
X1216025Y415648D01*
X1215900Y415398D01*
X1215650Y415148D01*
X1215359Y414981D01*
X1215067Y414898D01*
X1214775D01*
X1214484Y414981D01*
X1214234Y415106D01*
X1214025Y415273D01*
G01X1212884Y415398D02*
X1212634Y415106D01*
X1212300Y414940D01*
X1211925Y414898D01*
X1211592Y414940D01*
X1211259Y415148D01*
X1211050Y415398D01*
X1211009Y415648D01*
X1211092Y415940D01*
X1211384Y416148D01*
X1211675Y416231D01*
X1212050D01*
G01X1211675D02*
X1211425Y416356D01*
X1211217Y416565D01*
X1211134Y416815D01*
X1211217Y417065D01*
X1211425Y417273D01*
X1211800Y417398D01*
X1212175Y417356D01*
X1212550Y417190D01*
G01X1209825Y414898D02*
Y417398D01*
X1207909Y414898D01*
Y417398D01*
G01X1205767Y414898D02*
Y417398D01*
X1206267Y416898D01*
G01Y414898D02*
X1205267D01*
G01X1203584Y415273D02*
X1203334Y415065D01*
X1203042Y414940D01*
X1202667Y414898D01*
X1202292Y414981D01*
X1202000Y415148D01*
X1201792Y415440D01*
X1201750Y415773D01*
X1201834Y416106D01*
X1202042Y416315D01*
X1202334Y416481D01*
X1202625Y416523D01*
X1202917Y416481D01*
X1203292Y416315D01*
X1203167Y417398D01*
X1202042D01*
G01X1214150Y409190D02*
X1214400Y409315D01*
X1214692Y409398D01*
X1215025D01*
X1215400Y409273D01*
X1215692Y409065D01*
X1215900Y408815D01*
X1216067Y408398D01*
X1216109Y408023D01*
X1216025Y407648D01*
X1215900Y407398D01*
X1215650Y407148D01*
X1215359Y406981D01*
X1215067Y406898D01*
X1214775D01*
X1214484Y406981D01*
X1214234Y407106D01*
X1214025Y407273D01*
G01X1212884Y407398D02*
X1212634Y407106D01*
X1212300Y406940D01*
X1211925Y406898D01*
X1211592Y406940D01*
X1211259Y407148D01*
X1211050Y407398D01*
X1211009Y407648D01*
X1211092Y407940D01*
X1211384Y408148D01*
X1211675Y408231D01*
X1212050D01*
G01X1211675D02*
X1211425Y408356D01*
X1211217Y408565D01*
X1211134Y408815D01*
X1211217Y409065D01*
X1211425Y409273D01*
X1211800Y409398D01*
X1212175Y409356D01*
X1212550Y409190D01*
G01X1209825Y406898D02*
Y409398D01*
X1207909Y406898D01*
Y409398D01*
G01X1205767Y406898D02*
Y409398D01*
X1206267Y408898D01*
G01Y406898D02*
X1205267D01*
G01X1202667D02*
X1202375Y406940D01*
X1202042Y407065D01*
X1201834Y407273D01*
X1201750Y407565D01*
X1201834Y407856D01*
X1202084Y408106D01*
X1202459Y408231D01*
X1202875D01*
X1203125Y408315D01*
X1203334Y408523D01*
X1203417Y408815D01*
X1203292Y409106D01*
X1203000Y409315D01*
X1202667Y409398D01*
X1202334Y409315D01*
X1202042Y409106D01*
X1201917Y408815D01*
X1202000Y408523D01*
X1202209Y408315D01*
X1202459Y408231D01*
X1202875D01*
X1203250Y408106D01*
X1203500Y407856D01*
X1203584Y407565D01*
X1203500Y407273D01*
X1203292Y407065D01*
X1202959Y406940D01*
X1202667Y406898D01*
G01X1185521Y434117D02*
X1185646Y433867D01*
X1185729Y433575D01*
Y433242D01*
X1185604Y432867D01*
X1185396Y432575D01*
X1185146Y432367D01*
X1184729Y432200D01*
X1184354Y432158D01*
X1183979Y432242D01*
X1183729Y432367D01*
X1183479Y432617D01*
X1183312Y432908D01*
X1183229Y433200D01*
Y433492D01*
X1183312Y433783D01*
X1183437Y434033D01*
X1183604Y434242D01*
G01X1183729Y435383D02*
X1183437Y435633D01*
X1183271Y435967D01*
X1183229Y436342D01*
X1183271Y436675D01*
X1183479Y437008D01*
X1183729Y437217D01*
X1183979Y437258D01*
X1184271Y437175D01*
X1184479Y436883D01*
X1184562Y436592D01*
Y436217D01*
G01Y436592D02*
X1184687Y436842D01*
X1184896Y437050D01*
X1185146Y437133D01*
X1185396Y437050D01*
X1185604Y436842D01*
X1185729Y436467D01*
X1185687Y436092D01*
X1185521Y435717D01*
G01X1183229Y438442D02*
X1185729D01*
X1183229Y440358D01*
X1185729D01*
G01X1185312Y441708D02*
X1185562Y441958D01*
X1185687Y442250D01*
X1185729Y442583D01*
X1185646Y443000D01*
X1185437Y443292D01*
X1185187Y443375D01*
X1184937Y443333D01*
X1184729Y443167D01*
X1184312Y442333D01*
X1184021Y441958D01*
X1183604Y441708D01*
X1183229Y441625D01*
Y443375D01*
G01X1181521Y434117D02*
X1181646Y433867D01*
X1181729Y433575D01*
Y433242D01*
X1181604Y432867D01*
X1181396Y432575D01*
X1181146Y432367D01*
X1180729Y432200D01*
X1180354Y432158D01*
X1179979Y432242D01*
X1179729Y432367D01*
X1179479Y432617D01*
X1179312Y432908D01*
X1179229Y433200D01*
Y433492D01*
X1179312Y433783D01*
X1179437Y434033D01*
X1179604Y434242D01*
G01X1179729Y435383D02*
X1179437Y435633D01*
X1179271Y435967D01*
X1179229Y436342D01*
X1179271Y436675D01*
X1179479Y437008D01*
X1179729Y437217D01*
X1179979Y437258D01*
X1180271Y437175D01*
X1180479Y436883D01*
X1180562Y436592D01*
Y436217D01*
G01Y436592D02*
X1180687Y436842D01*
X1180896Y437050D01*
X1181146Y437133D01*
X1181396Y437050D01*
X1181604Y436842D01*
X1181729Y436467D01*
X1181687Y436092D01*
X1181521Y435717D01*
G01X1179229Y438442D02*
X1181729D01*
X1179229Y440358D01*
X1181729D01*
G01X1179729Y441583D02*
X1179437Y441833D01*
X1179271Y442167D01*
X1179229Y442542D01*
X1179271Y442875D01*
X1179479Y443208D01*
X1179729Y443417D01*
X1179979Y443458D01*
X1180271Y443375D01*
X1180479Y443083D01*
X1180562Y442792D01*
Y442417D01*
G01Y442792D02*
X1180687Y443042D01*
X1180896Y443250D01*
X1181146Y443333D01*
X1181396Y443250D01*
X1181604Y443042D01*
X1181729Y442667D01*
X1181687Y442292D01*
X1181521Y441917D01*
G01X1188373Y416992D02*
X1188623Y417117D01*
X1188915Y417200D01*
X1189248D01*
X1189623Y417075D01*
X1189915Y416867D01*
X1190123Y416617D01*
X1190290Y416200D01*
X1190332Y415825D01*
X1190248Y415450D01*
X1190123Y415200D01*
X1189873Y414950D01*
X1189582Y414783D01*
X1189290Y414700D01*
X1188998D01*
X1188707Y414783D01*
X1188457Y414908D01*
X1188248Y415075D01*
G01X1187107Y415200D02*
X1186857Y414908D01*
X1186523Y414742D01*
X1186148Y414700D01*
X1185815Y414742D01*
X1185482Y414950D01*
X1185273Y415200D01*
X1185232Y415450D01*
X1185315Y415742D01*
X1185607Y415950D01*
X1185898Y416033D01*
X1186273D01*
G01X1185898D02*
X1185648Y416158D01*
X1185440Y416367D01*
X1185357Y416617D01*
X1185440Y416867D01*
X1185648Y417075D01*
X1186023Y417200D01*
X1186398Y417158D01*
X1186773Y416992D01*
G01X1184048Y414700D02*
Y417200D01*
X1182132Y414700D01*
Y417200D01*
G01X1179990Y414700D02*
Y417200D01*
X1180490Y416700D01*
G01Y414700D02*
X1179490D01*
G01X1177682Y415742D02*
X1177390Y416033D01*
X1177140Y416200D01*
X1176807Y416283D01*
X1176515Y416200D01*
X1176307Y416033D01*
X1176140Y415783D01*
X1176098Y415492D01*
X1176140Y415242D01*
X1176307Y414992D01*
X1176557Y414783D01*
X1176848Y414700D01*
X1177182Y414783D01*
X1177473Y415033D01*
X1177640Y415408D01*
X1177682Y415825D01*
X1177598Y416367D01*
X1177473Y416658D01*
X1177265Y416950D01*
X1176973Y417158D01*
X1176682Y417200D01*
X1176390Y417117D01*
X1176182Y416908D01*
G01X1183211Y429599D02*
X1183461Y429724D01*
X1183753Y429807D01*
X1184086D01*
X1184461Y429682D01*
X1184753Y429474D01*
X1184961Y429224D01*
X1185128Y428807D01*
X1185170Y428432D01*
X1185086Y428057D01*
X1184961Y427807D01*
X1184711Y427557D01*
X1184420Y427390D01*
X1184128Y427307D01*
X1183836D01*
X1183545Y427390D01*
X1183295Y427515D01*
X1183086Y427682D01*
G01X1181945Y427807D02*
X1181695Y427515D01*
X1181361Y427349D01*
X1180986Y427307D01*
X1180653Y427349D01*
X1180320Y427557D01*
X1180111Y427807D01*
X1180070Y428057D01*
X1180153Y428349D01*
X1180445Y428557D01*
X1180736Y428640D01*
X1181111D01*
G01X1180736D02*
X1180486Y428765D01*
X1180278Y428974D01*
X1180195Y429224D01*
X1180278Y429474D01*
X1180486Y429682D01*
X1180861Y429807D01*
X1181236Y429765D01*
X1181611Y429599D01*
G01X1178886Y427307D02*
Y429807D01*
X1176970Y427307D01*
Y429807D01*
G01X1174911Y427307D02*
X1174828Y427849D01*
X1174703Y428307D01*
X1174536Y428724D01*
X1174328Y429182D01*
X1173995Y429807D01*
X1175661D01*
G01X1216402Y421545D02*
X1216652Y421670D01*
X1216944Y421753D01*
X1217277D01*
X1217652Y421628D01*
X1217944Y421420D01*
X1218152Y421170D01*
X1218319Y420753D01*
X1218361Y420378D01*
X1218277Y420003D01*
X1218152Y419753D01*
X1217902Y419503D01*
X1217611Y419336D01*
X1217319Y419253D01*
X1217027D01*
X1216736Y419336D01*
X1216486Y419461D01*
X1216277Y419628D01*
G01X1215136Y419753D02*
X1214886Y419461D01*
X1214552Y419295D01*
X1214177Y419253D01*
X1213844Y419295D01*
X1213511Y419503D01*
X1213302Y419753D01*
X1213261Y420003D01*
X1213344Y420295D01*
X1213636Y420503D01*
X1213927Y420586D01*
X1214302D01*
G01X1213927D02*
X1213677Y420711D01*
X1213469Y420920D01*
X1213386Y421170D01*
X1213469Y421420D01*
X1213677Y421628D01*
X1214052Y421753D01*
X1214427Y421711D01*
X1214802Y421545D01*
G01X1212077Y419253D02*
Y421753D01*
X1210161Y419253D01*
Y421753D01*
G01X1208019Y419253D02*
Y421753D01*
X1208519Y421253D01*
G01Y419253D02*
X1207519D01*
G01X1204919Y421753D02*
X1205252Y421670D01*
X1205502Y421461D01*
X1205669Y421211D01*
X1205794Y420878D01*
X1205836Y420503D01*
X1205794Y420128D01*
X1205669Y419795D01*
X1205502Y419545D01*
X1205252Y419336D01*
X1204919Y419253D01*
X1204586Y419336D01*
X1204336Y419545D01*
X1204169Y419795D01*
X1204044Y420128D01*
X1204002Y420503D01*
X1204044Y420878D01*
X1204169Y421211D01*
X1204336Y421461D01*
X1204586Y421670D01*
X1204919Y421753D01*
G01X1198902Y421545D02*
X1199152Y421670D01*
X1199444Y421753D01*
X1199777D01*
X1200152Y421628D01*
X1200444Y421420D01*
X1200652Y421170D01*
X1200819Y420753D01*
X1200861Y420378D01*
X1200777Y420003D01*
X1200652Y419753D01*
X1200402Y419503D01*
X1200111Y419336D01*
X1199819Y419253D01*
X1199527D01*
X1199236Y419336D01*
X1198986Y419461D01*
X1198777Y419628D01*
G01X1197636Y419753D02*
X1197386Y419461D01*
X1197052Y419295D01*
X1196677Y419253D01*
X1196344Y419295D01*
X1196011Y419503D01*
X1195802Y419753D01*
X1195761Y420003D01*
X1195844Y420295D01*
X1196136Y420503D01*
X1196427Y420586D01*
X1196802D01*
G01X1196427D02*
X1196177Y420711D01*
X1195969Y420920D01*
X1195886Y421170D01*
X1195969Y421420D01*
X1196177Y421628D01*
X1196552Y421753D01*
X1196927Y421711D01*
X1197302Y421545D01*
G01X1194577Y419253D02*
Y421753D01*
X1192661Y419253D01*
Y421753D01*
G01X1190519Y419253D02*
Y421753D01*
X1191019Y421253D01*
G01Y419253D02*
X1190019D01*
G01X1187419D02*
Y421753D01*
X1187919Y421253D01*
G01Y419253D02*
X1186919D01*
G01X1178056Y469030D02*
X1223609D01*
Y462505D01*
X1232330D01*
Y447015D01*
X1249817D01*
Y397240D01*
G01X1226218Y534175D02*
X1226468Y534300D01*
X1226760Y534383D01*
X1227093D01*
X1227468Y534258D01*
X1227760Y534050D01*
X1227968Y533800D01*
X1228135Y533383D01*
X1228177Y533008D01*
X1228093Y532633D01*
X1227968Y532383D01*
X1227718Y532133D01*
X1227427Y531966D01*
X1227135Y531883D01*
X1226843D01*
X1226552Y531966D01*
X1226302Y532091D01*
X1226093Y532258D01*
G01X1223535Y531883D02*
Y534383D01*
X1225077Y532591D01*
X1222993D01*
G01X1222018Y531883D02*
Y534383D01*
X1220935Y532300D01*
X1219852Y534383D01*
Y531883D01*
G01X1217335D02*
Y534383D01*
X1218877Y532591D01*
X1216793D01*
G01X1226152Y572077D02*
X1226402Y572202D01*
X1226694Y572285D01*
X1227027D01*
X1227402Y572160D01*
X1227694Y571952D01*
X1227902Y571702D01*
X1228069Y571285D01*
X1228111Y570910D01*
X1228027Y570535D01*
X1227902Y570285D01*
X1227652Y570035D01*
X1227361Y569868D01*
X1227069Y569785D01*
X1226777D01*
X1226486Y569868D01*
X1226236Y569993D01*
X1226027Y570160D01*
G01X1223469Y569785D02*
Y572285D01*
X1225011Y570493D01*
X1222927D01*
G01X1221702Y572285D02*
Y569785D01*
X1220036D01*
G01X1217269D02*
Y572285D01*
X1218811Y570493D01*
X1216727D01*
G01X1229741Y658648D02*
X1197041D01*
Y639948D01*
X1229741D01*
Y658648D01*
G01X1285800Y-55300D02*
Y-58300D01*
X1283800D01*
G01X1281200D02*
Y-55300D01*
X1281800Y-55900D01*
G01Y-58300D02*
X1280600D01*
G01X1278550Y-55800D02*
X1278250Y-55500D01*
X1277900Y-55350D01*
X1277500Y-55300D01*
X1277000Y-55400D01*
X1276650Y-55650D01*
X1276550Y-55950D01*
X1276600Y-56250D01*
X1276800Y-56500D01*
X1277800Y-57000D01*
X1278250Y-57350D01*
X1278550Y-57850D01*
X1278650Y-58300D01*
X1276550D01*
G01X1271400Y-55300D02*
Y-58300D01*
X1269400D01*
G01X1266800D02*
Y-55300D01*
X1267400Y-55900D01*
G01Y-58300D02*
X1266200D01*
G01X1264700Y-59300D02*
X1261700D01*
G01X1260450Y-57950D02*
X1260100Y-58200D01*
X1259700Y-58300D01*
X1259300Y-58200D01*
X1258950Y-57900D01*
X1258700Y-57450D01*
X1258600Y-57000D01*
Y-56450D01*
X1258700Y-56000D01*
X1258950Y-55600D01*
X1259250Y-55400D01*
X1259600Y-55300D01*
X1260000Y-55400D01*
X1260300Y-55600D01*
X1260500Y-55900D01*
X1260600Y-56300D01*
X1260500Y-56650D01*
X1260250Y-57000D01*
X1259950Y-57200D01*
X1259600Y-57250D01*
X1259200Y-57150D01*
X1258900Y-56900D01*
X1258600Y-56450D01*
G01X1257100Y-57850D02*
X1256800Y-58100D01*
X1256450Y-58250D01*
X1256000Y-58300D01*
X1255550Y-58200D01*
X1255200Y-58000D01*
X1254950Y-57650D01*
X1254900Y-57250D01*
X1255000Y-56850D01*
X1255250Y-56600D01*
X1255600Y-56400D01*
X1255950Y-56350D01*
X1256300Y-56400D01*
X1256750Y-56600D01*
X1256600Y-55300D01*
X1255250D01*
G01X1252400Y-58300D02*
X1252800Y-58250D01*
X1253150Y-58050D01*
X1253450Y-57750D01*
X1253650Y-57400D01*
X1253750Y-57000D01*
Y-56600D01*
X1253650Y-56200D01*
X1253450Y-55850D01*
X1253150Y-55550D01*
X1252800Y-55350D01*
X1252400Y-55300D01*
X1252000Y-55350D01*
X1251650Y-55550D01*
X1251350Y-55850D01*
X1251150Y-56200D01*
X1251050Y-56600D01*
Y-57000D01*
X1251150Y-57400D01*
X1251350Y-57750D01*
X1251650Y-58050D01*
X1252000Y-58250D01*
X1252400Y-58300D01*
G01X1249650D02*
Y-55300D01*
G01Y-56750D02*
X1249400Y-56500D01*
X1249150Y-56350D01*
X1248750Y-56300D01*
X1248450Y-56350D01*
X1248100Y-56550D01*
X1247950Y-56850D01*
Y-58300D01*
G01X1246700D02*
Y-56300D01*
G01Y-56850D02*
X1246550Y-56600D01*
X1246300Y-56400D01*
X1245950Y-56300D01*
X1245600Y-56400D01*
X1245350Y-56600D01*
X1245200Y-56850D01*
Y-58300D01*
G01Y-56850D02*
X1245050Y-56600D01*
X1244800Y-56400D01*
X1244450Y-56300D01*
X1244100Y-56400D01*
X1243850Y-56600D01*
X1243700Y-56900D01*
Y-58300D01*
G01X1243100Y-59300D02*
X1240100D01*
G01X1239100Y-58300D02*
Y-55300D01*
X1238100D01*
X1237700Y-55450D01*
X1237400Y-55650D01*
X1237150Y-55950D01*
X1236950Y-56300D01*
X1236900Y-56800D01*
X1236950Y-57300D01*
X1237150Y-57650D01*
X1237400Y-57950D01*
X1237700Y-58150D01*
X1238100Y-58300D01*
X1239100D01*
G01X1254191Y-11708D02*
X1254441Y-11583D01*
X1254733Y-11500D01*
X1255066D01*
X1255441Y-11625D01*
X1255733Y-11833D01*
X1255941Y-12083D01*
X1256108Y-12500D01*
X1256150Y-12875D01*
X1256066Y-13250D01*
X1255941Y-13500D01*
X1255691Y-13750D01*
X1255400Y-13917D01*
X1255108Y-14000D01*
X1254816D01*
X1254525Y-13917D01*
X1254275Y-13792D01*
X1254066Y-13625D01*
G01X1251508Y-14000D02*
Y-11500D01*
X1253050Y-13292D01*
X1250966D01*
G01X1249825Y-11500D02*
Y-13292D01*
X1249658Y-13667D01*
X1249325Y-13917D01*
X1248908Y-14000D01*
X1248491Y-13917D01*
X1248158Y-13667D01*
X1247991Y-13292D01*
Y-11500D01*
G01X1245308Y-14000D02*
Y-11500D01*
X1246850Y-13292D01*
X1244766D01*
G01X1268191Y-11408D02*
X1268441Y-11283D01*
X1268733Y-11200D01*
X1269066D01*
X1269441Y-11325D01*
X1269733Y-11533D01*
X1269941Y-11783D01*
X1270108Y-12200D01*
X1270150Y-12575D01*
X1270066Y-12950D01*
X1269941Y-13200D01*
X1269691Y-13450D01*
X1269400Y-13617D01*
X1269108Y-13700D01*
X1268816D01*
X1268525Y-13617D01*
X1268275Y-13492D01*
X1268066Y-13325D01*
G01X1265508Y-13700D02*
Y-11200D01*
X1267050Y-12992D01*
X1264966D01*
G01X1263825Y-11200D02*
Y-12992D01*
X1263658Y-13367D01*
X1263325Y-13617D01*
X1262908Y-13700D01*
X1262491Y-13617D01*
X1262158Y-13367D01*
X1261991Y-12992D01*
Y-11200D01*
G01X1260725Y-13200D02*
X1260475Y-13492D01*
X1260141Y-13658D01*
X1259766Y-13700D01*
X1259433Y-13658D01*
X1259100Y-13450D01*
X1258891Y-13200D01*
X1258850Y-12950D01*
X1258933Y-12658D01*
X1259225Y-12450D01*
X1259516Y-12367D01*
X1259891D01*
G01X1259516D02*
X1259266Y-12242D01*
X1259058Y-12033D01*
X1258975Y-11783D01*
X1259058Y-11533D01*
X1259266Y-11325D01*
X1259641Y-11200D01*
X1260016Y-11242D01*
X1260391Y-11408D01*
G01X1230148Y34069D02*
X1230398Y34194D01*
X1230690Y34277D01*
X1231023D01*
X1231398Y34152D01*
X1231690Y33944D01*
X1231898Y33694D01*
X1232065Y33277D01*
X1232107Y32902D01*
X1232023Y32527D01*
X1231898Y32277D01*
X1231648Y32027D01*
X1231357Y31860D01*
X1231065Y31777D01*
X1230773D01*
X1230482Y31860D01*
X1230232Y31985D01*
X1230023Y32152D01*
G01X1227465Y31777D02*
Y34277D01*
X1229007Y32485D01*
X1226923D01*
G01X1225782Y34277D02*
Y32485D01*
X1225615Y32110D01*
X1225282Y31860D01*
X1224865Y31777D01*
X1224448Y31860D01*
X1224115Y32110D01*
X1223948Y32485D01*
Y34277D01*
G01X1221765Y31777D02*
Y34277D01*
X1222265Y33777D01*
G01Y31777D02*
X1221265D01*
G01X1275852Y33500D02*
Y36600D01*
X1276312Y35980D01*
G01Y33500D02*
X1275392D01*
G01X1272292D02*
Y36600D01*
X1273710Y34378D01*
X1271794D01*
G01X1269192Y33500D02*
Y36600D01*
X1270610Y34378D01*
X1268694D01*
G01X1277080Y-1417D02*
X1276850Y-1107D01*
X1276582Y-952D01*
X1276275Y-900D01*
X1275892Y-1003D01*
X1275624Y-1262D01*
X1275547Y-1572D01*
X1275585Y-1882D01*
X1275739Y-2140D01*
X1276505Y-2657D01*
X1276850Y-3018D01*
X1277080Y-3535D01*
X1277157Y-4000D01*
X1275547D01*
G01X1273252D02*
X1272984Y-3948D01*
X1272677Y-3793D01*
X1272485Y-3535D01*
X1272409Y-3173D01*
X1272485Y-2812D01*
X1272715Y-2502D01*
X1273060Y-2347D01*
X1273444D01*
X1273674Y-2243D01*
X1273865Y-1985D01*
X1273942Y-1623D01*
X1273827Y-1262D01*
X1273559Y-1003D01*
X1273252Y-900D01*
X1272945Y-1003D01*
X1272677Y-1262D01*
X1272562Y-1623D01*
X1272639Y-1985D01*
X1272830Y-2243D01*
X1273060Y-2347D01*
X1273444D01*
X1273789Y-2502D01*
X1274019Y-2812D01*
X1274095Y-3173D01*
X1274019Y-3535D01*
X1273827Y-3793D01*
X1273520Y-3948D01*
X1273252Y-4000D01*
G01X1270152D02*
X1269884Y-3948D01*
X1269577Y-3793D01*
X1269385Y-3535D01*
X1269309Y-3173D01*
X1269385Y-2812D01*
X1269615Y-2502D01*
X1269960Y-2347D01*
X1270344D01*
X1270574Y-2243D01*
X1270765Y-1985D01*
X1270842Y-1623D01*
X1270727Y-1262D01*
X1270459Y-1003D01*
X1270152Y-900D01*
X1269845Y-1003D01*
X1269577Y-1262D01*
X1269462Y-1623D01*
X1269539Y-1985D01*
X1269730Y-2243D01*
X1269960Y-2347D01*
X1270344D01*
X1270689Y-2502D01*
X1270919Y-2812D01*
X1270995Y-3173D01*
X1270919Y-3535D01*
X1270727Y-3793D01*
X1270420Y-3948D01*
X1270152Y-4000D01*
G01X1270986Y283D02*
X1295376D01*
Y25873D01*
X1270986D01*
G01X1276580Y29583D02*
X1276350Y29893D01*
X1276082Y30048D01*
X1275775Y30100D01*
X1275392Y29997D01*
X1275124Y29738D01*
X1275047Y29428D01*
X1275085Y29118D01*
X1275239Y28860D01*
X1276005Y28343D01*
X1276350Y27982D01*
X1276580Y27465D01*
X1276657Y27000D01*
X1275047D01*
G01X1272752D02*
X1272484Y27052D01*
X1272177Y27207D01*
X1271985Y27465D01*
X1271909Y27827D01*
X1271985Y28188D01*
X1272215Y28498D01*
X1272560Y28653D01*
X1272944D01*
X1273174Y28757D01*
X1273365Y29015D01*
X1273442Y29377D01*
X1273327Y29738D01*
X1273059Y29997D01*
X1272752Y30100D01*
X1272445Y29997D01*
X1272177Y29738D01*
X1272062Y29377D01*
X1272139Y29015D01*
X1272330Y28757D01*
X1272560Y28653D01*
X1272944D01*
X1273289Y28498D01*
X1273519Y28188D01*
X1273595Y27827D01*
X1273519Y27465D01*
X1273327Y27207D01*
X1273020Y27052D01*
X1272752Y27000D01*
G01X1269652D02*
X1269384Y27052D01*
X1269077Y27207D01*
X1268885Y27465D01*
X1268809Y27827D01*
X1268885Y28188D01*
X1269115Y28498D01*
X1269460Y28653D01*
X1269844D01*
X1270074Y28757D01*
X1270265Y29015D01*
X1270342Y29377D01*
X1270227Y29738D01*
X1269959Y29997D01*
X1269652Y30100D01*
X1269345Y29997D01*
X1269077Y29738D01*
X1268962Y29377D01*
X1269039Y29015D01*
X1269230Y28757D01*
X1269460Y28653D01*
X1269844D01*
X1270189Y28498D01*
X1270419Y28188D01*
X1270495Y27827D01*
X1270419Y27465D01*
X1270227Y27207D01*
X1269920Y27052D01*
X1269652Y27000D01*
G01X1236858Y70704D02*
X1237108Y70829D01*
X1237400Y70912D01*
X1237733D01*
X1238108Y70787D01*
X1238400Y70579D01*
X1238608Y70329D01*
X1238775Y69912D01*
X1238817Y69537D01*
X1238733Y69162D01*
X1238608Y68912D01*
X1238358Y68662D01*
X1238067Y68495D01*
X1237775Y68412D01*
X1237483D01*
X1237192Y68495D01*
X1236942Y68620D01*
X1236733Y68787D01*
G01X1234175Y68412D02*
Y70912D01*
X1235717Y69120D01*
X1233633D01*
G01X1231575Y70912D02*
Y68412D01*
G01X1232533Y70912D02*
X1230617D01*
G01X1229392Y68787D02*
X1229142Y68579D01*
X1228850Y68454D01*
X1228475Y68412D01*
X1228100Y68495D01*
X1227808Y68662D01*
X1227600Y68954D01*
X1227558Y69287D01*
X1227642Y69620D01*
X1227850Y69829D01*
X1228142Y69995D01*
X1228433Y70037D01*
X1228725Y69995D01*
X1229100Y69829D01*
X1228975Y70912D01*
X1227850D01*
G01X1276580Y67583D02*
X1276350Y67893D01*
X1276082Y68048D01*
X1275775Y68100D01*
X1275392Y67997D01*
X1275124Y67738D01*
X1275047Y67428D01*
X1275085Y67118D01*
X1275239Y66860D01*
X1276005Y66343D01*
X1276350Y65982D01*
X1276580Y65465D01*
X1276657Y65000D01*
X1275047D01*
G01X1272752D02*
X1272484Y65052D01*
X1272177Y65207D01*
X1271985Y65465D01*
X1271909Y65827D01*
X1271985Y66188D01*
X1272215Y66498D01*
X1272560Y66653D01*
X1272944D01*
X1273174Y66757D01*
X1273365Y67015D01*
X1273442Y67377D01*
X1273327Y67738D01*
X1273059Y67997D01*
X1272752Y68100D01*
X1272445Y67997D01*
X1272177Y67738D01*
X1272062Y67377D01*
X1272139Y67015D01*
X1272330Y66757D01*
X1272560Y66653D01*
X1272944D01*
X1273289Y66498D01*
X1273519Y66188D01*
X1273595Y65827D01*
X1273519Y65465D01*
X1273327Y65207D01*
X1273020Y65052D01*
X1272752Y65000D01*
G01X1269652D02*
X1269384Y65052D01*
X1269077Y65207D01*
X1268885Y65465D01*
X1268809Y65827D01*
X1268885Y66188D01*
X1269115Y66498D01*
X1269460Y66653D01*
X1269844D01*
X1270074Y66757D01*
X1270265Y67015D01*
X1270342Y67377D01*
X1270227Y67738D01*
X1269959Y67997D01*
X1269652Y68100D01*
X1269345Y67997D01*
X1269077Y67738D01*
X1268962Y67377D01*
X1269039Y67015D01*
X1269230Y66757D01*
X1269460Y66653D01*
X1269844D01*
X1270189Y66498D01*
X1270419Y66188D01*
X1270495Y65827D01*
X1270419Y65465D01*
X1270227Y65207D01*
X1269920Y65052D01*
X1269652Y65000D01*
G01X1270986Y75883D02*
X1295376D01*
Y101473D01*
X1270986D01*
G01X1275852Y72000D02*
Y75100D01*
X1276312Y74480D01*
G01Y72000D02*
X1275392D01*
G01X1272292D02*
Y75100D01*
X1273710Y72878D01*
X1271794D01*
G01X1269192Y72000D02*
Y75100D01*
X1270610Y72878D01*
X1268694D01*
G01X1270986Y38083D02*
X1295376D01*
Y63673D01*
X1270986D01*
G01X1223900Y116267D02*
X1226400D01*
Y117308D01*
X1226275Y117642D01*
X1226108Y117850D01*
X1225775Y117933D01*
X1225442Y117850D01*
X1225233Y117600D01*
X1225108Y117308D01*
Y116267D01*
G01Y117308D02*
X1223900Y117933D01*
G01Y120200D02*
X1223942Y120492D01*
X1224067Y120825D01*
X1224275Y121033D01*
X1224567Y121117D01*
X1224858Y121033D01*
X1225108Y120783D01*
X1225233Y120408D01*
Y119992D01*
X1225317Y119742D01*
X1225525Y119533D01*
X1225817Y119450D01*
X1226108Y119575D01*
X1226317Y119867D01*
X1226400Y120200D01*
X1226317Y120533D01*
X1226108Y120825D01*
X1225817Y120950D01*
X1225525Y120867D01*
X1225317Y120658D01*
X1225233Y120408D01*
Y119992D01*
X1225108Y119617D01*
X1224858Y119367D01*
X1224567Y119283D01*
X1224275Y119367D01*
X1224067Y119575D01*
X1223942Y119908D01*
X1223900Y120200D01*
G01Y122383D02*
X1226400D01*
Y123217D01*
X1226275Y123550D01*
X1226108Y123800D01*
X1225858Y124008D01*
X1225567Y124175D01*
X1225150Y124217D01*
X1224733Y124175D01*
X1224442Y124008D01*
X1224192Y123800D01*
X1224025Y123550D01*
X1223900Y123217D01*
Y122383D01*
G01X1225983Y125608D02*
X1226233Y125858D01*
X1226358Y126150D01*
X1226400Y126483D01*
X1226317Y126900D01*
X1226108Y127192D01*
X1225858Y127275D01*
X1225608Y127233D01*
X1225400Y127067D01*
X1224983Y126233D01*
X1224692Y125858D01*
X1224275Y125608D01*
X1223900Y125525D01*
Y127275D01*
G01X1224192Y128792D02*
X1223983Y129083D01*
X1223900Y129417D01*
X1223983Y129750D01*
X1224233Y130042D01*
X1224608Y130250D01*
X1224983Y130333D01*
X1225442D01*
X1225817Y130250D01*
X1226150Y130042D01*
X1226317Y129792D01*
X1226400Y129500D01*
X1226317Y129167D01*
X1226150Y128917D01*
X1225900Y128750D01*
X1225567Y128667D01*
X1225275Y128750D01*
X1224983Y128958D01*
X1224817Y129208D01*
X1224775Y129500D01*
X1224858Y129833D01*
X1225067Y130083D01*
X1225442Y130333D01*
G01X1227900Y131267D02*
X1230400D01*
Y132308D01*
X1230275Y132642D01*
X1230108Y132850D01*
X1229775Y132933D01*
X1229442Y132850D01*
X1229233Y132600D01*
X1229108Y132308D01*
Y131267D01*
G01Y132308D02*
X1227900Y132933D01*
G01Y135200D02*
X1227942Y135492D01*
X1228067Y135825D01*
X1228275Y136033D01*
X1228567Y136117D01*
X1228858Y136033D01*
X1229108Y135783D01*
X1229233Y135408D01*
Y134992D01*
X1229317Y134742D01*
X1229525Y134533D01*
X1229817Y134450D01*
X1230108Y134575D01*
X1230317Y134867D01*
X1230400Y135200D01*
X1230317Y135533D01*
X1230108Y135825D01*
X1229817Y135950D01*
X1229525Y135867D01*
X1229317Y135658D01*
X1229233Y135408D01*
Y134992D01*
X1229108Y134617D01*
X1228858Y134367D01*
X1228567Y134283D01*
X1228275Y134367D01*
X1228067Y134575D01*
X1227942Y134908D01*
X1227900Y135200D01*
G01Y137383D02*
X1230400D01*
Y138217D01*
X1230275Y138550D01*
X1230108Y138800D01*
X1229858Y139008D01*
X1229567Y139175D01*
X1229150Y139217D01*
X1228733Y139175D01*
X1228442Y139008D01*
X1228192Y138800D01*
X1228025Y138550D01*
X1227900Y138217D01*
Y137383D01*
G01X1228400Y140483D02*
X1228108Y140733D01*
X1227942Y141067D01*
X1227900Y141442D01*
X1227942Y141775D01*
X1228150Y142108D01*
X1228400Y142317D01*
X1228650Y142358D01*
X1228942Y142275D01*
X1229150Y141983D01*
X1229233Y141692D01*
Y141317D01*
G01Y141692D02*
X1229358Y141942D01*
X1229567Y142150D01*
X1229817Y142233D01*
X1230067Y142150D01*
X1230275Y141942D01*
X1230400Y141567D01*
X1230358Y141192D01*
X1230192Y140817D01*
G01X1230400Y144500D02*
X1230317Y144167D01*
X1230108Y143917D01*
X1229858Y143750D01*
X1229525Y143625D01*
X1229150Y143583D01*
X1228775Y143625D01*
X1228442Y143750D01*
X1228192Y143917D01*
X1227983Y144167D01*
X1227900Y144500D01*
X1227983Y144833D01*
X1228192Y145083D01*
X1228442Y145250D01*
X1228775Y145375D01*
X1229150Y145417D01*
X1229525Y145375D01*
X1229858Y145250D01*
X1230108Y145083D01*
X1230317Y144833D01*
X1230400Y144500D01*
G01X1273231Y113255D02*
Y115755D01*
X1272190D01*
X1271856Y115630D01*
X1271648Y115463D01*
X1271565Y115130D01*
X1271648Y114797D01*
X1271898Y114588D01*
X1272190Y114463D01*
X1273231D01*
G01X1272190D02*
X1271565Y113255D01*
G01X1268798D02*
Y115755D01*
X1270340Y113963D01*
X1268256D01*
G01X1266198Y115755D02*
Y113255D01*
G01X1267156Y115755D02*
X1265240D01*
G01X1263181Y113255D02*
X1263098Y113797D01*
X1262973Y114255D01*
X1262806Y114672D01*
X1262598Y115130D01*
X1262265Y115755D01*
X1263931D01*
G01X1284320Y135420D02*
Y137920D01*
X1283279D01*
X1282945Y137795D01*
X1282737Y137628D01*
X1282654Y137295D01*
X1282737Y136962D01*
X1282987Y136753D01*
X1283279Y136628D01*
X1284320D01*
G01X1283279D02*
X1282654Y135420D01*
G01X1279887D02*
Y137920D01*
X1281429Y136128D01*
X1279345D01*
G01X1277287Y137920D02*
Y135420D01*
G01X1278245Y137920D02*
X1276329D01*
G01X1275104Y135795D02*
X1274854Y135587D01*
X1274562Y135462D01*
X1274187Y135420D01*
X1273812Y135503D01*
X1273520Y135670D01*
X1273312Y135962D01*
X1273270Y136295D01*
X1273354Y136628D01*
X1273562Y136837D01*
X1273854Y137003D01*
X1274145Y137045D01*
X1274437Y137003D01*
X1274812Y136837D01*
X1274687Y137920D01*
X1273562D01*
G01X1284442Y139980D02*
Y142480D01*
X1283401D01*
X1283067Y142355D01*
X1282859Y142188D01*
X1282776Y141855D01*
X1282859Y141522D01*
X1283109Y141313D01*
X1283401Y141188D01*
X1284442D01*
G01X1283401D02*
X1282776Y139980D01*
G01X1280009D02*
Y142480D01*
X1281551Y140688D01*
X1279467D01*
G01X1277409Y142480D02*
Y139980D01*
G01X1278367Y142480D02*
X1276451D01*
G01X1275226Y140480D02*
X1274976Y140188D01*
X1274642Y140022D01*
X1274267Y139980D01*
X1273934Y140022D01*
X1273601Y140230D01*
X1273392Y140480D01*
X1273351Y140730D01*
X1273434Y141022D01*
X1273726Y141230D01*
X1274017Y141313D01*
X1274392D01*
G01X1274017D02*
X1273767Y141438D01*
X1273559Y141647D01*
X1273476Y141897D01*
X1273559Y142147D01*
X1273767Y142355D01*
X1274142Y142480D01*
X1274517Y142438D01*
X1274892Y142272D01*
G01X1278382Y112106D02*
X1280882D01*
Y113147D01*
X1280757Y113481D01*
X1280590Y113689D01*
X1280257Y113772D01*
X1279924Y113689D01*
X1279715Y113439D01*
X1279590Y113147D01*
Y112106D01*
G01Y113147D02*
X1278382Y113772D01*
G01X1278882Y115122D02*
X1278590Y115372D01*
X1278424Y115706D01*
X1278382Y116081D01*
X1278424Y116414D01*
X1278632Y116747D01*
X1278882Y116956D01*
X1279132Y116997D01*
X1279424Y116914D01*
X1279632Y116622D01*
X1279715Y116331D01*
Y115956D01*
G01Y116331D02*
X1279840Y116581D01*
X1280049Y116789D01*
X1280299Y116872D01*
X1280549Y116789D01*
X1280757Y116581D01*
X1280882Y116206D01*
X1280840Y115831D01*
X1280674Y115456D01*
G01X1278382Y118306D02*
X1280882D01*
Y119347D01*
X1280757Y119681D01*
X1280590Y119889D01*
X1280257Y119972D01*
X1279924Y119889D01*
X1279715Y119639D01*
X1279590Y119347D01*
Y118306D01*
G01Y119347D02*
X1278382Y119972D01*
G01Y122239D02*
X1280882D01*
X1280382Y121739D01*
G01X1278382D02*
Y122739D01*
G01X1279424Y124547D02*
X1279715Y124839D01*
X1279882Y125089D01*
X1279965Y125422D01*
X1279882Y125714D01*
X1279715Y125922D01*
X1279465Y126089D01*
X1279174Y126131D01*
X1278924Y126089D01*
X1278674Y125922D01*
X1278465Y125672D01*
X1278382Y125381D01*
X1278465Y125047D01*
X1278715Y124756D01*
X1279090Y124589D01*
X1279507Y124547D01*
X1280049Y124631D01*
X1280340Y124756D01*
X1280632Y124964D01*
X1280840Y125256D01*
X1280882Y125547D01*
X1280799Y125839D01*
X1280590Y126047D01*
G01X1266583Y103500D02*
Y106000D01*
X1265542D01*
X1265208Y105875D01*
X1265000Y105708D01*
X1264917Y105375D01*
X1265000Y105042D01*
X1265250Y104833D01*
X1265542Y104708D01*
X1266583D01*
G01X1265542D02*
X1264917Y103500D01*
G01X1262150D02*
Y106000D01*
X1263692Y104208D01*
X1261608D01*
G01X1259550Y106000D02*
Y103500D01*
G01X1260508Y106000D02*
X1258592D01*
G01X1257158Y103792D02*
X1256867Y103583D01*
X1256533Y103500D01*
X1256200Y103583D01*
X1255908Y103833D01*
X1255700Y104208D01*
X1255617Y104583D01*
Y105042D01*
X1255700Y105417D01*
X1255908Y105750D01*
X1256158Y105917D01*
X1256450Y106000D01*
X1256783Y105917D01*
X1257033Y105750D01*
X1257200Y105500D01*
X1257283Y105167D01*
X1257200Y104875D01*
X1256992Y104583D01*
X1256742Y104417D01*
X1256450Y104375D01*
X1256117Y104458D01*
X1255867Y104667D01*
X1255617Y105042D01*
G01X1260933Y108628D02*
Y111128D01*
X1259892D01*
X1259558Y111003D01*
X1259350Y110836D01*
X1259267Y110503D01*
X1259350Y110170D01*
X1259600Y109961D01*
X1259892Y109836D01*
X1260933D01*
G01X1259892D02*
X1259267Y108628D01*
G01X1256500D02*
Y111128D01*
X1258042Y109336D01*
X1255958D01*
G01X1253900Y111128D02*
Y108628D01*
G01X1254858Y111128D02*
X1252942D01*
G01X1250800Y108628D02*
Y111128D01*
X1251300Y110628D01*
G01Y108628D02*
X1250300D01*
G01X1247700Y111128D02*
X1248033Y111045D01*
X1248283Y110836D01*
X1248450Y110586D01*
X1248575Y110253D01*
X1248617Y109878D01*
X1248575Y109503D01*
X1248450Y109170D01*
X1248283Y108920D01*
X1248033Y108711D01*
X1247700Y108628D01*
X1247367Y108711D01*
X1247117Y108920D01*
X1246950Y109170D01*
X1246825Y109503D01*
X1246783Y109878D01*
X1246825Y110253D01*
X1246950Y110586D01*
X1247117Y110836D01*
X1247367Y111045D01*
X1247700Y111128D01*
G01X1276324Y143454D02*
Y145954D01*
X1275283D01*
X1274949Y145829D01*
X1274741Y145662D01*
X1274658Y145329D01*
X1274741Y144996D01*
X1274991Y144787D01*
X1275283Y144662D01*
X1276324D01*
G01X1275283D02*
X1274658Y143454D01*
G01X1271891D02*
Y145954D01*
X1273433Y144162D01*
X1271349D01*
G01X1269291Y145954D02*
Y143454D01*
G01X1270249Y145954D02*
X1268333D01*
G01X1265691Y143454D02*
Y145954D01*
X1267233Y144162D01*
X1265149D01*
G01X1276489Y131770D02*
Y134270D01*
X1275448D01*
X1275114Y134145D01*
X1274906Y133978D01*
X1274823Y133645D01*
X1274906Y133312D01*
X1275156Y133103D01*
X1275448Y132978D01*
X1276489D01*
G01X1275448D02*
X1274823Y131770D01*
G01X1272056D02*
Y134270D01*
X1273598Y132478D01*
X1271514D01*
G01X1269456Y134270D02*
Y131770D01*
G01X1270414Y134270D02*
X1268498D01*
G01X1267148Y132812D02*
X1266856Y133103D01*
X1266606Y133270D01*
X1266273Y133353D01*
X1265981Y133270D01*
X1265773Y133103D01*
X1265606Y132853D01*
X1265564Y132562D01*
X1265606Y132312D01*
X1265773Y132062D01*
X1266023Y131853D01*
X1266314Y131770D01*
X1266648Y131853D01*
X1266939Y132103D01*
X1267106Y132478D01*
X1267148Y132895D01*
X1267064Y133437D01*
X1266939Y133728D01*
X1266731Y134020D01*
X1266439Y134228D01*
X1266148Y134270D01*
X1265856Y134187D01*
X1265648Y133978D01*
G01X1270478Y118860D02*
Y121360D01*
X1269437D01*
X1269103Y121235D01*
X1268895Y121068D01*
X1268812Y120735D01*
X1268895Y120402D01*
X1269145Y120193D01*
X1269437Y120068D01*
X1270478D01*
G01X1269437D02*
X1268812Y118860D01*
G01X1266045D02*
Y121360D01*
X1267587Y119568D01*
X1265503D01*
G01X1263445Y121360D02*
Y118860D01*
G01X1264403Y121360D02*
X1262487D01*
G01X1260345Y118860D02*
X1260053Y118902D01*
X1259720Y119027D01*
X1259512Y119235D01*
X1259428Y119527D01*
X1259512Y119818D01*
X1259762Y120068D01*
X1260137Y120193D01*
X1260553D01*
X1260803Y120277D01*
X1261012Y120485D01*
X1261095Y120777D01*
X1260970Y121068D01*
X1260678Y121277D01*
X1260345Y121360D01*
X1260012Y121277D01*
X1259720Y121068D01*
X1259595Y120777D01*
X1259678Y120485D01*
X1259887Y120277D01*
X1260137Y120193D01*
X1260553D01*
X1260928Y120068D01*
X1261178Y119818D01*
X1261262Y119527D01*
X1261178Y119235D01*
X1260970Y119027D01*
X1260637Y118902D01*
X1260345Y118860D01*
G01X1246956Y131747D02*
Y134247D01*
X1245915D01*
X1245581Y134122D01*
X1245373Y133955D01*
X1245290Y133622D01*
X1245373Y133289D01*
X1245623Y133080D01*
X1245915Y132955D01*
X1246956D01*
G01X1245915D02*
X1245290Y131747D01*
G01X1242523D02*
Y134247D01*
X1244065Y132455D01*
X1241981D01*
G01X1239923Y134247D02*
Y131747D01*
G01X1240881Y134247D02*
X1238965D01*
G01X1237615Y133830D02*
X1237365Y134080D01*
X1237073Y134205D01*
X1236740Y134247D01*
X1236323Y134164D01*
X1236031Y133955D01*
X1235948Y133705D01*
X1235990Y133455D01*
X1236156Y133247D01*
X1236990Y132830D01*
X1237365Y132539D01*
X1237615Y132122D01*
X1237698Y131747D01*
X1235948D01*
G01X1249863Y136045D02*
Y138545D01*
X1248822D01*
X1248488Y138420D01*
X1248280Y138253D01*
X1248197Y137920D01*
X1248280Y137587D01*
X1248530Y137378D01*
X1248822Y137253D01*
X1249863D01*
G01X1248822D02*
X1248197Y136045D01*
G01X1245430D02*
Y138545D01*
X1246972Y136753D01*
X1244888D01*
G01X1242830Y138545D02*
Y136045D01*
G01X1243788Y138545D02*
X1241872D01*
G01X1239730Y136045D02*
Y138545D01*
X1240230Y138045D01*
G01Y136045D02*
X1239230D01*
G01X1234500Y131400D02*
X1232000Y131983D01*
X1234500Y132650D01*
X1232000Y133317D01*
X1234500Y133900D01*
G01X1232000Y134917D02*
X1234500D01*
Y135958D01*
X1234375Y136292D01*
X1234208Y136500D01*
X1233875Y136583D01*
X1233542Y136500D01*
X1233333Y136250D01*
X1233208Y135958D01*
Y134917D01*
G01Y135958D02*
X1232000Y136583D01*
G01Y138850D02*
X1232042Y139142D01*
X1232167Y139475D01*
X1232375Y139683D01*
X1232667Y139767D01*
X1232958Y139683D01*
X1233208Y139433D01*
X1233333Y139058D01*
Y138642D01*
X1233417Y138392D01*
X1233625Y138183D01*
X1233917Y138100D01*
X1234208Y138225D01*
X1234417Y138517D01*
X1234500Y138850D01*
X1234417Y139183D01*
X1234208Y139475D01*
X1233917Y139600D01*
X1233625Y139517D01*
X1233417Y139308D01*
X1233333Y139058D01*
Y138642D01*
X1233208Y138267D01*
X1232958Y138017D01*
X1232667Y137933D01*
X1232375Y138017D01*
X1232167Y138225D01*
X1232042Y138558D01*
X1232000Y138850D01*
G01Y141033D02*
X1234500D01*
Y141867D01*
X1234375Y142200D01*
X1234208Y142450D01*
X1233958Y142658D01*
X1233667Y142825D01*
X1233250Y142867D01*
X1232833Y142825D01*
X1232542Y142658D01*
X1232292Y142450D01*
X1232125Y142200D01*
X1232000Y141867D01*
Y141033D01*
G01X1232500Y144133D02*
X1232208Y144383D01*
X1232042Y144717D01*
X1232000Y145092D01*
X1232042Y145425D01*
X1232250Y145758D01*
X1232500Y145967D01*
X1232750Y146008D01*
X1233042Y145925D01*
X1233250Y145633D01*
X1233333Y145342D01*
Y144967D01*
G01Y145342D02*
X1233458Y145592D01*
X1233667Y145800D01*
X1233917Y145883D01*
X1234167Y145800D01*
X1234375Y145592D01*
X1234500Y145217D01*
X1234458Y144842D01*
X1234292Y144467D01*
G01X1234500Y148150D02*
X1234417Y147817D01*
X1234208Y147567D01*
X1233958Y147400D01*
X1233625Y147275D01*
X1233250Y147233D01*
X1232875Y147275D01*
X1232542Y147400D01*
X1232292Y147567D01*
X1232083Y147817D01*
X1232000Y148150D01*
X1232083Y148483D01*
X1232292Y148733D01*
X1232542Y148900D01*
X1232875Y149025D01*
X1233250Y149067D01*
X1233625Y149025D01*
X1233958Y148900D01*
X1234208Y148733D01*
X1234417Y148483D01*
X1234500Y148150D01*
G01X1282420Y102800D02*
Y105900D01*
X1282880Y105280D01*
G01Y102800D02*
X1281960D01*
G01X1278860D02*
Y105900D01*
X1280278Y103678D01*
X1278362D01*
G01X1275760Y102800D02*
Y105900D01*
X1277178Y103678D01*
X1275262D01*
G01X1233550Y103100D02*
X1233883Y103142D01*
X1234175Y103308D01*
X1234425Y103558D01*
X1234592Y103850D01*
X1234675Y104183D01*
Y104517D01*
X1234592Y104850D01*
X1234425Y105142D01*
X1234175Y105392D01*
X1233883Y105558D01*
X1233550Y105600D01*
X1233217Y105558D01*
X1232925Y105392D01*
X1232675Y105142D01*
X1232508Y104850D01*
X1232425Y104517D01*
Y104183D01*
X1232508Y103850D01*
X1232675Y103558D01*
X1232925Y103308D01*
X1233217Y103142D01*
X1233550Y103100D01*
G01X1233217Y103767D02*
X1232717Y103100D01*
G01X1230450D02*
X1230158Y103142D01*
X1229825Y103267D01*
X1229617Y103475D01*
X1229533Y103767D01*
X1229617Y104058D01*
X1229867Y104308D01*
X1230242Y104433D01*
X1230658D01*
X1230908Y104517D01*
X1231117Y104725D01*
X1231200Y105017D01*
X1231075Y105308D01*
X1230783Y105517D01*
X1230450Y105600D01*
X1230117Y105517D01*
X1229825Y105308D01*
X1229700Y105017D01*
X1229783Y104725D01*
X1229992Y104517D01*
X1230242Y104433D01*
X1230658D01*
X1231033Y104308D01*
X1231283Y104058D01*
X1231367Y103767D01*
X1231283Y103475D01*
X1231075Y103267D01*
X1230742Y103142D01*
X1230450Y103100D01*
G01X1228267D02*
Y105600D01*
X1227433D01*
X1227100Y105475D01*
X1226850Y105308D01*
X1226642Y105058D01*
X1226475Y104767D01*
X1226433Y104350D01*
X1226475Y103933D01*
X1226642Y103642D01*
X1226850Y103392D01*
X1227100Y103225D01*
X1227433Y103100D01*
X1228267D01*
G01X1224250D02*
Y105600D01*
X1224750Y105100D01*
G01Y103100D02*
X1223750D01*
G01X1248579Y103359D02*
X1248912Y103401D01*
X1249204Y103567D01*
X1249454Y103817D01*
X1249621Y104109D01*
X1249704Y104442D01*
Y104776D01*
X1249621Y105109D01*
X1249454Y105401D01*
X1249204Y105651D01*
X1248912Y105817D01*
X1248579Y105859D01*
X1248246Y105817D01*
X1247954Y105651D01*
X1247704Y105401D01*
X1247537Y105109D01*
X1247454Y104776D01*
Y104442D01*
X1247537Y104109D01*
X1247704Y103817D01*
X1247954Y103567D01*
X1248246Y103401D01*
X1248579Y103359D01*
G01X1248246Y104026D02*
X1247746Y103359D01*
G01X1245479D02*
X1245187Y103401D01*
X1244854Y103526D01*
X1244646Y103734D01*
X1244562Y104026D01*
X1244646Y104317D01*
X1244896Y104567D01*
X1245271Y104692D01*
X1245687D01*
X1245937Y104776D01*
X1246146Y104984D01*
X1246229Y105276D01*
X1246104Y105567D01*
X1245812Y105776D01*
X1245479Y105859D01*
X1245146Y105776D01*
X1244854Y105567D01*
X1244729Y105276D01*
X1244812Y104984D01*
X1245021Y104776D01*
X1245271Y104692D01*
X1245687D01*
X1246062Y104567D01*
X1246312Y104317D01*
X1246396Y104026D01*
X1246312Y103734D01*
X1246104Y103526D01*
X1245771Y103401D01*
X1245479Y103359D01*
G01X1243629Y105859D02*
X1243046Y103359D01*
X1242379Y105859D01*
X1241712Y103359D01*
X1241129Y105859D01*
G01X1239279Y103359D02*
Y105859D01*
X1239779Y105359D01*
G01Y103359D02*
X1238779D01*
G01X1284583Y217900D02*
Y220400D01*
X1283542D01*
X1283208Y220275D01*
X1283000Y220108D01*
X1282917Y219775D01*
X1283000Y219442D01*
X1283250Y219233D01*
X1283542Y219108D01*
X1284583D01*
G01X1283542D02*
X1282917Y217900D01*
G01X1280150D02*
Y220400D01*
X1281692Y218608D01*
X1279608D01*
G01X1278383Y217900D02*
Y220400D01*
X1277342D01*
X1277008Y220275D01*
X1276800Y220108D01*
X1276717Y219775D01*
X1276800Y219442D01*
X1277050Y219233D01*
X1277342Y219108D01*
X1278383D01*
G01X1277342D02*
X1276717Y217900D01*
G01X1275242Y218942D02*
X1274950Y219233D01*
X1274700Y219400D01*
X1274367Y219483D01*
X1274075Y219400D01*
X1273867Y219233D01*
X1273700Y218983D01*
X1273658Y218692D01*
X1273700Y218442D01*
X1273867Y218192D01*
X1274117Y217983D01*
X1274408Y217900D01*
X1274742Y217983D01*
X1275033Y218233D01*
X1275200Y218608D01*
X1275242Y219025D01*
X1275158Y219567D01*
X1275033Y219858D01*
X1274825Y220150D01*
X1274533Y220358D01*
X1274242Y220400D01*
X1273950Y220317D01*
X1273742Y220108D01*
G01X1284683Y213900D02*
Y216400D01*
X1283642D01*
X1283308Y216275D01*
X1283100Y216108D01*
X1283017Y215775D01*
X1283100Y215442D01*
X1283350Y215233D01*
X1283642Y215108D01*
X1284683D01*
G01X1283642D02*
X1283017Y213900D01*
G01X1281667Y214275D02*
X1281417Y214067D01*
X1281125Y213942D01*
X1280750Y213900D01*
X1280375Y213983D01*
X1280083Y214150D01*
X1279875Y214442D01*
X1279833Y214775D01*
X1279917Y215108D01*
X1280125Y215317D01*
X1280417Y215483D01*
X1280708Y215525D01*
X1281000Y215483D01*
X1281375Y215317D01*
X1281250Y216400D01*
X1280125D01*
G01X1278900D02*
X1278317Y213900D01*
X1277650Y216400D01*
X1276983Y213900D01*
X1276400Y216400D01*
G01X1274550Y213900D02*
Y216400D01*
X1275050Y215900D01*
G01Y213900D02*
X1274050D01*
G01X1246802Y246271D02*
Y248771D01*
X1245761D01*
X1245427Y248646D01*
X1245219Y248479D01*
X1245136Y248146D01*
X1245219Y247813D01*
X1245469Y247604D01*
X1245761Y247479D01*
X1246802D01*
G01X1245761D02*
X1245136Y246271D01*
G01X1242369D02*
Y248771D01*
X1243911Y246979D01*
X1241827D01*
G01X1240602Y246271D02*
Y248771D01*
X1239602D01*
X1239269Y248646D01*
X1239019Y248354D01*
X1238936Y248021D01*
X1239019Y247688D01*
X1239227Y247438D01*
X1239602Y247313D01*
X1240602D01*
G01X1237461Y248354D02*
X1237211Y248604D01*
X1236919Y248729D01*
X1236586Y248771D01*
X1236169Y248688D01*
X1235877Y248479D01*
X1235794Y248229D01*
X1235836Y247979D01*
X1236002Y247771D01*
X1236836Y247354D01*
X1237211Y247063D01*
X1237461Y246646D01*
X1237544Y246271D01*
X1235794D01*
G01X1234486Y246771D02*
X1234236Y246479D01*
X1233902Y246313D01*
X1233527Y246271D01*
X1233194Y246313D01*
X1232861Y246521D01*
X1232652Y246771D01*
X1232611Y247021D01*
X1232694Y247313D01*
X1232986Y247521D01*
X1233277Y247604D01*
X1233652D01*
G01X1233277D02*
X1233027Y247729D01*
X1232819Y247938D01*
X1232736Y248188D01*
X1232819Y248438D01*
X1233027Y248646D01*
X1233402Y248771D01*
X1233777Y248729D01*
X1234152Y248563D01*
G01X1246440Y250693D02*
Y253193D01*
X1245399D01*
X1245065Y253068D01*
X1244857Y252901D01*
X1244774Y252568D01*
X1244857Y252235D01*
X1245107Y252026D01*
X1245399Y251901D01*
X1246440D01*
G01X1245399D02*
X1244774Y250693D01*
G01X1242007D02*
Y253193D01*
X1243549Y251401D01*
X1241465D01*
G01X1240240Y250693D02*
Y253193D01*
X1239240D01*
X1238907Y253068D01*
X1238657Y252776D01*
X1238574Y252443D01*
X1238657Y252110D01*
X1238865Y251860D01*
X1239240Y251735D01*
X1240240D01*
G01X1237099Y252776D02*
X1236849Y253026D01*
X1236557Y253151D01*
X1236224Y253193D01*
X1235807Y253110D01*
X1235515Y252901D01*
X1235432Y252651D01*
X1235474Y252401D01*
X1235640Y252193D01*
X1236474Y251776D01*
X1236849Y251485D01*
X1237099Y251068D01*
X1237182Y250693D01*
X1235432D01*
G01X1233207D02*
Y253193D01*
X1233707Y252693D01*
G01Y250693D02*
X1232707D01*
G01X1242150Y255967D02*
X1244650D01*
Y257008D01*
X1244525Y257342D01*
X1244358Y257550D01*
X1244025Y257633D01*
X1243692Y257550D01*
X1243483Y257300D01*
X1243358Y257008D01*
Y255967D01*
G01Y257008D02*
X1242150Y257633D01*
G01Y260400D02*
X1244650D01*
X1242858Y258858D01*
Y260942D01*
G01X1242150Y262167D02*
X1244650D01*
Y263167D01*
X1244525Y263500D01*
X1244233Y263750D01*
X1243900Y263833D01*
X1243567Y263750D01*
X1243317Y263542D01*
X1243192Y263167D01*
Y262167D01*
G01X1242150Y266100D02*
X1244650D01*
X1244150Y265600D01*
G01X1242150D02*
Y266600D01*
G01Y269200D02*
X1242192Y269492D01*
X1242317Y269825D01*
X1242525Y270033D01*
X1242817Y270117D01*
X1243108Y270033D01*
X1243358Y269783D01*
X1243483Y269408D01*
Y268992D01*
X1243567Y268742D01*
X1243775Y268533D01*
X1244067Y268450D01*
X1244358Y268575D01*
X1244567Y268867D01*
X1244650Y269200D01*
X1244567Y269533D01*
X1244358Y269825D01*
X1244067Y269950D01*
X1243775Y269867D01*
X1243567Y269658D01*
X1243483Y269408D01*
Y268992D01*
X1243358Y268617D01*
X1243108Y268367D01*
X1242817Y268283D01*
X1242525Y268367D01*
X1242317Y268575D01*
X1242192Y268908D01*
X1242150Y269200D01*
G01X1227650Y254617D02*
X1230150D01*
Y255658D01*
X1230025Y255992D01*
X1229858Y256200D01*
X1229525Y256283D01*
X1229192Y256200D01*
X1228983Y255950D01*
X1228858Y255658D01*
Y254617D01*
G01Y255658D02*
X1227650Y256283D01*
G01Y259050D02*
X1230150D01*
X1228358Y257508D01*
Y259592D01*
G01X1227650Y260817D02*
X1230150D01*
Y261817D01*
X1230025Y262150D01*
X1229733Y262400D01*
X1229400Y262483D01*
X1229067Y262400D01*
X1228817Y262192D01*
X1228692Y261817D01*
Y260817D01*
G01X1227650Y264750D02*
X1230150D01*
X1229650Y264250D01*
G01X1227650D02*
Y265250D01*
G01X1227942Y267142D02*
X1227733Y267433D01*
X1227650Y267767D01*
X1227733Y268100D01*
X1227983Y268392D01*
X1228358Y268600D01*
X1228733Y268683D01*
X1229192D01*
X1229567Y268600D01*
X1229900Y268392D01*
X1230067Y268142D01*
X1230150Y267850D01*
X1230067Y267517D01*
X1229900Y267267D01*
X1229650Y267100D01*
X1229317Y267017D01*
X1229025Y267100D01*
X1228733Y267308D01*
X1228567Y267558D01*
X1228525Y267850D01*
X1228608Y268183D01*
X1228817Y268433D01*
X1229192Y268683D01*
G01X1227501Y237316D02*
X1230001D01*
Y238357D01*
X1229876Y238691D01*
X1229709Y238899D01*
X1229376Y238982D01*
X1229043Y238899D01*
X1228834Y238649D01*
X1228709Y238357D01*
Y237316D01*
G01Y238357D02*
X1227501Y238982D01*
G01Y241749D02*
X1230001D01*
X1228209Y240207D01*
Y242291D01*
G01X1227501Y243516D02*
X1230001D01*
Y244516D01*
X1229876Y244849D01*
X1229584Y245099D01*
X1229251Y245182D01*
X1228918Y245099D01*
X1228668Y244891D01*
X1228543Y244516D01*
Y243516D01*
G01X1229584Y246657D02*
X1229834Y246907D01*
X1229959Y247199D01*
X1230001Y247532D01*
X1229918Y247949D01*
X1229709Y248241D01*
X1229459Y248324D01*
X1229209Y248282D01*
X1229001Y248116D01*
X1228584Y247282D01*
X1228293Y246907D01*
X1227876Y246657D01*
X1227501Y246574D01*
Y248324D01*
G01Y251049D02*
X1230001D01*
X1228209Y249507D01*
Y251591D01*
G01X1276524Y225953D02*
Y228453D01*
X1275483D01*
X1275149Y228328D01*
X1274941Y228161D01*
X1274858Y227828D01*
X1274941Y227495D01*
X1275191Y227286D01*
X1275483Y227161D01*
X1276524D01*
G01X1275483D02*
X1274858Y225953D01*
G01X1272091D02*
Y228453D01*
X1273633Y226661D01*
X1271549D01*
G01X1270324Y225953D02*
Y228453D01*
X1269283D01*
X1268949Y228328D01*
X1268741Y228161D01*
X1268658Y227828D01*
X1268741Y227495D01*
X1268991Y227286D01*
X1269283Y227161D01*
X1270324D01*
G01X1269283D02*
X1268658Y225953D01*
G01X1267308Y226328D02*
X1267058Y226120D01*
X1266766Y225995D01*
X1266391Y225953D01*
X1266016Y226036D01*
X1265724Y226203D01*
X1265516Y226495D01*
X1265474Y226828D01*
X1265558Y227161D01*
X1265766Y227370D01*
X1266058Y227536D01*
X1266349Y227578D01*
X1266641Y227536D01*
X1267016Y227370D01*
X1266891Y228453D01*
X1265766D01*
G01X1276524Y229953D02*
Y232453D01*
X1275483D01*
X1275149Y232328D01*
X1274941Y232161D01*
X1274858Y231828D01*
X1274941Y231495D01*
X1275191Y231286D01*
X1275483Y231161D01*
X1276524D01*
G01X1275483D02*
X1274858Y229953D01*
G01X1272091D02*
Y232453D01*
X1273633Y230661D01*
X1271549D01*
G01X1270324Y229953D02*
Y232453D01*
X1269283D01*
X1268949Y232328D01*
X1268741Y232161D01*
X1268658Y231828D01*
X1268741Y231495D01*
X1268991Y231286D01*
X1269283Y231161D01*
X1270324D01*
G01X1269283D02*
X1268658Y229953D01*
G01X1266391D02*
Y232453D01*
X1266891Y231953D01*
G01Y229953D02*
X1265891D01*
G01X1283871Y239375D02*
Y241875D01*
X1282830D01*
X1282496Y241750D01*
X1282288Y241583D01*
X1282205Y241250D01*
X1282288Y240917D01*
X1282538Y240708D01*
X1282830Y240583D01*
X1283871D01*
G01X1282830D02*
X1282205Y239375D01*
G01X1279438D02*
Y241875D01*
X1280980Y240083D01*
X1278896D01*
G01X1277671Y239375D02*
Y241875D01*
X1276630D01*
X1276296Y241750D01*
X1276088Y241583D01*
X1276005Y241250D01*
X1276088Y240917D01*
X1276338Y240708D01*
X1276630Y240583D01*
X1277671D01*
G01X1276630D02*
X1276005Y239375D01*
G01X1274530Y241458D02*
X1274280Y241708D01*
X1273988Y241833D01*
X1273655Y241875D01*
X1273238Y241792D01*
X1272946Y241583D01*
X1272863Y241333D01*
X1272905Y241083D01*
X1273071Y240875D01*
X1273905Y240458D01*
X1274280Y240167D01*
X1274530Y239750D01*
X1274613Y239375D01*
X1272863D01*
G01X1283488Y235375D02*
Y237875D01*
X1282447D01*
X1282113Y237750D01*
X1281905Y237583D01*
X1281822Y237250D01*
X1281905Y236917D01*
X1282155Y236708D01*
X1282447Y236583D01*
X1283488D01*
G01X1282447D02*
X1281822Y235375D01*
G01X1279055D02*
Y237875D01*
X1280597Y236083D01*
X1278513D01*
G01X1277288Y235375D02*
Y237875D01*
X1276247D01*
X1275913Y237750D01*
X1275705Y237583D01*
X1275622Y237250D01*
X1275705Y236917D01*
X1275955Y236708D01*
X1276247Y236583D01*
X1277288D01*
G01X1276247D02*
X1275622Y235375D01*
G01X1272855D02*
Y237875D01*
X1274397Y236083D01*
X1272313D01*
G01X1282367Y225000D02*
Y223208D01*
X1282200Y222833D01*
X1281867Y222583D01*
X1281450Y222500D01*
X1281033Y222583D01*
X1280700Y222833D01*
X1280533Y223208D01*
Y225000D01*
G01X1277850Y222500D02*
Y225000D01*
X1279392Y223208D01*
X1277308D01*
G01X1276083Y222500D02*
Y225000D01*
X1275042D01*
X1274708Y224875D01*
X1274500Y224708D01*
X1274417Y224375D01*
X1274500Y224042D01*
X1274750Y223833D01*
X1275042Y223708D01*
X1276083D01*
G01X1275042D02*
X1274417Y222500D01*
G01X1272150D02*
Y225000D01*
X1272650Y224500D01*
G01Y222500D02*
X1271650D01*
G01X1298000Y311500D02*
Y287400D01*
X1231600D01*
Y322699D01*
X1231601Y322700D01*
G01D02*
X1298000D01*
Y311501D01*
X1298001Y311500D01*
X1308900D01*
Y308600D01*
X1328939D01*
X1328944Y308605D01*
X1327444Y310105D01*
Y307105D01*
X1328944Y308605D01*
G01X1280092Y308817D02*
X1280217Y308567D01*
X1280300Y308275D01*
Y307942D01*
X1280175Y307567D01*
X1279967Y307275D01*
X1279717Y307067D01*
X1279300Y306900D01*
X1278925Y306858D01*
X1278550Y306942D01*
X1278300Y307067D01*
X1278050Y307317D01*
X1277883Y307608D01*
X1277800Y307900D01*
Y308192D01*
X1277883Y308483D01*
X1278008Y308733D01*
X1278175Y308942D01*
G01X1278300Y310083D02*
X1278008Y310333D01*
X1277842Y310667D01*
X1277800Y311042D01*
X1277842Y311375D01*
X1278050Y311708D01*
X1278300Y311917D01*
X1278550Y311958D01*
X1278842Y311875D01*
X1279050Y311583D01*
X1279133Y311292D01*
Y310917D01*
G01Y311292D02*
X1279258Y311542D01*
X1279467Y311750D01*
X1279717Y311833D01*
X1279967Y311750D01*
X1280175Y311542D01*
X1280300Y311167D01*
X1280258Y310792D01*
X1280092Y310417D01*
G01X1277800Y313267D02*
X1280300D01*
Y314267D01*
X1280175Y314600D01*
X1279883Y314850D01*
X1279550Y314933D01*
X1279217Y314850D01*
X1278967Y314642D01*
X1278842Y314267D01*
Y313267D01*
G01X1278300Y316283D02*
X1278008Y316533D01*
X1277842Y316867D01*
X1277800Y317242D01*
X1277842Y317575D01*
X1278050Y317908D01*
X1278300Y318117D01*
X1278550Y318158D01*
X1278842Y318075D01*
X1279050Y317783D01*
X1279133Y317492D01*
Y317117D01*
G01Y317492D02*
X1279258Y317742D01*
X1279467Y317950D01*
X1279717Y318033D01*
X1279967Y317950D01*
X1280175Y317742D01*
X1280300Y317367D01*
X1280258Y316992D01*
X1280092Y316617D01*
G01X1279883Y319508D02*
X1280133Y319758D01*
X1280258Y320050D01*
X1280300Y320383D01*
X1280217Y320800D01*
X1280008Y321092D01*
X1279758Y321175D01*
X1279508Y321133D01*
X1279300Y320967D01*
X1278883Y320133D01*
X1278592Y319758D01*
X1278175Y319508D01*
X1277800Y319425D01*
Y321175D01*
G01X1280079Y292041D02*
X1280204Y291791D01*
X1280287Y291499D01*
Y291166D01*
X1280162Y290791D01*
X1279954Y290499D01*
X1279704Y290291D01*
X1279287Y290124D01*
X1278912Y290082D01*
X1278537Y290166D01*
X1278287Y290291D01*
X1278037Y290541D01*
X1277870Y290832D01*
X1277787Y291124D01*
Y291416D01*
X1277870Y291707D01*
X1277995Y291957D01*
X1278162Y292166D01*
G01X1278287Y293307D02*
X1277995Y293557D01*
X1277829Y293891D01*
X1277787Y294266D01*
X1277829Y294599D01*
X1278037Y294932D01*
X1278287Y295141D01*
X1278537Y295182D01*
X1278829Y295099D01*
X1279037Y294807D01*
X1279120Y294516D01*
Y294141D01*
G01Y294516D02*
X1279245Y294766D01*
X1279454Y294974D01*
X1279704Y295057D01*
X1279954Y294974D01*
X1280162Y294766D01*
X1280287Y294391D01*
X1280245Y294016D01*
X1280079Y293641D01*
G01X1277787Y296491D02*
X1280287D01*
Y297491D01*
X1280162Y297824D01*
X1279870Y298074D01*
X1279537Y298157D01*
X1279204Y298074D01*
X1278954Y297866D01*
X1278829Y297491D01*
Y296491D01*
G01X1278287Y299507D02*
X1277995Y299757D01*
X1277829Y300091D01*
X1277787Y300466D01*
X1277829Y300799D01*
X1278037Y301132D01*
X1278287Y301341D01*
X1278537Y301382D01*
X1278829Y301299D01*
X1279037Y301007D01*
X1279120Y300716D01*
Y300341D01*
G01Y300716D02*
X1279245Y300966D01*
X1279454Y301174D01*
X1279704Y301257D01*
X1279954Y301174D01*
X1280162Y300966D01*
X1280287Y300591D01*
X1280245Y300216D01*
X1280079Y299841D01*
G01X1278287Y302607D02*
X1277995Y302857D01*
X1277829Y303191D01*
X1277787Y303566D01*
X1277829Y303899D01*
X1278037Y304232D01*
X1278287Y304441D01*
X1278537Y304482D01*
X1278829Y304399D01*
X1279037Y304107D01*
X1279120Y303816D01*
Y303441D01*
G01Y303816D02*
X1279245Y304066D01*
X1279454Y304274D01*
X1279704Y304357D01*
X1279954Y304274D01*
X1280162Y304066D01*
X1280287Y303691D01*
X1280245Y303316D01*
X1280079Y302941D01*
G01X1256092Y308817D02*
X1256217Y308567D01*
X1256300Y308275D01*
Y307942D01*
X1256175Y307567D01*
X1255967Y307275D01*
X1255717Y307067D01*
X1255300Y306900D01*
X1254925Y306858D01*
X1254550Y306942D01*
X1254300Y307067D01*
X1254050Y307317D01*
X1253883Y307608D01*
X1253800Y307900D01*
Y308192D01*
X1253883Y308483D01*
X1254008Y308733D01*
X1254175Y308942D01*
G01X1254300Y310083D02*
X1254008Y310333D01*
X1253842Y310667D01*
X1253800Y311042D01*
X1253842Y311375D01*
X1254050Y311708D01*
X1254300Y311917D01*
X1254550Y311958D01*
X1254842Y311875D01*
X1255050Y311583D01*
X1255133Y311292D01*
Y310917D01*
G01Y311292D02*
X1255258Y311542D01*
X1255467Y311750D01*
X1255717Y311833D01*
X1255967Y311750D01*
X1256175Y311542D01*
X1256300Y311167D01*
X1256258Y310792D01*
X1256092Y310417D01*
G01X1253800Y313267D02*
X1256300D01*
Y314267D01*
X1256175Y314600D01*
X1255883Y314850D01*
X1255550Y314933D01*
X1255217Y314850D01*
X1254967Y314642D01*
X1254842Y314267D01*
Y313267D01*
G01X1255883Y316408D02*
X1256133Y316658D01*
X1256258Y316950D01*
X1256300Y317283D01*
X1256217Y317700D01*
X1256008Y317992D01*
X1255758Y318075D01*
X1255508Y318033D01*
X1255300Y317867D01*
X1254883Y317033D01*
X1254592Y316658D01*
X1254175Y316408D01*
X1253800Y316325D01*
Y318075D01*
G01X1256300Y320300D02*
X1256217Y319967D01*
X1256008Y319717D01*
X1255758Y319550D01*
X1255425Y319425D01*
X1255050Y319383D01*
X1254675Y319425D01*
X1254342Y319550D01*
X1254092Y319717D01*
X1253883Y319967D01*
X1253800Y320300D01*
X1253883Y320633D01*
X1254092Y320883D01*
X1254342Y321050D01*
X1254675Y321175D01*
X1255050Y321217D01*
X1255425Y321175D01*
X1255758Y321050D01*
X1256008Y320883D01*
X1256217Y320633D01*
X1256300Y320300D01*
G01X1252079Y292041D02*
X1252204Y291791D01*
X1252287Y291499D01*
Y291166D01*
X1252162Y290791D01*
X1251954Y290499D01*
X1251704Y290291D01*
X1251287Y290124D01*
X1250912Y290082D01*
X1250537Y290166D01*
X1250287Y290291D01*
X1250037Y290541D01*
X1249870Y290832D01*
X1249787Y291124D01*
Y291416D01*
X1249870Y291707D01*
X1249995Y291957D01*
X1250162Y292166D01*
G01X1250287Y293307D02*
X1249995Y293557D01*
X1249829Y293891D01*
X1249787Y294266D01*
X1249829Y294599D01*
X1250037Y294932D01*
X1250287Y295141D01*
X1250537Y295182D01*
X1250829Y295099D01*
X1251037Y294807D01*
X1251120Y294516D01*
Y294141D01*
G01Y294516D02*
X1251245Y294766D01*
X1251454Y294974D01*
X1251704Y295057D01*
X1251954Y294974D01*
X1252162Y294766D01*
X1252287Y294391D01*
X1252245Y294016D01*
X1252079Y293641D01*
G01X1249787Y296491D02*
X1252287D01*
Y297491D01*
X1252162Y297824D01*
X1251870Y298074D01*
X1251537Y298157D01*
X1251204Y298074D01*
X1250954Y297866D01*
X1250829Y297491D01*
Y296491D01*
G01X1249787Y300424D02*
X1252287D01*
X1251787Y299924D01*
G01X1249787D02*
Y300924D01*
G01X1250079Y302816D02*
X1249870Y303107D01*
X1249787Y303441D01*
X1249870Y303774D01*
X1250120Y304066D01*
X1250495Y304274D01*
X1250870Y304357D01*
X1251329D01*
X1251704Y304274D01*
X1252037Y304066D01*
X1252204Y303816D01*
X1252287Y303524D01*
X1252204Y303191D01*
X1252037Y302941D01*
X1251787Y302774D01*
X1251454Y302691D01*
X1251162Y302774D01*
X1250870Y302982D01*
X1250704Y303232D01*
X1250662Y303524D01*
X1250745Y303857D01*
X1250954Y304107D01*
X1251329Y304357D01*
G01X1256079Y292041D02*
X1256204Y291791D01*
X1256287Y291499D01*
Y291166D01*
X1256162Y290791D01*
X1255954Y290499D01*
X1255704Y290291D01*
X1255287Y290124D01*
X1254912Y290082D01*
X1254537Y290166D01*
X1254287Y290291D01*
X1254037Y290541D01*
X1253870Y290832D01*
X1253787Y291124D01*
Y291416D01*
X1253870Y291707D01*
X1253995Y291957D01*
X1254162Y292166D01*
G01X1254287Y293307D02*
X1253995Y293557D01*
X1253829Y293891D01*
X1253787Y294266D01*
X1253829Y294599D01*
X1254037Y294932D01*
X1254287Y295141D01*
X1254537Y295182D01*
X1254829Y295099D01*
X1255037Y294807D01*
X1255120Y294516D01*
Y294141D01*
G01Y294516D02*
X1255245Y294766D01*
X1255454Y294974D01*
X1255704Y295057D01*
X1255954Y294974D01*
X1256162Y294766D01*
X1256287Y294391D01*
X1256245Y294016D01*
X1256079Y293641D01*
G01X1253787Y296491D02*
X1256287D01*
Y297491D01*
X1256162Y297824D01*
X1255870Y298074D01*
X1255537Y298157D01*
X1255204Y298074D01*
X1254954Y297866D01*
X1254829Y297491D01*
Y296491D01*
G01X1255870Y299632D02*
X1256120Y299882D01*
X1256245Y300174D01*
X1256287Y300507D01*
X1256204Y300924D01*
X1255995Y301216D01*
X1255745Y301299D01*
X1255495Y301257D01*
X1255287Y301091D01*
X1254870Y300257D01*
X1254579Y299882D01*
X1254162Y299632D01*
X1253787Y299549D01*
Y301299D01*
G01Y303524D02*
X1256287D01*
X1255787Y303024D01*
G01X1253787D02*
Y304024D01*
G01X1272092Y308817D02*
X1272217Y308567D01*
X1272300Y308275D01*
Y307942D01*
X1272175Y307567D01*
X1271967Y307275D01*
X1271717Y307067D01*
X1271300Y306900D01*
X1270925Y306858D01*
X1270550Y306942D01*
X1270300Y307067D01*
X1270050Y307317D01*
X1269883Y307608D01*
X1269800Y307900D01*
Y308192D01*
X1269883Y308483D01*
X1270008Y308733D01*
X1270175Y308942D01*
G01X1270300Y310083D02*
X1270008Y310333D01*
X1269842Y310667D01*
X1269800Y311042D01*
X1269842Y311375D01*
X1270050Y311708D01*
X1270300Y311917D01*
X1270550Y311958D01*
X1270842Y311875D01*
X1271050Y311583D01*
X1271133Y311292D01*
Y310917D01*
G01Y311292D02*
X1271258Y311542D01*
X1271467Y311750D01*
X1271717Y311833D01*
X1271967Y311750D01*
X1272175Y311542D01*
X1272300Y311167D01*
X1272258Y310792D01*
X1272092Y310417D01*
G01X1269800Y313267D02*
X1272300D01*
Y314267D01*
X1272175Y314600D01*
X1271883Y314850D01*
X1271550Y314933D01*
X1271217Y314850D01*
X1270967Y314642D01*
X1270842Y314267D01*
Y313267D01*
G01X1271883Y316408D02*
X1272133Y316658D01*
X1272258Y316950D01*
X1272300Y317283D01*
X1272217Y317700D01*
X1272008Y317992D01*
X1271758Y318075D01*
X1271508Y318033D01*
X1271300Y317867D01*
X1270883Y317033D01*
X1270592Y316658D01*
X1270175Y316408D01*
X1269800Y316325D01*
Y318075D01*
G01Y320300D02*
X1269842Y320592D01*
X1269967Y320925D01*
X1270175Y321133D01*
X1270467Y321217D01*
X1270758Y321133D01*
X1271008Y320883D01*
X1271133Y320508D01*
Y320092D01*
X1271217Y319842D01*
X1271425Y319633D01*
X1271717Y319550D01*
X1272008Y319675D01*
X1272217Y319967D01*
X1272300Y320300D01*
X1272217Y320633D01*
X1272008Y320925D01*
X1271717Y321050D01*
X1271425Y320967D01*
X1271217Y320758D01*
X1271133Y320508D01*
Y320092D01*
X1271008Y319717D01*
X1270758Y319467D01*
X1270467Y319383D01*
X1270175Y319467D01*
X1269967Y319675D01*
X1269842Y320008D01*
X1269800Y320300D01*
G01X1276079Y292041D02*
X1276204Y291791D01*
X1276287Y291499D01*
Y291166D01*
X1276162Y290791D01*
X1275954Y290499D01*
X1275704Y290291D01*
X1275287Y290124D01*
X1274912Y290082D01*
X1274537Y290166D01*
X1274287Y290291D01*
X1274037Y290541D01*
X1273870Y290832D01*
X1273787Y291124D01*
Y291416D01*
X1273870Y291707D01*
X1273995Y291957D01*
X1274162Y292166D01*
G01X1274287Y293307D02*
X1273995Y293557D01*
X1273829Y293891D01*
X1273787Y294266D01*
X1273829Y294599D01*
X1274037Y294932D01*
X1274287Y295141D01*
X1274537Y295182D01*
X1274829Y295099D01*
X1275037Y294807D01*
X1275120Y294516D01*
Y294141D01*
G01Y294516D02*
X1275245Y294766D01*
X1275454Y294974D01*
X1275704Y295057D01*
X1275954Y294974D01*
X1276162Y294766D01*
X1276287Y294391D01*
X1276245Y294016D01*
X1276079Y293641D01*
G01X1273787Y296491D02*
X1276287D01*
Y297491D01*
X1276162Y297824D01*
X1275870Y298074D01*
X1275537Y298157D01*
X1275204Y298074D01*
X1274954Y297866D01*
X1274829Y297491D01*
Y296491D01*
G01X1274287Y299507D02*
X1273995Y299757D01*
X1273829Y300091D01*
X1273787Y300466D01*
X1273829Y300799D01*
X1274037Y301132D01*
X1274287Y301341D01*
X1274537Y301382D01*
X1274829Y301299D01*
X1275037Y301007D01*
X1275120Y300716D01*
Y300341D01*
G01Y300716D02*
X1275245Y300966D01*
X1275454Y301174D01*
X1275704Y301257D01*
X1275954Y301174D01*
X1276162Y300966D01*
X1276287Y300591D01*
X1276245Y300216D01*
X1276079Y299841D01*
G01X1273787Y303524D02*
X1276287D01*
X1275787Y303024D01*
G01X1273787D02*
Y304024D01*
G01X1272079Y292041D02*
X1272204Y291791D01*
X1272287Y291499D01*
Y291166D01*
X1272162Y290791D01*
X1271954Y290499D01*
X1271704Y290291D01*
X1271287Y290124D01*
X1270912Y290082D01*
X1270537Y290166D01*
X1270287Y290291D01*
X1270037Y290541D01*
X1269870Y290832D01*
X1269787Y291124D01*
Y291416D01*
X1269870Y291707D01*
X1269995Y291957D01*
X1270162Y292166D01*
G01X1270287Y293307D02*
X1269995Y293557D01*
X1269829Y293891D01*
X1269787Y294266D01*
X1269829Y294599D01*
X1270037Y294932D01*
X1270287Y295141D01*
X1270537Y295182D01*
X1270829Y295099D01*
X1271037Y294807D01*
X1271120Y294516D01*
Y294141D01*
G01Y294516D02*
X1271245Y294766D01*
X1271454Y294974D01*
X1271704Y295057D01*
X1271954Y294974D01*
X1272162Y294766D01*
X1272287Y294391D01*
X1272245Y294016D01*
X1272079Y293641D01*
G01X1269787Y296491D02*
X1272287D01*
Y297491D01*
X1272162Y297824D01*
X1271870Y298074D01*
X1271537Y298157D01*
X1271204Y298074D01*
X1270954Y297866D01*
X1270829Y297491D01*
Y296491D01*
G01X1271870Y299632D02*
X1272120Y299882D01*
X1272245Y300174D01*
X1272287Y300507D01*
X1272204Y300924D01*
X1271995Y301216D01*
X1271745Y301299D01*
X1271495Y301257D01*
X1271287Y301091D01*
X1270870Y300257D01*
X1270579Y299882D01*
X1270162Y299632D01*
X1269787Y299549D01*
Y301299D01*
G01X1270079Y302816D02*
X1269870Y303107D01*
X1269787Y303441D01*
X1269870Y303774D01*
X1270120Y304066D01*
X1270495Y304274D01*
X1270870Y304357D01*
X1271329D01*
X1271704Y304274D01*
X1272037Y304066D01*
X1272204Y303816D01*
X1272287Y303524D01*
X1272204Y303191D01*
X1272037Y302941D01*
X1271787Y302774D01*
X1271454Y302691D01*
X1271162Y302774D01*
X1270870Y302982D01*
X1270704Y303232D01*
X1270662Y303524D01*
X1270745Y303857D01*
X1270954Y304107D01*
X1271329Y304357D01*
G01X1276092Y308817D02*
X1276217Y308567D01*
X1276300Y308275D01*
Y307942D01*
X1276175Y307567D01*
X1275967Y307275D01*
X1275717Y307067D01*
X1275300Y306900D01*
X1274925Y306858D01*
X1274550Y306942D01*
X1274300Y307067D01*
X1274050Y307317D01*
X1273883Y307608D01*
X1273800Y307900D01*
Y308192D01*
X1273883Y308483D01*
X1274008Y308733D01*
X1274175Y308942D01*
G01X1274300Y310083D02*
X1274008Y310333D01*
X1273842Y310667D01*
X1273800Y311042D01*
X1273842Y311375D01*
X1274050Y311708D01*
X1274300Y311917D01*
X1274550Y311958D01*
X1274842Y311875D01*
X1275050Y311583D01*
X1275133Y311292D01*
Y310917D01*
G01Y311292D02*
X1275258Y311542D01*
X1275467Y311750D01*
X1275717Y311833D01*
X1275967Y311750D01*
X1276175Y311542D01*
X1276300Y311167D01*
X1276258Y310792D01*
X1276092Y310417D01*
G01X1273800Y313267D02*
X1276300D01*
Y314267D01*
X1276175Y314600D01*
X1275883Y314850D01*
X1275550Y314933D01*
X1275217Y314850D01*
X1274967Y314642D01*
X1274842Y314267D01*
Y313267D01*
G01X1274300Y316283D02*
X1274008Y316533D01*
X1273842Y316867D01*
X1273800Y317242D01*
X1273842Y317575D01*
X1274050Y317908D01*
X1274300Y318117D01*
X1274550Y318158D01*
X1274842Y318075D01*
X1275050Y317783D01*
X1275133Y317492D01*
Y317117D01*
G01Y317492D02*
X1275258Y317742D01*
X1275467Y317950D01*
X1275717Y318033D01*
X1275967Y317950D01*
X1276175Y317742D01*
X1276300Y317367D01*
X1276258Y316992D01*
X1276092Y316617D01*
G01X1276300Y320300D02*
X1276217Y319967D01*
X1276008Y319717D01*
X1275758Y319550D01*
X1275425Y319425D01*
X1275050Y319383D01*
X1274675Y319425D01*
X1274342Y319550D01*
X1274092Y319717D01*
X1273883Y319967D01*
X1273800Y320300D01*
X1273883Y320633D01*
X1274092Y320883D01*
X1274342Y321050D01*
X1274675Y321175D01*
X1275050Y321217D01*
X1275425Y321175D01*
X1275758Y321050D01*
X1276008Y320883D01*
X1276217Y320633D01*
X1276300Y320300D01*
G01X1268079Y292041D02*
X1268204Y291791D01*
X1268287Y291499D01*
Y291166D01*
X1268162Y290791D01*
X1267954Y290499D01*
X1267704Y290291D01*
X1267287Y290124D01*
X1266912Y290082D01*
X1266537Y290166D01*
X1266287Y290291D01*
X1266037Y290541D01*
X1265870Y290832D01*
X1265787Y291124D01*
Y291416D01*
X1265870Y291707D01*
X1265995Y291957D01*
X1266162Y292166D01*
G01X1266287Y293307D02*
X1265995Y293557D01*
X1265829Y293891D01*
X1265787Y294266D01*
X1265829Y294599D01*
X1266037Y294932D01*
X1266287Y295141D01*
X1266537Y295182D01*
X1266829Y295099D01*
X1267037Y294807D01*
X1267120Y294516D01*
Y294141D01*
G01Y294516D02*
X1267245Y294766D01*
X1267454Y294974D01*
X1267704Y295057D01*
X1267954Y294974D01*
X1268162Y294766D01*
X1268287Y294391D01*
X1268245Y294016D01*
X1268079Y293641D01*
G01X1265787Y296491D02*
X1268287D01*
Y297491D01*
X1268162Y297824D01*
X1267870Y298074D01*
X1267537Y298157D01*
X1267204Y298074D01*
X1266954Y297866D01*
X1266829Y297491D01*
Y296491D01*
G01X1267870Y299632D02*
X1268120Y299882D01*
X1268245Y300174D01*
X1268287Y300507D01*
X1268204Y300924D01*
X1267995Y301216D01*
X1267745Y301299D01*
X1267495Y301257D01*
X1267287Y301091D01*
X1266870Y300257D01*
X1266579Y299882D01*
X1266162Y299632D01*
X1265787Y299549D01*
Y301299D01*
G01X1266829Y302732D02*
X1267120Y303024D01*
X1267287Y303274D01*
X1267370Y303607D01*
X1267287Y303899D01*
X1267120Y304107D01*
X1266870Y304274D01*
X1266579Y304316D01*
X1266329Y304274D01*
X1266079Y304107D01*
X1265870Y303857D01*
X1265787Y303566D01*
X1265870Y303232D01*
X1266120Y302941D01*
X1266495Y302774D01*
X1266912Y302732D01*
X1267454Y302816D01*
X1267745Y302941D01*
X1268037Y303149D01*
X1268245Y303441D01*
X1268287Y303732D01*
X1268204Y304024D01*
X1267995Y304232D01*
G01X1268092Y308817D02*
X1268217Y308567D01*
X1268300Y308275D01*
Y307942D01*
X1268175Y307567D01*
X1267967Y307275D01*
X1267717Y307067D01*
X1267300Y306900D01*
X1266925Y306858D01*
X1266550Y306942D01*
X1266300Y307067D01*
X1266050Y307317D01*
X1265883Y307608D01*
X1265800Y307900D01*
Y308192D01*
X1265883Y308483D01*
X1266008Y308733D01*
X1266175Y308942D01*
G01X1266300Y310083D02*
X1266008Y310333D01*
X1265842Y310667D01*
X1265800Y311042D01*
X1265842Y311375D01*
X1266050Y311708D01*
X1266300Y311917D01*
X1266550Y311958D01*
X1266842Y311875D01*
X1267050Y311583D01*
X1267133Y311292D01*
Y310917D01*
G01Y311292D02*
X1267258Y311542D01*
X1267467Y311750D01*
X1267717Y311833D01*
X1267967Y311750D01*
X1268175Y311542D01*
X1268300Y311167D01*
X1268258Y310792D01*
X1268092Y310417D01*
G01X1265800Y313267D02*
X1268300D01*
Y314267D01*
X1268175Y314600D01*
X1267883Y314850D01*
X1267550Y314933D01*
X1267217Y314850D01*
X1266967Y314642D01*
X1266842Y314267D01*
Y313267D01*
G01X1267883Y316408D02*
X1268133Y316658D01*
X1268258Y316950D01*
X1268300Y317283D01*
X1268217Y317700D01*
X1268008Y317992D01*
X1267758Y318075D01*
X1267508Y318033D01*
X1267300Y317867D01*
X1266883Y317033D01*
X1266592Y316658D01*
X1266175Y316408D01*
X1265800Y316325D01*
Y318075D01*
G01Y320217D02*
X1266342Y320300D01*
X1266800Y320425D01*
X1267217Y320592D01*
X1267675Y320800D01*
X1268300Y321133D01*
Y319467D01*
G01X1240092Y308817D02*
X1240217Y308567D01*
X1240300Y308275D01*
Y307942D01*
X1240175Y307567D01*
X1239967Y307275D01*
X1239717Y307067D01*
X1239300Y306900D01*
X1238925Y306858D01*
X1238550Y306942D01*
X1238300Y307067D01*
X1238050Y307317D01*
X1237883Y307608D01*
X1237800Y307900D01*
Y308192D01*
X1237883Y308483D01*
X1238008Y308733D01*
X1238175Y308942D01*
G01X1238300Y310083D02*
X1238008Y310333D01*
X1237842Y310667D01*
X1237800Y311042D01*
X1237842Y311375D01*
X1238050Y311708D01*
X1238300Y311917D01*
X1238550Y311958D01*
X1238842Y311875D01*
X1239050Y311583D01*
X1239133Y311292D01*
Y310917D01*
G01Y311292D02*
X1239258Y311542D01*
X1239467Y311750D01*
X1239717Y311833D01*
X1239967Y311750D01*
X1240175Y311542D01*
X1240300Y311167D01*
X1240258Y310792D01*
X1240092Y310417D01*
G01X1237800Y313267D02*
X1240300D01*
Y314267D01*
X1240175Y314600D01*
X1239883Y314850D01*
X1239550Y314933D01*
X1239217Y314850D01*
X1238967Y314642D01*
X1238842Y314267D01*
Y313267D01*
G01X1237800Y317200D02*
X1240300D01*
X1239800Y316700D01*
G01X1237800D02*
Y317700D01*
G01X1238300Y319383D02*
X1238008Y319633D01*
X1237842Y319967D01*
X1237800Y320342D01*
X1237842Y320675D01*
X1238050Y321008D01*
X1238300Y321217D01*
X1238550Y321258D01*
X1238842Y321175D01*
X1239050Y320883D01*
X1239133Y320592D01*
Y320217D01*
G01Y320592D02*
X1239258Y320842D01*
X1239467Y321050D01*
X1239717Y321133D01*
X1239967Y321050D01*
X1240175Y320842D01*
X1240300Y320467D01*
X1240258Y320092D01*
X1240092Y319717D01*
G01X1244092Y308817D02*
X1244217Y308567D01*
X1244300Y308275D01*
Y307942D01*
X1244175Y307567D01*
X1243967Y307275D01*
X1243717Y307067D01*
X1243300Y306900D01*
X1242925Y306858D01*
X1242550Y306942D01*
X1242300Y307067D01*
X1242050Y307317D01*
X1241883Y307608D01*
X1241800Y307900D01*
Y308192D01*
X1241883Y308483D01*
X1242008Y308733D01*
X1242175Y308942D01*
G01X1242300Y310083D02*
X1242008Y310333D01*
X1241842Y310667D01*
X1241800Y311042D01*
X1241842Y311375D01*
X1242050Y311708D01*
X1242300Y311917D01*
X1242550Y311958D01*
X1242842Y311875D01*
X1243050Y311583D01*
X1243133Y311292D01*
Y310917D01*
G01Y311292D02*
X1243258Y311542D01*
X1243467Y311750D01*
X1243717Y311833D01*
X1243967Y311750D01*
X1244175Y311542D01*
X1244300Y311167D01*
X1244258Y310792D01*
X1244092Y310417D01*
G01X1241800Y313267D02*
X1244300D01*
Y314267D01*
X1244175Y314600D01*
X1243883Y314850D01*
X1243550Y314933D01*
X1243217Y314850D01*
X1242967Y314642D01*
X1242842Y314267D01*
Y313267D01*
G01X1241800Y317200D02*
X1244300D01*
X1243800Y316700D01*
G01X1241800D02*
Y317700D01*
G01X1242175Y319383D02*
X1241967Y319633D01*
X1241842Y319925D01*
X1241800Y320300D01*
X1241883Y320675D01*
X1242050Y320967D01*
X1242342Y321175D01*
X1242675Y321217D01*
X1243008Y321133D01*
X1243217Y320925D01*
X1243383Y320633D01*
X1243425Y320342D01*
X1243383Y320050D01*
X1243217Y319675D01*
X1244300Y319800D01*
Y320925D01*
G01X1248092Y308817D02*
X1248217Y308567D01*
X1248300Y308275D01*
Y307942D01*
X1248175Y307567D01*
X1247967Y307275D01*
X1247717Y307067D01*
X1247300Y306900D01*
X1246925Y306858D01*
X1246550Y306942D01*
X1246300Y307067D01*
X1246050Y307317D01*
X1245883Y307608D01*
X1245800Y307900D01*
Y308192D01*
X1245883Y308483D01*
X1246008Y308733D01*
X1246175Y308942D01*
G01X1246300Y310083D02*
X1246008Y310333D01*
X1245842Y310667D01*
X1245800Y311042D01*
X1245842Y311375D01*
X1246050Y311708D01*
X1246300Y311917D01*
X1246550Y311958D01*
X1246842Y311875D01*
X1247050Y311583D01*
X1247133Y311292D01*
Y310917D01*
G01Y311292D02*
X1247258Y311542D01*
X1247467Y311750D01*
X1247717Y311833D01*
X1247967Y311750D01*
X1248175Y311542D01*
X1248300Y311167D01*
X1248258Y310792D01*
X1248092Y310417D01*
G01X1245800Y313267D02*
X1248300D01*
Y314267D01*
X1248175Y314600D01*
X1247883Y314850D01*
X1247550Y314933D01*
X1247217Y314850D01*
X1246967Y314642D01*
X1246842Y314267D01*
Y313267D01*
G01X1245800Y317200D02*
X1248300D01*
X1247800Y316700D01*
G01X1245800D02*
Y317700D01*
G01Y320217D02*
X1246342Y320300D01*
X1246800Y320425D01*
X1247217Y320592D01*
X1247675Y320800D01*
X1248300Y321133D01*
Y319467D01*
G01X1240079Y292041D02*
X1240204Y291791D01*
X1240287Y291499D01*
Y291166D01*
X1240162Y290791D01*
X1239954Y290499D01*
X1239704Y290291D01*
X1239287Y290124D01*
X1238912Y290082D01*
X1238537Y290166D01*
X1238287Y290291D01*
X1238037Y290541D01*
X1237870Y290832D01*
X1237787Y291124D01*
Y291416D01*
X1237870Y291707D01*
X1237995Y291957D01*
X1238162Y292166D01*
G01X1238287Y293307D02*
X1237995Y293557D01*
X1237829Y293891D01*
X1237787Y294266D01*
X1237829Y294599D01*
X1238037Y294932D01*
X1238287Y295141D01*
X1238537Y295182D01*
X1238829Y295099D01*
X1239037Y294807D01*
X1239120Y294516D01*
Y294141D01*
G01Y294516D02*
X1239245Y294766D01*
X1239454Y294974D01*
X1239704Y295057D01*
X1239954Y294974D01*
X1240162Y294766D01*
X1240287Y294391D01*
X1240245Y294016D01*
X1240079Y293641D01*
G01X1237787Y296491D02*
X1240287D01*
Y297491D01*
X1240162Y297824D01*
X1239870Y298074D01*
X1239537Y298157D01*
X1239204Y298074D01*
X1238954Y297866D01*
X1238829Y297491D01*
Y296491D01*
G01X1237787Y300424D02*
X1240287D01*
X1239787Y299924D01*
G01X1237787D02*
Y300924D01*
G01X1239870Y302732D02*
X1240120Y302982D01*
X1240245Y303274D01*
X1240287Y303607D01*
X1240204Y304024D01*
X1239995Y304316D01*
X1239745Y304399D01*
X1239495Y304357D01*
X1239287Y304191D01*
X1238870Y303357D01*
X1238579Y302982D01*
X1238162Y302732D01*
X1237787Y302649D01*
Y304399D01*
G01X1244079Y292041D02*
X1244204Y291791D01*
X1244287Y291499D01*
Y291166D01*
X1244162Y290791D01*
X1243954Y290499D01*
X1243704Y290291D01*
X1243287Y290124D01*
X1242912Y290082D01*
X1242537Y290166D01*
X1242287Y290291D01*
X1242037Y290541D01*
X1241870Y290832D01*
X1241787Y291124D01*
Y291416D01*
X1241870Y291707D01*
X1241995Y291957D01*
X1242162Y292166D01*
G01X1242287Y293307D02*
X1241995Y293557D01*
X1241829Y293891D01*
X1241787Y294266D01*
X1241829Y294599D01*
X1242037Y294932D01*
X1242287Y295141D01*
X1242537Y295182D01*
X1242829Y295099D01*
X1243037Y294807D01*
X1243120Y294516D01*
Y294141D01*
G01Y294516D02*
X1243245Y294766D01*
X1243454Y294974D01*
X1243704Y295057D01*
X1243954Y294974D01*
X1244162Y294766D01*
X1244287Y294391D01*
X1244245Y294016D01*
X1244079Y293641D01*
G01X1241787Y296491D02*
X1244287D01*
Y297491D01*
X1244162Y297824D01*
X1243870Y298074D01*
X1243537Y298157D01*
X1243204Y298074D01*
X1242954Y297866D01*
X1242829Y297491D01*
Y296491D01*
G01X1241787Y300424D02*
X1244287D01*
X1243787Y299924D01*
G01X1241787D02*
Y300924D01*
G01Y304024D02*
X1244287D01*
X1242495Y302482D01*
Y304566D01*
G01X1248079Y292041D02*
X1248204Y291791D01*
X1248287Y291499D01*
Y291166D01*
X1248162Y290791D01*
X1247954Y290499D01*
X1247704Y290291D01*
X1247287Y290124D01*
X1246912Y290082D01*
X1246537Y290166D01*
X1246287Y290291D01*
X1246037Y290541D01*
X1245870Y290832D01*
X1245787Y291124D01*
Y291416D01*
X1245870Y291707D01*
X1245995Y291957D01*
X1246162Y292166D01*
G01X1246287Y293307D02*
X1245995Y293557D01*
X1245829Y293891D01*
X1245787Y294266D01*
X1245829Y294599D01*
X1246037Y294932D01*
X1246287Y295141D01*
X1246537Y295182D01*
X1246829Y295099D01*
X1247037Y294807D01*
X1247120Y294516D01*
Y294141D01*
G01Y294516D02*
X1247245Y294766D01*
X1247454Y294974D01*
X1247704Y295057D01*
X1247954Y294974D01*
X1248162Y294766D01*
X1248287Y294391D01*
X1248245Y294016D01*
X1248079Y293641D01*
G01X1245787Y296491D02*
X1248287D01*
Y297491D01*
X1248162Y297824D01*
X1247870Y298074D01*
X1247537Y298157D01*
X1247204Y298074D01*
X1246954Y297866D01*
X1246829Y297491D01*
Y296491D01*
G01X1245787Y300424D02*
X1248287D01*
X1247787Y299924D01*
G01X1245787D02*
Y300924D01*
G01X1246829Y302732D02*
X1247120Y303024D01*
X1247287Y303274D01*
X1247370Y303607D01*
X1247287Y303899D01*
X1247120Y304107D01*
X1246870Y304274D01*
X1246579Y304316D01*
X1246329Y304274D01*
X1246079Y304107D01*
X1245870Y303857D01*
X1245787Y303566D01*
X1245870Y303232D01*
X1246120Y302941D01*
X1246495Y302774D01*
X1246912Y302732D01*
X1247454Y302816D01*
X1247745Y302941D01*
X1248037Y303149D01*
X1248245Y303441D01*
X1248287Y303732D01*
X1248204Y304024D01*
X1247995Y304232D01*
G01X1260079Y292041D02*
X1260204Y291791D01*
X1260287Y291499D01*
Y291166D01*
X1260162Y290791D01*
X1259954Y290499D01*
X1259704Y290291D01*
X1259287Y290124D01*
X1258912Y290082D01*
X1258537Y290166D01*
X1258287Y290291D01*
X1258037Y290541D01*
X1257870Y290832D01*
X1257787Y291124D01*
Y291416D01*
X1257870Y291707D01*
X1257995Y291957D01*
X1258162Y292166D01*
G01X1258287Y293307D02*
X1257995Y293557D01*
X1257829Y293891D01*
X1257787Y294266D01*
X1257829Y294599D01*
X1258037Y294932D01*
X1258287Y295141D01*
X1258537Y295182D01*
X1258829Y295099D01*
X1259037Y294807D01*
X1259120Y294516D01*
Y294141D01*
G01Y294516D02*
X1259245Y294766D01*
X1259454Y294974D01*
X1259704Y295057D01*
X1259954Y294974D01*
X1260162Y294766D01*
X1260287Y294391D01*
X1260245Y294016D01*
X1260079Y293641D01*
G01X1257787Y296491D02*
X1260287D01*
Y297491D01*
X1260162Y297824D01*
X1259870Y298074D01*
X1259537Y298157D01*
X1259204Y298074D01*
X1258954Y297866D01*
X1258829Y297491D01*
Y296491D01*
G01X1259870Y299632D02*
X1260120Y299882D01*
X1260245Y300174D01*
X1260287Y300507D01*
X1260204Y300924D01*
X1259995Y301216D01*
X1259745Y301299D01*
X1259495Y301257D01*
X1259287Y301091D01*
X1258870Y300257D01*
X1258579Y299882D01*
X1258162Y299632D01*
X1257787Y299549D01*
Y301299D01*
G01X1259870Y302732D02*
X1260120Y302982D01*
X1260245Y303274D01*
X1260287Y303607D01*
X1260204Y304024D01*
X1259995Y304316D01*
X1259745Y304399D01*
X1259495Y304357D01*
X1259287Y304191D01*
X1258870Y303357D01*
X1258579Y302982D01*
X1258162Y302732D01*
X1257787Y302649D01*
Y304399D01*
G01X1264079Y292041D02*
X1264204Y291791D01*
X1264287Y291499D01*
Y291166D01*
X1264162Y290791D01*
X1263954Y290499D01*
X1263704Y290291D01*
X1263287Y290124D01*
X1262912Y290082D01*
X1262537Y290166D01*
X1262287Y290291D01*
X1262037Y290541D01*
X1261870Y290832D01*
X1261787Y291124D01*
Y291416D01*
X1261870Y291707D01*
X1261995Y291957D01*
X1262162Y292166D01*
G01X1262287Y293307D02*
X1261995Y293557D01*
X1261829Y293891D01*
X1261787Y294266D01*
X1261829Y294599D01*
X1262037Y294932D01*
X1262287Y295141D01*
X1262537Y295182D01*
X1262829Y295099D01*
X1263037Y294807D01*
X1263120Y294516D01*
Y294141D01*
G01Y294516D02*
X1263245Y294766D01*
X1263454Y294974D01*
X1263704Y295057D01*
X1263954Y294974D01*
X1264162Y294766D01*
X1264287Y294391D01*
X1264245Y294016D01*
X1264079Y293641D01*
G01X1261787Y296491D02*
X1264287D01*
Y297491D01*
X1264162Y297824D01*
X1263870Y298074D01*
X1263537Y298157D01*
X1263204Y298074D01*
X1262954Y297866D01*
X1262829Y297491D01*
Y296491D01*
G01X1263870Y299632D02*
X1264120Y299882D01*
X1264245Y300174D01*
X1264287Y300507D01*
X1264204Y300924D01*
X1263995Y301216D01*
X1263745Y301299D01*
X1263495Y301257D01*
X1263287Y301091D01*
X1262870Y300257D01*
X1262579Y299882D01*
X1262162Y299632D01*
X1261787Y299549D01*
Y301299D01*
G01Y304024D02*
X1264287D01*
X1262495Y302482D01*
Y304566D01*
G01X1260092Y308817D02*
X1260217Y308567D01*
X1260300Y308275D01*
Y307942D01*
X1260175Y307567D01*
X1259967Y307275D01*
X1259717Y307067D01*
X1259300Y306900D01*
X1258925Y306858D01*
X1258550Y306942D01*
X1258300Y307067D01*
X1258050Y307317D01*
X1257883Y307608D01*
X1257800Y307900D01*
Y308192D01*
X1257883Y308483D01*
X1258008Y308733D01*
X1258175Y308942D01*
G01X1258300Y310083D02*
X1258008Y310333D01*
X1257842Y310667D01*
X1257800Y311042D01*
X1257842Y311375D01*
X1258050Y311708D01*
X1258300Y311917D01*
X1258550Y311958D01*
X1258842Y311875D01*
X1259050Y311583D01*
X1259133Y311292D01*
Y310917D01*
G01Y311292D02*
X1259258Y311542D01*
X1259467Y311750D01*
X1259717Y311833D01*
X1259967Y311750D01*
X1260175Y311542D01*
X1260300Y311167D01*
X1260258Y310792D01*
X1260092Y310417D01*
G01X1257800Y313267D02*
X1260300D01*
Y314267D01*
X1260175Y314600D01*
X1259883Y314850D01*
X1259550Y314933D01*
X1259217Y314850D01*
X1258967Y314642D01*
X1258842Y314267D01*
Y313267D01*
G01X1259883Y316408D02*
X1260133Y316658D01*
X1260258Y316950D01*
X1260300Y317283D01*
X1260217Y317700D01*
X1260008Y317992D01*
X1259758Y318075D01*
X1259508Y318033D01*
X1259300Y317867D01*
X1258883Y317033D01*
X1258592Y316658D01*
X1258175Y316408D01*
X1257800Y316325D01*
Y318075D01*
G01X1258300Y319383D02*
X1258008Y319633D01*
X1257842Y319967D01*
X1257800Y320342D01*
X1257842Y320675D01*
X1258050Y321008D01*
X1258300Y321217D01*
X1258550Y321258D01*
X1258842Y321175D01*
X1259050Y320883D01*
X1259133Y320592D01*
Y320217D01*
G01Y320592D02*
X1259258Y320842D01*
X1259467Y321050D01*
X1259717Y321133D01*
X1259967Y321050D01*
X1260175Y320842D01*
X1260300Y320467D01*
X1260258Y320092D01*
X1260092Y319717D01*
G01X1264092Y308817D02*
X1264217Y308567D01*
X1264300Y308275D01*
Y307942D01*
X1264175Y307567D01*
X1263967Y307275D01*
X1263717Y307067D01*
X1263300Y306900D01*
X1262925Y306858D01*
X1262550Y306942D01*
X1262300Y307067D01*
X1262050Y307317D01*
X1261883Y307608D01*
X1261800Y307900D01*
Y308192D01*
X1261883Y308483D01*
X1262008Y308733D01*
X1262175Y308942D01*
G01X1262300Y310083D02*
X1262008Y310333D01*
X1261842Y310667D01*
X1261800Y311042D01*
X1261842Y311375D01*
X1262050Y311708D01*
X1262300Y311917D01*
X1262550Y311958D01*
X1262842Y311875D01*
X1263050Y311583D01*
X1263133Y311292D01*
Y310917D01*
G01Y311292D02*
X1263258Y311542D01*
X1263467Y311750D01*
X1263717Y311833D01*
X1263967Y311750D01*
X1264175Y311542D01*
X1264300Y311167D01*
X1264258Y310792D01*
X1264092Y310417D01*
G01X1261800Y313267D02*
X1264300D01*
Y314267D01*
X1264175Y314600D01*
X1263883Y314850D01*
X1263550Y314933D01*
X1263217Y314850D01*
X1262967Y314642D01*
X1262842Y314267D01*
Y313267D01*
G01X1263883Y316408D02*
X1264133Y316658D01*
X1264258Y316950D01*
X1264300Y317283D01*
X1264217Y317700D01*
X1264008Y317992D01*
X1263758Y318075D01*
X1263508Y318033D01*
X1263300Y317867D01*
X1262883Y317033D01*
X1262592Y316658D01*
X1262175Y316408D01*
X1261800Y316325D01*
Y318075D01*
G01X1262175Y319383D02*
X1261967Y319633D01*
X1261842Y319925D01*
X1261800Y320300D01*
X1261883Y320675D01*
X1262050Y320967D01*
X1262342Y321175D01*
X1262675Y321217D01*
X1263008Y321133D01*
X1263217Y320925D01*
X1263383Y320633D01*
X1263425Y320342D01*
X1263383Y320050D01*
X1263217Y319675D01*
X1264300Y319800D01*
Y320925D01*
G01X1252092Y308817D02*
X1252217Y308567D01*
X1252300Y308275D01*
Y307942D01*
X1252175Y307567D01*
X1251967Y307275D01*
X1251717Y307067D01*
X1251300Y306900D01*
X1250925Y306858D01*
X1250550Y306942D01*
X1250300Y307067D01*
X1250050Y307317D01*
X1249883Y307608D01*
X1249800Y307900D01*
Y308192D01*
X1249883Y308483D01*
X1250008Y308733D01*
X1250175Y308942D01*
G01X1250300Y310083D02*
X1250008Y310333D01*
X1249842Y310667D01*
X1249800Y311042D01*
X1249842Y311375D01*
X1250050Y311708D01*
X1250300Y311917D01*
X1250550Y311958D01*
X1250842Y311875D01*
X1251050Y311583D01*
X1251133Y311292D01*
Y310917D01*
G01Y311292D02*
X1251258Y311542D01*
X1251467Y311750D01*
X1251717Y311833D01*
X1251967Y311750D01*
X1252175Y311542D01*
X1252300Y311167D01*
X1252258Y310792D01*
X1252092Y310417D01*
G01X1249800Y313267D02*
X1252300D01*
Y314267D01*
X1252175Y314600D01*
X1251883Y314850D01*
X1251550Y314933D01*
X1251217Y314850D01*
X1250967Y314642D01*
X1250842Y314267D01*
Y313267D01*
G01X1249800Y317200D02*
X1252300D01*
X1251800Y316700D01*
G01X1249800D02*
Y317700D01*
G01Y320300D02*
X1249842Y320592D01*
X1249967Y320925D01*
X1250175Y321133D01*
X1250467Y321217D01*
X1250758Y321133D01*
X1251008Y320883D01*
X1251133Y320508D01*
Y320092D01*
X1251217Y319842D01*
X1251425Y319633D01*
X1251717Y319550D01*
X1252008Y319675D01*
X1252217Y319967D01*
X1252300Y320300D01*
X1252217Y320633D01*
X1252008Y320925D01*
X1251717Y321050D01*
X1251425Y320967D01*
X1251217Y320758D01*
X1251133Y320508D01*
Y320092D01*
X1251008Y319717D01*
X1250758Y319467D01*
X1250467Y319383D01*
X1250175Y319467D01*
X1249967Y319675D01*
X1249842Y320008D01*
X1249800Y320300D01*
G01X1236092Y308817D02*
X1236217Y308567D01*
X1236300Y308275D01*
Y307942D01*
X1236175Y307567D01*
X1235967Y307275D01*
X1235717Y307067D01*
X1235300Y306900D01*
X1234925Y306858D01*
X1234550Y306942D01*
X1234300Y307067D01*
X1234050Y307317D01*
X1233883Y307608D01*
X1233800Y307900D01*
Y308192D01*
X1233883Y308483D01*
X1234008Y308733D01*
X1234175Y308942D01*
G01X1234300Y310083D02*
X1234008Y310333D01*
X1233842Y310667D01*
X1233800Y311042D01*
X1233842Y311375D01*
X1234050Y311708D01*
X1234300Y311917D01*
X1234550Y311958D01*
X1234842Y311875D01*
X1235050Y311583D01*
X1235133Y311292D01*
Y310917D01*
G01Y311292D02*
X1235258Y311542D01*
X1235467Y311750D01*
X1235717Y311833D01*
X1235967Y311750D01*
X1236175Y311542D01*
X1236300Y311167D01*
X1236258Y310792D01*
X1236092Y310417D01*
G01X1233800Y313267D02*
X1236300D01*
Y314267D01*
X1236175Y314600D01*
X1235883Y314850D01*
X1235550Y314933D01*
X1235217Y314850D01*
X1234967Y314642D01*
X1234842Y314267D01*
Y313267D01*
G01X1233800Y317200D02*
X1236300D01*
X1235800Y316700D01*
G01X1233800D02*
Y317700D01*
G01Y320300D02*
X1236300D01*
X1235800Y319800D01*
G01X1233800D02*
Y320800D01*
G01X1236079Y292041D02*
X1236204Y291791D01*
X1236287Y291499D01*
Y291166D01*
X1236162Y290791D01*
X1235954Y290499D01*
X1235704Y290291D01*
X1235287Y290124D01*
X1234912Y290082D01*
X1234537Y290166D01*
X1234287Y290291D01*
X1234037Y290541D01*
X1233870Y290832D01*
X1233787Y291124D01*
Y291416D01*
X1233870Y291707D01*
X1233995Y291957D01*
X1234162Y292166D01*
G01X1234287Y293307D02*
X1233995Y293557D01*
X1233829Y293891D01*
X1233787Y294266D01*
X1233829Y294599D01*
X1234037Y294932D01*
X1234287Y295141D01*
X1234537Y295182D01*
X1234829Y295099D01*
X1235037Y294807D01*
X1235120Y294516D01*
Y294141D01*
G01Y294516D02*
X1235245Y294766D01*
X1235454Y294974D01*
X1235704Y295057D01*
X1235954Y294974D01*
X1236162Y294766D01*
X1236287Y294391D01*
X1236245Y294016D01*
X1236079Y293641D01*
G01X1233787Y296491D02*
X1236287D01*
Y297491D01*
X1236162Y297824D01*
X1235870Y298074D01*
X1235537Y298157D01*
X1235204Y298074D01*
X1234954Y297866D01*
X1234829Y297491D01*
Y296491D01*
G01X1233787Y300424D02*
X1236287D01*
X1235787Y299924D01*
G01X1233787D02*
Y300924D01*
G01X1236287Y303524D02*
X1236204Y303191D01*
X1235995Y302941D01*
X1235745Y302774D01*
X1235412Y302649D01*
X1235037Y302607D01*
X1234662Y302649D01*
X1234329Y302774D01*
X1234079Y302941D01*
X1233870Y303191D01*
X1233787Y303524D01*
X1233870Y303857D01*
X1234079Y304107D01*
X1234329Y304274D01*
X1234662Y304399D01*
X1235037Y304441D01*
X1235412Y304399D01*
X1235745Y304274D01*
X1235995Y304107D01*
X1236204Y303857D01*
X1236287Y303524D01*
G01X1243111Y403104D02*
X1243236Y402854D01*
X1243319Y402562D01*
Y402229D01*
X1243194Y401854D01*
X1242986Y401562D01*
X1242736Y401354D01*
X1242319Y401187D01*
X1241944Y401145D01*
X1241569Y401229D01*
X1241319Y401354D01*
X1241069Y401604D01*
X1240902Y401895D01*
X1240819Y402187D01*
Y402479D01*
X1240902Y402770D01*
X1241027Y403020D01*
X1241194Y403229D01*
G01X1242902Y404495D02*
X1243152Y404745D01*
X1243277Y405037D01*
X1243319Y405370D01*
X1243236Y405787D01*
X1243027Y406079D01*
X1242777Y406162D01*
X1242527Y406120D01*
X1242319Y405954D01*
X1241902Y405120D01*
X1241611Y404745D01*
X1241194Y404495D01*
X1240819Y404412D01*
Y406162D01*
G01Y407429D02*
X1243319D01*
X1240819Y409345D01*
X1243319D01*
G01X1240819Y411487D02*
X1243319D01*
X1242819Y410987D01*
G01X1240819D02*
Y411987D01*
G01X1241319Y413670D02*
X1241027Y413920D01*
X1240861Y414254D01*
X1240819Y414629D01*
X1240861Y414962D01*
X1241069Y415295D01*
X1241319Y415504D01*
X1241569Y415545D01*
X1241861Y415462D01*
X1242069Y415170D01*
X1242152Y414879D01*
Y414504D01*
G01Y414879D02*
X1242277Y415129D01*
X1242486Y415337D01*
X1242736Y415420D01*
X1242986Y415337D01*
X1243194Y415129D01*
X1243319Y414754D01*
X1243277Y414379D01*
X1243111Y414004D01*
G01X1237197Y399807D02*
X1237322Y399557D01*
X1237405Y399265D01*
Y398932D01*
X1237280Y398557D01*
X1237072Y398265D01*
X1236822Y398057D01*
X1236405Y397890D01*
X1236030Y397848D01*
X1235655Y397932D01*
X1235405Y398057D01*
X1235155Y398307D01*
X1234988Y398598D01*
X1234905Y398890D01*
Y399182D01*
X1234988Y399473D01*
X1235113Y399723D01*
X1235280Y399932D01*
G01X1236988Y401198D02*
X1237238Y401448D01*
X1237363Y401740D01*
X1237405Y402073D01*
X1237322Y402490D01*
X1237113Y402782D01*
X1236863Y402865D01*
X1236613Y402823D01*
X1236405Y402657D01*
X1235988Y401823D01*
X1235697Y401448D01*
X1235280Y401198D01*
X1234905Y401115D01*
Y402865D01*
G01Y404132D02*
X1237405D01*
X1234905Y406048D01*
X1237405D01*
G01X1234905Y408190D02*
X1237405D01*
X1236905Y407690D01*
G01X1234905D02*
Y408690D01*
G01Y411290D02*
X1234947Y411582D01*
X1235072Y411915D01*
X1235280Y412123D01*
X1235572Y412207D01*
X1235863Y412123D01*
X1236113Y411873D01*
X1236238Y411498D01*
Y411082D01*
X1236322Y410832D01*
X1236530Y410623D01*
X1236822Y410540D01*
X1237113Y410665D01*
X1237322Y410957D01*
X1237405Y411290D01*
X1237322Y411623D01*
X1237113Y411915D01*
X1236822Y412040D01*
X1236530Y411957D01*
X1236322Y411748D01*
X1236238Y411498D01*
Y411082D01*
X1236113Y410707D01*
X1235863Y410457D01*
X1235572Y410373D01*
X1235280Y410457D01*
X1235072Y410665D01*
X1234947Y410998D01*
X1234905Y411290D01*
G01X1232457Y391488D02*
X1232707Y391613D01*
X1232999Y391696D01*
X1233332D01*
X1233707Y391571D01*
X1233999Y391363D01*
X1234207Y391113D01*
X1234374Y390696D01*
X1234416Y390321D01*
X1234332Y389946D01*
X1234207Y389696D01*
X1233957Y389446D01*
X1233666Y389279D01*
X1233374Y389196D01*
X1233082D01*
X1232791Y389279D01*
X1232541Y389404D01*
X1232332Y389571D01*
G01X1231066Y391279D02*
X1230816Y391529D01*
X1230524Y391654D01*
X1230191Y391696D01*
X1229774Y391613D01*
X1229482Y391404D01*
X1229399Y391154D01*
X1229441Y390904D01*
X1229607Y390696D01*
X1230441Y390279D01*
X1230816Y389988D01*
X1231066Y389571D01*
X1231149Y389196D01*
X1229399D01*
G01X1228132D02*
Y391696D01*
X1226216Y389196D01*
Y391696D01*
G01X1224866Y391279D02*
X1224616Y391529D01*
X1224324Y391654D01*
X1223991Y391696D01*
X1223574Y391613D01*
X1223282Y391404D01*
X1223199Y391154D01*
X1223241Y390904D01*
X1223407Y390696D01*
X1224241Y390279D01*
X1224616Y389988D01*
X1224866Y389571D01*
X1224949Y389196D01*
X1223199D01*
G01X1221891Y389571D02*
X1221641Y389363D01*
X1221349Y389238D01*
X1220974Y389196D01*
X1220599Y389279D01*
X1220307Y389446D01*
X1220099Y389738D01*
X1220057Y390071D01*
X1220141Y390404D01*
X1220349Y390613D01*
X1220641Y390779D01*
X1220932Y390821D01*
X1221224Y390779D01*
X1221599Y390613D01*
X1221474Y391696D01*
X1220349D01*
G01X1244676Y400426D02*
X1244764Y400692D01*
X1244911Y400957D01*
X1245147Y401192D01*
X1245501Y401369D01*
X1245854Y401428D01*
X1246178Y401399D01*
X1246591Y401222D01*
X1246885Y400986D01*
X1247091Y400662D01*
X1247180Y400397D01*
Y400043D01*
X1247091Y399719D01*
X1246944Y399454D01*
X1246738Y399248D01*
X1246473Y399101D01*
X1246208Y399012D01*
X1245942Y398983D01*
G01X1243839Y399295D02*
X1243485D01*
X1243191Y399177D01*
X1242925Y398971D01*
X1242690Y398617D01*
X1242631Y398264D01*
X1242749Y398028D01*
X1242955Y397881D01*
X1243220Y397851D01*
X1244104Y398146D01*
X1244575Y398205D01*
X1245047Y398087D01*
X1245371Y397881D01*
X1244133Y396643D01*
G01X1243238Y395748D02*
X1241470Y397516D01*
X1241882Y394392D01*
X1240115Y396160D01*
G01X1240368Y392878D02*
X1238600Y394646D01*
X1239307D01*
G01X1240722Y393232D02*
X1240015Y392525D01*
G01X1238471Y391393D02*
X1238412Y391040D01*
X1238235Y390745D01*
X1237940Y390568D01*
X1237557Y390539D01*
X1237145Y390657D01*
X1236821Y390863D01*
X1236497Y391187D01*
X1236290Y391511D01*
X1236202Y391894D01*
X1236261Y392189D01*
X1236408Y392454D01*
X1236703Y392631D01*
X1236998Y392690D01*
X1237292Y392631D01*
X1237587Y392454D01*
X1237734Y392189D01*
X1237793Y391835D01*
X1237734Y391540D01*
X1237557Y391305D01*
X1237263Y391128D01*
X1236939Y391099D01*
X1236497Y391187D01*
G01X1223649Y442185D02*
X1226149D01*
Y443226D01*
X1226024Y443560D01*
X1225857Y443768D01*
X1225524Y443851D01*
X1225191Y443768D01*
X1224982Y443518D01*
X1224857Y443226D01*
Y442185D01*
G01Y443226D02*
X1223649Y443851D01*
G01X1225732Y445326D02*
X1225982Y445576D01*
X1226107Y445868D01*
X1226149Y446201D01*
X1226066Y446618D01*
X1225857Y446910D01*
X1225607Y446993D01*
X1225357Y446951D01*
X1225149Y446785D01*
X1224732Y445951D01*
X1224441Y445576D01*
X1224024Y445326D01*
X1223649Y445243D01*
Y446993D01*
G01Y448135D02*
X1226149D01*
X1224066Y449218D01*
X1226149Y450301D01*
X1223649D01*
G01X1224691Y451526D02*
X1224982Y451818D01*
X1225149Y452068D01*
X1225232Y452401D01*
X1225149Y452693D01*
X1224982Y452901D01*
X1224732Y453068D01*
X1224441Y453110D01*
X1224191Y453068D01*
X1223941Y452901D01*
X1223732Y452651D01*
X1223649Y452360D01*
X1223732Y452026D01*
X1223982Y451735D01*
X1224357Y451568D01*
X1224774Y451526D01*
X1225316Y451610D01*
X1225607Y451735D01*
X1225899Y451943D01*
X1226107Y452235D01*
X1226149Y452526D01*
X1226066Y452818D01*
X1225857Y453026D01*
G01X1244806Y417783D02*
X1247306D01*
Y418824D01*
X1247181Y419158D01*
X1247014Y419366D01*
X1246681Y419449D01*
X1246348Y419366D01*
X1246139Y419116D01*
X1246014Y418824D01*
Y417783D01*
G01Y418824D02*
X1244806Y419449D01*
G01X1246889Y420924D02*
X1247139Y421174D01*
X1247264Y421466D01*
X1247306Y421799D01*
X1247223Y422216D01*
X1247014Y422508D01*
X1246764Y422591D01*
X1246514Y422549D01*
X1246306Y422383D01*
X1245889Y421549D01*
X1245598Y421174D01*
X1245181Y420924D01*
X1244806Y420841D01*
Y422591D01*
G01Y423858D02*
X1247306D01*
X1244806Y425774D01*
X1247306D01*
G01X1244806Y428416D02*
X1247306D01*
X1245514Y426874D01*
Y428958D01*
G01X1246069Y443617D02*
X1246319Y443742D01*
X1246611Y443825D01*
X1246944D01*
X1247319Y443700D01*
X1247611Y443492D01*
X1247819Y443242D01*
X1247986Y442825D01*
X1248028Y442450D01*
X1247944Y442075D01*
X1247819Y441825D01*
X1247569Y441575D01*
X1247278Y441408D01*
X1246986Y441325D01*
X1246694D01*
X1246403Y441408D01*
X1246153Y441533D01*
X1245944Y441700D01*
G01X1244678Y443408D02*
X1244428Y443658D01*
X1244136Y443783D01*
X1243803Y443825D01*
X1243386Y443742D01*
X1243094Y443533D01*
X1243011Y443283D01*
X1243053Y443033D01*
X1243219Y442825D01*
X1244053Y442408D01*
X1244428Y442117D01*
X1244678Y441700D01*
X1244761Y441325D01*
X1243011D01*
G01X1241744D02*
Y443825D01*
X1239828Y441325D01*
Y443825D01*
G01X1237769Y441325D02*
X1237686Y441867D01*
X1237561Y442325D01*
X1237394Y442742D01*
X1237186Y443200D01*
X1236853Y443825D01*
X1238519D01*
G01X1239098Y419533D02*
X1239223Y419283D01*
X1239306Y418991D01*
Y418658D01*
X1239181Y418283D01*
X1238973Y417991D01*
X1238723Y417783D01*
X1238306Y417616D01*
X1237931Y417574D01*
X1237556Y417658D01*
X1237306Y417783D01*
X1237056Y418033D01*
X1236889Y418324D01*
X1236806Y418616D01*
Y418908D01*
X1236889Y419199D01*
X1237014Y419449D01*
X1237181Y419658D01*
G01X1238889Y420924D02*
X1239139Y421174D01*
X1239264Y421466D01*
X1239306Y421799D01*
X1239223Y422216D01*
X1239014Y422508D01*
X1238764Y422591D01*
X1238514Y422549D01*
X1238306Y422383D01*
X1237889Y421549D01*
X1237598Y421174D01*
X1237181Y420924D01*
X1236806Y420841D01*
Y422591D01*
G01Y423858D02*
X1239306D01*
X1236806Y425774D01*
X1239306D01*
G01X1236806Y427916D02*
X1239306D01*
X1238806Y427416D01*
G01X1236806D02*
Y428416D01*
G01X1238889Y430224D02*
X1239139Y430474D01*
X1239264Y430766D01*
X1239306Y431099D01*
X1239223Y431516D01*
X1239014Y431808D01*
X1238764Y431891D01*
X1238514Y431849D01*
X1238306Y431683D01*
X1237889Y430849D01*
X1237598Y430474D01*
X1237181Y430224D01*
X1236806Y430141D01*
Y431891D01*
G01X1245695Y435369D02*
X1245945Y435494D01*
X1246237Y435577D01*
X1246570D01*
X1246945Y435452D01*
X1247237Y435244D01*
X1247445Y434994D01*
X1247612Y434577D01*
X1247654Y434202D01*
X1247570Y433827D01*
X1247445Y433577D01*
X1247195Y433327D01*
X1246904Y433160D01*
X1246612Y433077D01*
X1246320D01*
X1246029Y433160D01*
X1245779Y433285D01*
X1245570Y433452D01*
G01X1244304Y435160D02*
X1244054Y435410D01*
X1243762Y435535D01*
X1243429Y435577D01*
X1243012Y435494D01*
X1242720Y435285D01*
X1242637Y435035D01*
X1242679Y434785D01*
X1242845Y434577D01*
X1243679Y434160D01*
X1244054Y433869D01*
X1244304Y433452D01*
X1244387Y433077D01*
X1242637D01*
G01X1241370D02*
Y435577D01*
X1239454Y433077D01*
Y435577D01*
G01X1237312Y433077D02*
Y435577D01*
X1237812Y435077D01*
G01Y433077D02*
X1236812D01*
G01X1234212D02*
Y435577D01*
X1234712Y435077D01*
G01Y433077D02*
X1233712D01*
G01X1243098Y419533D02*
X1243223Y419283D01*
X1243306Y418991D01*
Y418658D01*
X1243181Y418283D01*
X1242973Y417991D01*
X1242723Y417783D01*
X1242306Y417616D01*
X1241931Y417574D01*
X1241556Y417658D01*
X1241306Y417783D01*
X1241056Y418033D01*
X1240889Y418324D01*
X1240806Y418616D01*
Y418908D01*
X1240889Y419199D01*
X1241014Y419449D01*
X1241181Y419658D01*
G01X1242889Y420924D02*
X1243139Y421174D01*
X1243264Y421466D01*
X1243306Y421799D01*
X1243223Y422216D01*
X1243014Y422508D01*
X1242764Y422591D01*
X1242514Y422549D01*
X1242306Y422383D01*
X1241889Y421549D01*
X1241598Y421174D01*
X1241181Y420924D01*
X1240806Y420841D01*
Y422591D01*
G01Y423858D02*
X1243306D01*
X1240806Y425774D01*
X1243306D01*
G01X1240806Y427916D02*
X1243306D01*
X1242806Y427416D01*
G01X1240806D02*
Y428416D01*
G01X1241181Y430099D02*
X1240973Y430349D01*
X1240848Y430641D01*
X1240806Y431016D01*
X1240889Y431391D01*
X1241056Y431683D01*
X1241348Y431891D01*
X1241681Y431933D01*
X1242014Y431849D01*
X1242223Y431641D01*
X1242389Y431349D01*
X1242431Y431058D01*
X1242389Y430766D01*
X1242223Y430391D01*
X1243306Y430516D01*
Y431641D01*
G01X1235098Y419533D02*
X1235223Y419283D01*
X1235306Y418991D01*
Y418658D01*
X1235181Y418283D01*
X1234973Y417991D01*
X1234723Y417783D01*
X1234306Y417616D01*
X1233931Y417574D01*
X1233556Y417658D01*
X1233306Y417783D01*
X1233056Y418033D01*
X1232889Y418324D01*
X1232806Y418616D01*
Y418908D01*
X1232889Y419199D01*
X1233014Y419449D01*
X1233181Y419658D01*
G01X1234889Y420924D02*
X1235139Y421174D01*
X1235264Y421466D01*
X1235306Y421799D01*
X1235223Y422216D01*
X1235014Y422508D01*
X1234764Y422591D01*
X1234514Y422549D01*
X1234306Y422383D01*
X1233889Y421549D01*
X1233598Y421174D01*
X1233181Y420924D01*
X1232806Y420841D01*
Y422591D01*
G01Y423858D02*
X1235306D01*
X1232806Y425774D01*
X1235306D01*
G01X1232806Y427916D02*
X1235306D01*
X1234806Y427416D01*
G01X1232806D02*
Y428416D01*
G01X1233848Y430224D02*
X1234139Y430516D01*
X1234306Y430766D01*
X1234389Y431099D01*
X1234306Y431391D01*
X1234139Y431599D01*
X1233889Y431766D01*
X1233598Y431808D01*
X1233348Y431766D01*
X1233098Y431599D01*
X1232889Y431349D01*
X1232806Y431058D01*
X1232889Y430724D01*
X1233139Y430433D01*
X1233514Y430266D01*
X1233931Y430224D01*
X1234473Y430308D01*
X1234764Y430433D01*
X1235056Y430641D01*
X1235264Y430933D01*
X1235306Y431224D01*
X1235223Y431516D01*
X1235014Y431724D01*
G01X1245695Y439369D02*
X1245945Y439494D01*
X1246237Y439577D01*
X1246570D01*
X1246945Y439452D01*
X1247237Y439244D01*
X1247445Y438994D01*
X1247612Y438577D01*
X1247654Y438202D01*
X1247570Y437827D01*
X1247445Y437577D01*
X1247195Y437327D01*
X1246904Y437160D01*
X1246612Y437077D01*
X1246320D01*
X1246029Y437160D01*
X1245779Y437285D01*
X1245570Y437452D01*
G01X1244304Y439160D02*
X1244054Y439410D01*
X1243762Y439535D01*
X1243429Y439577D01*
X1243012Y439494D01*
X1242720Y439285D01*
X1242637Y439035D01*
X1242679Y438785D01*
X1242845Y438577D01*
X1243679Y438160D01*
X1244054Y437869D01*
X1244304Y437452D01*
X1244387Y437077D01*
X1242637D01*
G01X1241370D02*
Y439577D01*
X1239454Y437077D01*
Y439577D01*
G01X1238020Y437369D02*
X1237729Y437160D01*
X1237395Y437077D01*
X1237062Y437160D01*
X1236770Y437410D01*
X1236562Y437785D01*
X1236479Y438160D01*
Y438619D01*
X1236562Y438994D01*
X1236770Y439327D01*
X1237020Y439494D01*
X1237312Y439577D01*
X1237645Y439494D01*
X1237895Y439327D01*
X1238062Y439077D01*
X1238145Y438744D01*
X1238062Y438452D01*
X1237854Y438160D01*
X1237604Y437994D01*
X1237312Y437952D01*
X1236979Y438035D01*
X1236729Y438244D01*
X1236479Y438619D01*
G01X1230418Y438653D02*
X1230668Y438778D01*
X1230960Y438861D01*
X1231293D01*
X1231668Y438736D01*
X1231960Y438528D01*
X1232168Y438278D01*
X1232335Y437861D01*
X1232377Y437486D01*
X1232293Y437111D01*
X1232168Y436861D01*
X1231918Y436611D01*
X1231627Y436444D01*
X1231335Y436361D01*
X1231043D01*
X1230752Y436444D01*
X1230502Y436569D01*
X1230293Y436736D01*
G01X1229027Y438444D02*
X1228777Y438694D01*
X1228485Y438819D01*
X1228152Y438861D01*
X1227735Y438778D01*
X1227443Y438569D01*
X1227360Y438319D01*
X1227402Y438069D01*
X1227568Y437861D01*
X1228402Y437444D01*
X1228777Y437153D01*
X1229027Y436736D01*
X1229110Y436361D01*
X1227360D01*
G01X1226093D02*
Y438861D01*
X1224177Y436361D01*
Y438861D01*
G01X1222035Y436361D02*
X1221743Y436403D01*
X1221410Y436528D01*
X1221202Y436736D01*
X1221118Y437028D01*
X1221202Y437319D01*
X1221452Y437569D01*
X1221827Y437694D01*
X1222243D01*
X1222493Y437778D01*
X1222702Y437986D01*
X1222785Y438278D01*
X1222660Y438569D01*
X1222368Y438778D01*
X1222035Y438861D01*
X1221702Y438778D01*
X1221410Y438569D01*
X1221285Y438278D01*
X1221368Y437986D01*
X1221577Y437778D01*
X1221827Y437694D01*
X1222243D01*
X1222618Y437569D01*
X1222868Y437319D01*
X1222952Y437028D01*
X1222868Y436736D01*
X1222660Y436528D01*
X1222327Y436403D01*
X1222035Y436361D01*
G01X1242819Y472769D02*
Y475269D01*
X1241778D01*
X1241444Y475144D01*
X1241236Y474977D01*
X1241153Y474644D01*
X1241236Y474311D01*
X1241486Y474102D01*
X1241778Y473977D01*
X1242819D01*
G01X1241778D02*
X1241153Y472769D01*
G01X1239803Y473269D02*
X1239553Y472977D01*
X1239219Y472811D01*
X1238844Y472769D01*
X1238511Y472811D01*
X1238178Y473019D01*
X1237969Y473269D01*
X1237928Y473519D01*
X1238011Y473811D01*
X1238303Y474019D01*
X1238594Y474102D01*
X1238969D01*
G01X1238594D02*
X1238344Y474227D01*
X1238136Y474436D01*
X1238053Y474686D01*
X1238136Y474936D01*
X1238344Y475144D01*
X1238719Y475269D01*
X1239094Y475227D01*
X1239469Y475061D01*
G01X1236619Y472769D02*
Y475269D01*
X1235578D01*
X1235244Y475144D01*
X1235036Y474977D01*
X1234953Y474644D01*
X1235036Y474311D01*
X1235286Y474102D01*
X1235578Y473977D01*
X1236619D01*
G01X1235578D02*
X1234953Y472769D01*
G01X1232686D02*
Y475269D01*
X1233186Y474769D01*
G01Y472769D02*
X1232186D01*
G01X1230378Y474852D02*
X1230128Y475102D01*
X1229836Y475227D01*
X1229503Y475269D01*
X1229086Y475186D01*
X1228794Y474977D01*
X1228711Y474727D01*
X1228753Y474477D01*
X1228919Y474269D01*
X1229753Y473852D01*
X1230128Y473561D01*
X1230378Y473144D01*
X1230461Y472769D01*
X1228711D01*
G01X1243839Y482245D02*
X1246339D01*
Y483286D01*
X1246214Y483620D01*
X1246047Y483828D01*
X1245714Y483911D01*
X1245381Y483828D01*
X1245172Y483578D01*
X1245047Y483286D01*
Y482245D01*
G01Y483286D02*
X1243839Y483911D01*
G01X1244339Y485261D02*
X1244047Y485511D01*
X1243881Y485845D01*
X1243839Y486220D01*
X1243881Y486553D01*
X1244089Y486886D01*
X1244339Y487095D01*
X1244589Y487136D01*
X1244881Y487053D01*
X1245089Y486761D01*
X1245172Y486470D01*
Y486095D01*
G01Y486470D02*
X1245297Y486720D01*
X1245506Y486928D01*
X1245756Y487011D01*
X1246006Y486928D01*
X1246214Y486720D01*
X1246339Y486345D01*
X1246297Y485970D01*
X1246131Y485595D01*
G01X1243839Y488445D02*
X1246339D01*
Y489486D01*
X1246214Y489820D01*
X1246047Y490028D01*
X1245714Y490111D01*
X1245381Y490028D01*
X1245172Y489778D01*
X1245047Y489486D01*
Y488445D01*
G01Y489486D02*
X1243839Y490111D01*
G01Y492378D02*
X1243881Y492670D01*
X1244006Y493003D01*
X1244214Y493211D01*
X1244506Y493295D01*
X1244797Y493211D01*
X1245047Y492961D01*
X1245172Y492586D01*
Y492170D01*
X1245256Y491920D01*
X1245464Y491711D01*
X1245756Y491628D01*
X1246047Y491753D01*
X1246256Y492045D01*
X1246339Y492378D01*
X1246256Y492711D01*
X1246047Y493003D01*
X1245756Y493128D01*
X1245464Y493045D01*
X1245256Y492836D01*
X1245172Y492586D01*
Y492170D01*
X1245047Y491795D01*
X1244797Y491545D01*
X1244506Y491461D01*
X1244214Y491545D01*
X1244006Y491753D01*
X1243881Y492086D01*
X1243839Y492378D01*
G01X1258709Y489034D02*
X1261209D01*
Y490075D01*
X1261084Y490409D01*
X1260917Y490617D01*
X1260584Y490700D01*
X1260251Y490617D01*
X1260042Y490367D01*
X1259917Y490075D01*
Y489034D01*
G01Y490075D02*
X1258709Y490700D01*
G01X1259209Y492050D02*
X1258917Y492300D01*
X1258751Y492634D01*
X1258709Y493009D01*
X1258751Y493342D01*
X1258959Y493675D01*
X1259209Y493884D01*
X1259459Y493925D01*
X1259751Y493842D01*
X1259959Y493550D01*
X1260042Y493259D01*
Y492884D01*
G01Y493259D02*
X1260167Y493509D01*
X1260376Y493717D01*
X1260626Y493800D01*
X1260876Y493717D01*
X1261084Y493509D01*
X1261209Y493134D01*
X1261167Y492759D01*
X1261001Y492384D01*
G01X1258709Y495234D02*
X1261209D01*
Y496275D01*
X1261084Y496609D01*
X1260917Y496817D01*
X1260584Y496900D01*
X1260251Y496817D01*
X1260042Y496567D01*
X1259917Y496275D01*
Y495234D01*
G01Y496275D02*
X1258709Y496900D01*
G01X1259084Y498250D02*
X1258876Y498500D01*
X1258751Y498792D01*
X1258709Y499167D01*
X1258792Y499542D01*
X1258959Y499834D01*
X1259251Y500042D01*
X1259584Y500084D01*
X1259917Y500000D01*
X1260126Y499792D01*
X1260292Y499500D01*
X1260334Y499209D01*
X1260292Y498917D01*
X1260126Y498542D01*
X1261209Y498667D01*
Y499792D01*
G01X1242469Y476169D02*
Y478669D01*
X1241428D01*
X1241094Y478544D01*
X1240886Y478377D01*
X1240803Y478044D01*
X1240886Y477711D01*
X1241136Y477502D01*
X1241428Y477377D01*
X1242469D01*
G01X1241428D02*
X1240803Y476169D01*
G01X1239453Y476669D02*
X1239203Y476377D01*
X1238869Y476211D01*
X1238494Y476169D01*
X1238161Y476211D01*
X1237828Y476419D01*
X1237619Y476669D01*
X1237578Y476919D01*
X1237661Y477211D01*
X1237953Y477419D01*
X1238244Y477502D01*
X1238619D01*
G01X1238244D02*
X1237994Y477627D01*
X1237786Y477836D01*
X1237703Y478086D01*
X1237786Y478336D01*
X1237994Y478544D01*
X1238369Y478669D01*
X1238744Y478627D01*
X1239119Y478461D01*
G01X1236269Y476169D02*
Y478669D01*
X1235228D01*
X1234894Y478544D01*
X1234686Y478377D01*
X1234603Y478044D01*
X1234686Y477711D01*
X1234936Y477502D01*
X1235228Y477377D01*
X1236269D01*
G01X1235228D02*
X1234603Y476169D01*
G01X1233044Y476461D02*
X1232753Y476252D01*
X1232419Y476169D01*
X1232086Y476252D01*
X1231794Y476502D01*
X1231586Y476877D01*
X1231503Y477252D01*
Y477711D01*
X1231586Y478086D01*
X1231794Y478419D01*
X1232044Y478586D01*
X1232336Y478669D01*
X1232669Y478586D01*
X1232919Y478419D01*
X1233086Y478169D01*
X1233169Y477836D01*
X1233086Y477544D01*
X1232878Y477252D01*
X1232628Y477086D01*
X1232336Y477044D01*
X1232003Y477127D01*
X1231753Y477336D01*
X1231503Y477711D01*
G01X1289033Y493582D02*
X1289283Y493707D01*
X1289575Y493790D01*
X1289908D01*
X1290283Y493665D01*
X1290575Y493457D01*
X1290783Y493207D01*
X1290950Y492790D01*
X1290992Y492415D01*
X1290908Y492040D01*
X1290783Y491790D01*
X1290533Y491540D01*
X1290242Y491373D01*
X1289950Y491290D01*
X1289658D01*
X1289367Y491373D01*
X1289117Y491498D01*
X1288908Y491665D01*
G01X1286933Y491290D02*
X1286850Y491832D01*
X1286725Y492290D01*
X1286558Y492707D01*
X1286350Y493165D01*
X1286017Y493790D01*
X1287683D01*
G01X1282917Y491290D02*
X1284583D01*
Y493790D01*
X1282917D01*
G01X1283583Y492582D02*
X1284583D01*
G01X1280650Y491290D02*
Y493790D01*
X1281150Y493290D01*
G01Y491290D02*
X1280150D01*
G01X1275569Y490739D02*
X1275819Y490864D01*
X1276111Y490947D01*
X1276444D01*
X1276819Y490822D01*
X1277111Y490614D01*
X1277319Y490364D01*
X1277486Y489947D01*
X1277528Y489572D01*
X1277444Y489197D01*
X1277319Y488947D01*
X1277069Y488697D01*
X1276778Y488530D01*
X1276486Y488447D01*
X1276194D01*
X1275903Y488530D01*
X1275653Y488655D01*
X1275444Y488822D01*
G01X1273469Y488447D02*
X1273386Y488989D01*
X1273261Y489447D01*
X1273094Y489864D01*
X1272886Y490322D01*
X1272553Y490947D01*
X1274219D01*
G01X1269453Y488447D02*
X1271119D01*
Y490947D01*
X1269453D01*
G01X1270119Y489739D02*
X1271119D01*
G01X1267978Y490530D02*
X1267728Y490780D01*
X1267436Y490905D01*
X1267103Y490947D01*
X1266686Y490864D01*
X1266394Y490655D01*
X1266311Y490405D01*
X1266353Y490155D01*
X1266519Y489947D01*
X1267353Y489530D01*
X1267728Y489239D01*
X1267978Y488822D01*
X1268061Y488447D01*
X1266311D01*
G01X1289897Y472490D02*
Y470698D01*
X1289730Y470323D01*
X1289397Y470073D01*
X1288980Y469990D01*
X1288563Y470073D01*
X1288230Y470323D01*
X1288063Y470698D01*
Y472490D01*
G01X1285963Y469990D02*
X1285880Y470532D01*
X1285755Y470990D01*
X1285588Y471407D01*
X1285380Y471865D01*
X1285047Y472490D01*
X1286713D01*
G01X1281947Y469990D02*
X1283613D01*
Y472490D01*
X1281947D01*
G01X1282613Y471282D02*
X1283613D01*
G01X1279680Y469990D02*
Y472490D01*
X1280180Y471990D01*
G01Y469990D02*
X1279180D01*
G01X1268903Y473600D02*
X1276291D01*
G01X1268902Y485800D02*
X1276274D01*
G01X1280580Y500084D02*
X1280350Y500394D01*
X1280082Y500549D01*
X1279775Y500601D01*
X1279392Y500498D01*
X1279124Y500239D01*
X1279047Y499929D01*
X1279085Y499619D01*
X1279239Y499361D01*
X1280005Y498844D01*
X1280350Y498483D01*
X1280580Y497966D01*
X1280657Y497501D01*
X1279047D01*
G01X1276752D02*
X1276484Y497553D01*
X1276177Y497708D01*
X1275985Y497966D01*
X1275909Y498328D01*
X1275985Y498689D01*
X1276215Y498999D01*
X1276560Y499154D01*
X1276944D01*
X1277174Y499258D01*
X1277365Y499516D01*
X1277442Y499878D01*
X1277327Y500239D01*
X1277059Y500498D01*
X1276752Y500601D01*
X1276445Y500498D01*
X1276177Y500239D01*
X1276062Y499878D01*
X1276139Y499516D01*
X1276330Y499258D01*
X1276560Y499154D01*
X1276944D01*
X1277289Y498999D01*
X1277519Y498689D01*
X1277595Y498328D01*
X1277519Y497966D01*
X1277327Y497708D01*
X1277020Y497553D01*
X1276752Y497501D01*
G01X1273652D02*
X1273384Y497553D01*
X1273077Y497708D01*
X1272885Y497966D01*
X1272809Y498328D01*
X1272885Y498689D01*
X1273115Y498999D01*
X1273460Y499154D01*
X1273844D01*
X1274074Y499258D01*
X1274265Y499516D01*
X1274342Y499878D01*
X1274227Y500239D01*
X1273959Y500498D01*
X1273652Y500601D01*
X1273345Y500498D01*
X1273077Y500239D01*
X1272962Y499878D01*
X1273039Y499516D01*
X1273230Y499258D01*
X1273460Y499154D01*
X1273844D01*
X1274189Y498999D01*
X1274419Y498689D01*
X1274495Y498328D01*
X1274419Y497966D01*
X1274227Y497708D01*
X1273920Y497553D01*
X1273652Y497501D01*
G01X1270986Y501284D02*
X1295376D01*
Y526874D01*
X1270986D01*
G01X1240239Y533972D02*
X1240489Y534097D01*
X1240781Y534180D01*
X1241114D01*
X1241489Y534055D01*
X1241781Y533847D01*
X1241989Y533597D01*
X1242156Y533180D01*
X1242198Y532805D01*
X1242114Y532430D01*
X1241989Y532180D01*
X1241739Y531930D01*
X1241448Y531763D01*
X1241156Y531680D01*
X1240864D01*
X1240573Y531763D01*
X1240323Y531888D01*
X1240114Y532055D01*
G01X1237556Y531680D02*
Y534180D01*
X1239098Y532388D01*
X1237014D01*
G01X1236039Y531680D02*
Y534180D01*
X1234956Y532097D01*
X1233873Y534180D01*
Y531680D01*
G01X1232773Y532180D02*
X1232523Y531888D01*
X1232189Y531722D01*
X1231814Y531680D01*
X1231481Y531722D01*
X1231148Y531930D01*
X1230939Y532180D01*
X1230898Y532430D01*
X1230981Y532722D01*
X1231273Y532930D01*
X1231564Y533013D01*
X1231939D01*
G01X1231564D02*
X1231314Y533138D01*
X1231106Y533347D01*
X1231023Y533597D01*
X1231106Y533847D01*
X1231314Y534055D01*
X1231689Y534180D01*
X1232064Y534138D01*
X1232439Y533972D01*
G01X1242505Y572009D02*
X1242755Y572134D01*
X1243047Y572217D01*
X1243380D01*
X1243755Y572092D01*
X1244047Y571884D01*
X1244255Y571634D01*
X1244422Y571217D01*
X1244464Y570842D01*
X1244380Y570467D01*
X1244255Y570217D01*
X1244005Y569967D01*
X1243714Y569800D01*
X1243422Y569717D01*
X1243130D01*
X1242839Y569800D01*
X1242589Y569925D01*
X1242380Y570092D01*
G01X1239822Y569717D02*
Y572217D01*
X1241364Y570425D01*
X1239280D01*
G01X1238055Y572217D02*
Y569717D01*
X1236389D01*
G01X1235039Y570217D02*
X1234789Y569925D01*
X1234455Y569759D01*
X1234080Y569717D01*
X1233747Y569759D01*
X1233414Y569967D01*
X1233205Y570217D01*
X1233164Y570467D01*
X1233247Y570759D01*
X1233539Y570967D01*
X1233830Y571050D01*
X1234205D01*
G01X1233830D02*
X1233580Y571175D01*
X1233372Y571384D01*
X1233289Y571634D01*
X1233372Y571884D01*
X1233580Y572092D01*
X1233955Y572217D01*
X1234330Y572175D01*
X1234705Y572009D01*
G01X1277080Y575584D02*
X1276850Y575894D01*
X1276582Y576049D01*
X1276275Y576101D01*
X1275892Y575998D01*
X1275624Y575739D01*
X1275547Y575429D01*
X1275585Y575119D01*
X1275739Y574861D01*
X1276505Y574344D01*
X1276850Y573983D01*
X1277080Y573466D01*
X1277157Y573001D01*
X1275547D01*
G01X1273252D02*
X1272984Y573053D01*
X1272677Y573208D01*
X1272485Y573466D01*
X1272409Y573828D01*
X1272485Y574189D01*
X1272715Y574499D01*
X1273060Y574654D01*
X1273444D01*
X1273674Y574758D01*
X1273865Y575016D01*
X1273942Y575378D01*
X1273827Y575739D01*
X1273559Y575998D01*
X1273252Y576101D01*
X1272945Y575998D01*
X1272677Y575739D01*
X1272562Y575378D01*
X1272639Y575016D01*
X1272830Y574758D01*
X1273060Y574654D01*
X1273444D01*
X1273789Y574499D01*
X1274019Y574189D01*
X1274095Y573828D01*
X1274019Y573466D01*
X1273827Y573208D01*
X1273520Y573053D01*
X1273252Y573001D01*
G01X1270152D02*
X1269884Y573053D01*
X1269577Y573208D01*
X1269385Y573466D01*
X1269309Y573828D01*
X1269385Y574189D01*
X1269615Y574499D01*
X1269960Y574654D01*
X1270344D01*
X1270574Y574758D01*
X1270765Y575016D01*
X1270842Y575378D01*
X1270727Y575739D01*
X1270459Y575998D01*
X1270152Y576101D01*
X1269845Y575998D01*
X1269577Y575739D01*
X1269462Y575378D01*
X1269539Y575016D01*
X1269730Y574758D01*
X1269960Y574654D01*
X1270344D01*
X1270689Y574499D01*
X1270919Y574189D01*
X1270995Y573828D01*
X1270919Y573466D01*
X1270727Y573208D01*
X1270420Y573053D01*
X1270152Y573001D01*
G01X1270986Y576884D02*
X1295376D01*
Y602474D01*
X1270986D01*
G01X1276352Y565501D02*
Y568601D01*
X1276812Y567981D01*
G01Y565501D02*
X1275892D01*
G01X1272792D02*
Y568601D01*
X1274210Y566379D01*
X1272294D01*
G01X1269692Y565501D02*
Y568601D01*
X1271110Y566379D01*
X1269194D01*
G01X1277080Y537084D02*
X1276850Y537394D01*
X1276582Y537549D01*
X1276275Y537601D01*
X1275892Y537498D01*
X1275624Y537239D01*
X1275547Y536929D01*
X1275585Y536619D01*
X1275739Y536361D01*
X1276505Y535844D01*
X1276850Y535483D01*
X1277080Y534966D01*
X1277157Y534501D01*
X1275547D01*
G01X1273252D02*
X1272984Y534553D01*
X1272677Y534708D01*
X1272485Y534966D01*
X1272409Y535328D01*
X1272485Y535689D01*
X1272715Y535999D01*
X1273060Y536154D01*
X1273444D01*
X1273674Y536258D01*
X1273865Y536516D01*
X1273942Y536878D01*
X1273827Y537239D01*
X1273559Y537498D01*
X1273252Y537601D01*
X1272945Y537498D01*
X1272677Y537239D01*
X1272562Y536878D01*
X1272639Y536516D01*
X1272830Y536258D01*
X1273060Y536154D01*
X1273444D01*
X1273789Y535999D01*
X1274019Y535689D01*
X1274095Y535328D01*
X1274019Y534966D01*
X1273827Y534708D01*
X1273520Y534553D01*
X1273252Y534501D01*
G01X1270152D02*
X1269884Y534553D01*
X1269577Y534708D01*
X1269385Y534966D01*
X1269309Y535328D01*
X1269385Y535689D01*
X1269615Y535999D01*
X1269960Y536154D01*
X1270344D01*
X1270574Y536258D01*
X1270765Y536516D01*
X1270842Y536878D01*
X1270727Y537239D01*
X1270459Y537498D01*
X1270152Y537601D01*
X1269845Y537498D01*
X1269577Y537239D01*
X1269462Y536878D01*
X1269539Y536516D01*
X1269730Y536258D01*
X1269960Y536154D01*
X1270344D01*
X1270689Y535999D01*
X1270919Y535689D01*
X1270995Y535328D01*
X1270919Y534966D01*
X1270727Y534708D01*
X1270420Y534553D01*
X1270152Y534501D01*
G01X1270986Y539084D02*
X1295376D01*
Y564674D01*
X1270986D01*
G01X1276852Y528001D02*
Y531101D01*
X1277312Y530481D01*
G01Y528001D02*
X1276392D01*
G01X1273292D02*
Y531101D01*
X1274710Y528879D01*
X1272794D01*
G01X1270192Y528001D02*
Y531101D01*
X1271610Y528879D01*
X1269694D01*
G01X1253007Y616748D02*
X1253257Y616873D01*
X1253549Y616956D01*
X1253882D01*
X1254257Y616831D01*
X1254549Y616623D01*
X1254757Y616373D01*
X1254924Y615956D01*
X1254966Y615581D01*
X1254882Y615206D01*
X1254757Y614956D01*
X1254507Y614706D01*
X1254216Y614539D01*
X1253924Y614456D01*
X1253632D01*
X1253341Y614539D01*
X1253091Y614664D01*
X1252882Y614831D01*
G01X1250324Y614456D02*
Y616956D01*
X1251866Y615164D01*
X1249782D01*
G01X1248557Y616956D02*
Y614456D01*
X1246891D01*
G01X1245416Y616539D02*
X1245166Y616789D01*
X1244874Y616914D01*
X1244541Y616956D01*
X1244124Y616873D01*
X1243832Y616664D01*
X1243749Y616414D01*
X1243791Y616164D01*
X1243957Y615956D01*
X1244791Y615539D01*
X1245166Y615248D01*
X1245416Y614831D01*
X1245499Y614456D01*
X1243749D01*
G01X1268507Y616992D02*
X1268757Y617117D01*
X1269049Y617200D01*
X1269382D01*
X1269757Y617075D01*
X1270049Y616867D01*
X1270257Y616617D01*
X1270424Y616200D01*
X1270466Y615825D01*
X1270382Y615450D01*
X1270257Y615200D01*
X1270007Y614950D01*
X1269716Y614783D01*
X1269424Y614700D01*
X1269132D01*
X1268841Y614783D01*
X1268591Y614908D01*
X1268382Y615075D01*
G01X1265824Y614700D02*
Y617200D01*
X1267366Y615408D01*
X1265282D01*
G01X1264057Y617200D02*
Y614700D01*
X1262391D01*
G01X1260124D02*
Y617200D01*
X1260624Y616700D01*
G01Y614700D02*
X1259624D01*
G01X1275352Y604001D02*
Y607101D01*
X1275812Y606481D01*
G01Y604001D02*
X1274892D01*
G01X1271792D02*
Y607101D01*
X1273210Y604879D01*
X1271294D01*
G01X1268692Y604001D02*
Y607101D01*
X1270110Y604879D01*
X1268194D01*
G01X1231750Y639850D02*
X1264450D01*
Y658550D01*
X1231750D01*
Y639850D01*
G01X1296675Y6532D02*
X1299175D01*
Y7573D01*
X1299050Y7907D01*
X1298883Y8115D01*
X1298550Y8198D01*
X1298217Y8115D01*
X1298008Y7865D01*
X1297883Y7573D01*
Y6532D01*
G01Y7573D02*
X1296675Y8198D01*
G01Y10965D02*
X1299175D01*
X1297383Y9423D01*
Y11507D01*
G01X1299175Y12648D02*
X1297383D01*
X1297008Y12815D01*
X1296758Y13148D01*
X1296675Y13565D01*
X1296758Y13982D01*
X1297008Y14315D01*
X1297383Y14482D01*
X1299175D01*
G01X1296675Y17165D02*
X1299175D01*
X1297383Y15623D01*
Y17707D01*
G01X1312347Y23931D02*
X1314847D01*
Y24972D01*
X1314722Y25306D01*
X1314555Y25514D01*
X1314222Y25597D01*
X1313889Y25514D01*
X1313680Y25264D01*
X1313555Y24972D01*
Y23931D01*
G01Y24972D02*
X1312347Y25597D01*
G01Y28364D02*
X1314847D01*
X1313055Y26822D01*
Y28906D01*
G01X1314847Y30047D02*
X1313055D01*
X1312680Y30214D01*
X1312430Y30547D01*
X1312347Y30964D01*
X1312430Y31381D01*
X1312680Y31714D01*
X1313055Y31881D01*
X1314847D01*
G01X1312847Y33147D02*
X1312555Y33397D01*
X1312389Y33731D01*
X1312347Y34106D01*
X1312389Y34439D01*
X1312597Y34772D01*
X1312847Y34981D01*
X1313097Y35022D01*
X1313389Y34939D01*
X1313597Y34647D01*
X1313680Y34356D01*
Y33981D01*
G01Y34356D02*
X1313805Y34606D01*
X1314014Y34814D01*
X1314264Y34897D01*
X1314514Y34814D01*
X1314722Y34606D01*
X1314847Y34231D01*
X1314805Y33856D01*
X1314639Y33481D01*
G01X1319581Y25696D02*
X1319623Y25363D01*
X1319789Y25071D01*
X1320039Y24821D01*
X1320331Y24654D01*
X1320664Y24571D01*
X1320998D01*
X1321331Y24654D01*
X1321623Y24821D01*
X1321873Y25071D01*
X1322039Y25363D01*
X1322081Y25696D01*
X1322039Y26029D01*
X1321873Y26321D01*
X1321623Y26571D01*
X1321331Y26738D01*
X1320998Y26821D01*
X1320664D01*
X1320331Y26738D01*
X1320039Y26571D01*
X1319789Y26321D01*
X1319623Y26029D01*
X1319581Y25696D01*
G01X1320248Y26029D02*
X1319581Y26529D01*
G01Y29296D02*
X1322081D01*
X1320289Y27754D01*
Y29838D01*
G01X1322081Y30979D02*
X1320289D01*
X1319914Y31146D01*
X1319664Y31479D01*
X1319581Y31896D01*
X1319664Y32313D01*
X1319914Y32646D01*
X1320289Y32813D01*
X1322081D01*
G01X1319581Y34996D02*
X1322081D01*
X1321581Y34496D01*
G01X1319581D02*
Y35496D01*
G01X1305733Y-4208D02*
X1305983Y-4083D01*
X1306275Y-4000D01*
X1306608D01*
X1306983Y-4125D01*
X1307275Y-4333D01*
X1307483Y-4583D01*
X1307650Y-5000D01*
X1307692Y-5375D01*
X1307608Y-5750D01*
X1307483Y-6000D01*
X1307233Y-6250D01*
X1306942Y-6417D01*
X1306650Y-6500D01*
X1306358D01*
X1306067Y-6417D01*
X1305817Y-6292D01*
X1305608Y-6125D01*
G01X1304467Y-6000D02*
X1304217Y-6292D01*
X1303883Y-6458D01*
X1303508Y-6500D01*
X1303175Y-6458D01*
X1302842Y-6250D01*
X1302633Y-6000D01*
X1302592Y-5750D01*
X1302675Y-5458D01*
X1302967Y-5250D01*
X1303258Y-5167D01*
X1303633D01*
G01X1303258D02*
X1303008Y-5042D01*
X1302800Y-4833D01*
X1302717Y-4583D01*
X1302800Y-4333D01*
X1303008Y-4125D01*
X1303383Y-4000D01*
X1303758Y-4042D01*
X1304133Y-4208D01*
G01X1301367Y-4000D02*
Y-5792D01*
X1301200Y-6167D01*
X1300867Y-6417D01*
X1300450Y-6500D01*
X1300033Y-6417D01*
X1299700Y-6167D01*
X1299533Y-5792D01*
Y-4000D01*
G01X1297350Y-6500D02*
X1297058Y-6458D01*
X1296725Y-6333D01*
X1296517Y-6125D01*
X1296433Y-5833D01*
X1296517Y-5542D01*
X1296767Y-5292D01*
X1297142Y-5167D01*
X1297558D01*
X1297808Y-5083D01*
X1298017Y-4875D01*
X1298100Y-4583D01*
X1297975Y-4292D01*
X1297683Y-4083D01*
X1297350Y-4000D01*
X1297017Y-4083D01*
X1296725Y-4292D01*
X1296600Y-4583D01*
X1296683Y-4875D01*
X1296892Y-5083D01*
X1297142Y-5167D01*
X1297558D01*
X1297933Y-5292D01*
X1298183Y-5542D01*
X1298267Y-5833D01*
X1298183Y-6125D01*
X1297975Y-6333D01*
X1297642Y-6458D01*
X1297350Y-6500D01*
G01X1308636Y-1700D02*
Y2091D01*
X1321432D01*
Y-1700D01*
G01X1308636Y-14300D02*
Y-17862D01*
X1321432D01*
Y-14300D01*
G01X1344000Y1000D02*
X1321428D01*
G01X1344000Y-17000D02*
X1321425D01*
G01X1340933Y25592D02*
X1341183Y25717D01*
X1341475Y25800D01*
X1341808D01*
X1342183Y25675D01*
X1342475Y25467D01*
X1342683Y25217D01*
X1342850Y24800D01*
X1342892Y24425D01*
X1342808Y24050D01*
X1342683Y23800D01*
X1342433Y23550D01*
X1342142Y23383D01*
X1341850Y23300D01*
X1341558D01*
X1341267Y23383D01*
X1341017Y23508D01*
X1340808Y23675D01*
G01X1339667Y23800D02*
X1339417Y23508D01*
X1339083Y23342D01*
X1338708Y23300D01*
X1338375Y23342D01*
X1338042Y23550D01*
X1337833Y23800D01*
X1337792Y24050D01*
X1337875Y24342D01*
X1338167Y24550D01*
X1338458Y24633D01*
X1338833D01*
G01X1338458D02*
X1338208Y24758D01*
X1338000Y24967D01*
X1337917Y25217D01*
X1338000Y25467D01*
X1338208Y25675D01*
X1338583Y25800D01*
X1338958Y25758D01*
X1339333Y25592D01*
G01X1336567Y25800D02*
Y24008D01*
X1336400Y23633D01*
X1336067Y23383D01*
X1335650Y23300D01*
X1335233Y23383D01*
X1334900Y23633D01*
X1334733Y24008D01*
Y25800D01*
G01X1333467Y23675D02*
X1333217Y23467D01*
X1332925Y23342D01*
X1332550Y23300D01*
X1332175Y23383D01*
X1331883Y23550D01*
X1331675Y23842D01*
X1331633Y24175D01*
X1331717Y24508D01*
X1331925Y24717D01*
X1332217Y24883D01*
X1332508Y24925D01*
X1332800Y24883D01*
X1333175Y24717D01*
X1333050Y25800D01*
X1331925D01*
G01X1344000Y4000D02*
X1321425D01*
G01X1344000Y22000D02*
X1321428D01*
G01X1308636Y6700D02*
Y3138D01*
X1321432D01*
Y6700D01*
G01X1308636Y19300D02*
Y23091D01*
X1321432D01*
Y19300D01*
G01X1299700Y49167D02*
X1302200D01*
Y50208D01*
X1302075Y50542D01*
X1301908Y50750D01*
X1301575Y50833D01*
X1301242Y50750D01*
X1301033Y50500D01*
X1300908Y50208D01*
Y49167D01*
G01Y50208D02*
X1299700Y50833D01*
G01Y53600D02*
X1302200D01*
X1300408Y52058D01*
Y54142D01*
G01X1302200Y55283D02*
X1300408D01*
X1300033Y55450D01*
X1299783Y55783D01*
X1299700Y56200D01*
X1299783Y56617D01*
X1300033Y56950D01*
X1300408Y57117D01*
X1302200D01*
G01X1301783Y58508D02*
X1302033Y58758D01*
X1302158Y59050D01*
X1302200Y59383D01*
X1302117Y59800D01*
X1301908Y60092D01*
X1301658Y60175D01*
X1301408Y60133D01*
X1301200Y59967D01*
X1300783Y59133D01*
X1300492Y58758D01*
X1300075Y58508D01*
X1299700Y58425D01*
Y60175D01*
G01X1303100Y49167D02*
X1305600D01*
Y50208D01*
X1305475Y50542D01*
X1305308Y50750D01*
X1304975Y50833D01*
X1304642Y50750D01*
X1304433Y50500D01*
X1304308Y50208D01*
Y49167D01*
G01Y50208D02*
X1303100Y50833D01*
G01Y53600D02*
X1305600D01*
X1303808Y52058D01*
Y54142D01*
G01X1305600Y55283D02*
X1303808D01*
X1303433Y55450D01*
X1303183Y55783D01*
X1303100Y56200D01*
X1303183Y56617D01*
X1303433Y56950D01*
X1303808Y57117D01*
X1305600D01*
G01X1303100Y59300D02*
X1305600D01*
X1305100Y58800D01*
G01X1303100D02*
Y59800D01*
G01X1338483Y77510D02*
Y80010D01*
X1337442D01*
X1337108Y79885D01*
X1336900Y79718D01*
X1336817Y79385D01*
X1336900Y79052D01*
X1337150Y78843D01*
X1337442Y78718D01*
X1338483D01*
G01X1337442D02*
X1336817Y77510D01*
G01X1335467Y78010D02*
X1335217Y77718D01*
X1334883Y77552D01*
X1334508Y77510D01*
X1334175Y77552D01*
X1333842Y77760D01*
X1333633Y78010D01*
X1333592Y78260D01*
X1333675Y78552D01*
X1333967Y78760D01*
X1334258Y78843D01*
X1334633D01*
G01X1334258D02*
X1334008Y78968D01*
X1333800Y79177D01*
X1333717Y79427D01*
X1333800Y79677D01*
X1334008Y79885D01*
X1334383Y80010D01*
X1334758Y79968D01*
X1335133Y79802D01*
G01X1331450Y80010D02*
Y77510D01*
G01X1332408Y80010D02*
X1330492D01*
G01X1328350Y77510D02*
Y80010D01*
X1328850Y79510D01*
G01Y77510D02*
X1327850D01*
G01X1325250D02*
Y80010D01*
X1325750Y79510D01*
G01Y77510D02*
X1324750D01*
G01X1349533Y67500D02*
Y70000D01*
X1348492D01*
X1348158Y69875D01*
X1347950Y69708D01*
X1347867Y69375D01*
X1347950Y69042D01*
X1348200Y68833D01*
X1348492Y68708D01*
X1349533D01*
G01X1348492D02*
X1347867Y67500D01*
G01X1346517Y68000D02*
X1346267Y67708D01*
X1345933Y67542D01*
X1345558Y67500D01*
X1345225Y67542D01*
X1344892Y67750D01*
X1344683Y68000D01*
X1344642Y68250D01*
X1344725Y68542D01*
X1345017Y68750D01*
X1345308Y68833D01*
X1345683D01*
G01X1345308D02*
X1345058Y68958D01*
X1344850Y69167D01*
X1344767Y69417D01*
X1344850Y69667D01*
X1345058Y69875D01*
X1345433Y70000D01*
X1345808Y69958D01*
X1346183Y69792D01*
G01X1343417Y70000D02*
Y68208D01*
X1343250Y67833D01*
X1342917Y67583D01*
X1342500Y67500D01*
X1342083Y67583D01*
X1341750Y67833D01*
X1341583Y68208D01*
Y70000D01*
G01X1340192Y69583D02*
X1339942Y69833D01*
X1339650Y69958D01*
X1339317Y70000D01*
X1338900Y69917D01*
X1338608Y69708D01*
X1338525Y69458D01*
X1338567Y69208D01*
X1338733Y69000D01*
X1339567Y68583D01*
X1339942Y68292D01*
X1340192Y67875D01*
X1340275Y67500D01*
X1338525D01*
G01X1340833Y49600D02*
Y52100D01*
X1339792D01*
X1339458Y51975D01*
X1339250Y51808D01*
X1339167Y51475D01*
X1339250Y51142D01*
X1339500Y50933D01*
X1339792Y50808D01*
X1340833D01*
G01X1339792D02*
X1339167Y49600D01*
G01X1337817Y50100D02*
X1337567Y49808D01*
X1337233Y49642D01*
X1336858Y49600D01*
X1336525Y49642D01*
X1336192Y49850D01*
X1335983Y50100D01*
X1335942Y50350D01*
X1336025Y50642D01*
X1336317Y50850D01*
X1336608Y50933D01*
X1336983D01*
G01X1336608D02*
X1336358Y51058D01*
X1336150Y51267D01*
X1336067Y51517D01*
X1336150Y51767D01*
X1336358Y51975D01*
X1336733Y52100D01*
X1337108Y52058D01*
X1337483Y51892D01*
G01X1334717Y52100D02*
Y50308D01*
X1334550Y49933D01*
X1334217Y49683D01*
X1333800Y49600D01*
X1333383Y49683D01*
X1333050Y49933D01*
X1332883Y50308D01*
Y52100D01*
G01X1330200Y49600D02*
Y52100D01*
X1331742Y50308D01*
X1329658D01*
G01X1331792Y56267D02*
X1331917Y56017D01*
X1332000Y55725D01*
Y55392D01*
X1331875Y55017D01*
X1331667Y54725D01*
X1331417Y54517D01*
X1331000Y54350D01*
X1330625Y54308D01*
X1330250Y54392D01*
X1330000Y54517D01*
X1329750Y54767D01*
X1329583Y55058D01*
X1329500Y55350D01*
Y55642D01*
X1329583Y55933D01*
X1329708Y56183D01*
X1329875Y56392D01*
G01X1330000Y57533D02*
X1329708Y57783D01*
X1329542Y58117D01*
X1329500Y58492D01*
X1329542Y58825D01*
X1329750Y59158D01*
X1330000Y59367D01*
X1330250Y59408D01*
X1330542Y59325D01*
X1330750Y59033D01*
X1330833Y58742D01*
Y58367D01*
G01Y58742D02*
X1330958Y58992D01*
X1331167Y59200D01*
X1331417Y59283D01*
X1331667Y59200D01*
X1331875Y58992D01*
X1332000Y58617D01*
X1331958Y58242D01*
X1331792Y57867D01*
G01X1332000Y60633D02*
X1330208D01*
X1329833Y60800D01*
X1329583Y61133D01*
X1329500Y61550D01*
X1329583Y61967D01*
X1329833Y62300D01*
X1330208Y62467D01*
X1332000D01*
G01X1329500Y64650D02*
X1332000D01*
X1331500Y64150D01*
G01X1329500D02*
Y65150D01*
G01X1310700Y36136D02*
X1306909D01*
Y48932D01*
X1310700D01*
G01X1323300Y36136D02*
X1326862D01*
Y48932D01*
X1323300D01*
G01X1326000Y71500D02*
X1323302D01*
G01X1308000D02*
X1310695D01*
G01X1308000D02*
Y48928D01*
G01X1326000Y71500D02*
Y48925D01*
G01X1317033Y107142D02*
X1317283Y107267D01*
X1317575Y107350D01*
X1317908D01*
X1318283Y107225D01*
X1318575Y107017D01*
X1318783Y106767D01*
X1318950Y106350D01*
X1318992Y105975D01*
X1318908Y105600D01*
X1318783Y105350D01*
X1318533Y105100D01*
X1318242Y104933D01*
X1317950Y104850D01*
X1317658D01*
X1317367Y104933D01*
X1317117Y105058D01*
X1316908Y105225D01*
G01X1315767Y105350D02*
X1315517Y105058D01*
X1315183Y104892D01*
X1314808Y104850D01*
X1314475Y104892D01*
X1314142Y105100D01*
X1313933Y105350D01*
X1313892Y105600D01*
X1313975Y105892D01*
X1314267Y106100D01*
X1314558Y106183D01*
X1314933D01*
G01X1314558D02*
X1314308Y106308D01*
X1314100Y106517D01*
X1314017Y106767D01*
X1314100Y107017D01*
X1314308Y107225D01*
X1314683Y107350D01*
X1315058Y107308D01*
X1315433Y107142D01*
G01X1311750Y107350D02*
Y104850D01*
G01X1312708Y107350D02*
X1310792D01*
G01X1309358Y105142D02*
X1309067Y104933D01*
X1308733Y104850D01*
X1308400Y104933D01*
X1308108Y105183D01*
X1307900Y105558D01*
X1307817Y105933D01*
Y106392D01*
X1307900Y106767D01*
X1308108Y107100D01*
X1308358Y107267D01*
X1308650Y107350D01*
X1308983Y107267D01*
X1309233Y107100D01*
X1309400Y106850D01*
X1309483Y106517D01*
X1309400Y106225D01*
X1309192Y105933D01*
X1308942Y105767D01*
X1308650Y105725D01*
X1308317Y105808D01*
X1308067Y106017D01*
X1307817Y106392D01*
G01X1318633Y125242D02*
X1318883Y125367D01*
X1319175Y125450D01*
X1319508D01*
X1319883Y125325D01*
X1320175Y125117D01*
X1320383Y124867D01*
X1320550Y124450D01*
X1320592Y124075D01*
X1320508Y123700D01*
X1320383Y123450D01*
X1320133Y123200D01*
X1319842Y123033D01*
X1319550Y122950D01*
X1319258D01*
X1318967Y123033D01*
X1318717Y123158D01*
X1318508Y123325D01*
G01X1317367Y123450D02*
X1317117Y123158D01*
X1316783Y122992D01*
X1316408Y122950D01*
X1316075Y122992D01*
X1315742Y123200D01*
X1315533Y123450D01*
X1315492Y123700D01*
X1315575Y123992D01*
X1315867Y124200D01*
X1316158Y124283D01*
X1316533D01*
G01X1316158D02*
X1315908Y124408D01*
X1315700Y124617D01*
X1315617Y124867D01*
X1315700Y125117D01*
X1315908Y125325D01*
X1316283Y125450D01*
X1316658Y125408D01*
X1317033Y125242D01*
G01X1313350Y125450D02*
Y122950D01*
G01X1314308Y125450D02*
X1312392D01*
G01X1310333Y122950D02*
X1310250Y123492D01*
X1310125Y123950D01*
X1309958Y124367D01*
X1309750Y124825D01*
X1309417Y125450D01*
X1311083D01*
G01X1335042Y100317D02*
X1335167Y100067D01*
X1335250Y99775D01*
Y99442D01*
X1335125Y99067D01*
X1334917Y98775D01*
X1334667Y98567D01*
X1334250Y98400D01*
X1333875Y98358D01*
X1333500Y98442D01*
X1333250Y98567D01*
X1333000Y98817D01*
X1332833Y99108D01*
X1332750Y99400D01*
Y99692D01*
X1332833Y99983D01*
X1332958Y100233D01*
X1333125Y100442D01*
G01X1333250Y101583D02*
X1332958Y101833D01*
X1332792Y102167D01*
X1332750Y102542D01*
X1332792Y102875D01*
X1333000Y103208D01*
X1333250Y103417D01*
X1333500Y103458D01*
X1333792Y103375D01*
X1334000Y103083D01*
X1334083Y102792D01*
Y102417D01*
G01Y102792D02*
X1334208Y103042D01*
X1334417Y103250D01*
X1334667Y103333D01*
X1334917Y103250D01*
X1335125Y103042D01*
X1335250Y102667D01*
X1335208Y102292D01*
X1335042Y101917D01*
G01X1335250Y105600D02*
X1332750D01*
G01X1335250Y104642D02*
Y106558D01*
G01X1332750Y108700D02*
X1335250D01*
X1334750Y108200D01*
G01X1332750D02*
Y109200D01*
G01Y111800D02*
X1335250D01*
X1334750Y111300D01*
G01X1332750D02*
Y112300D01*
G01X1304189Y153096D02*
X1304314Y152846D01*
X1304397Y152554D01*
Y152221D01*
X1304272Y151846D01*
X1304064Y151554D01*
X1303814Y151346D01*
X1303397Y151179D01*
X1303022Y151137D01*
X1302647Y151221D01*
X1302397Y151346D01*
X1302147Y151596D01*
X1301980Y151887D01*
X1301897Y152179D01*
Y152471D01*
X1301980Y152762D01*
X1302105Y153012D01*
X1302272Y153221D01*
G01X1301897Y155779D02*
X1304397D01*
X1302605Y154237D01*
Y156321D01*
G01X1304397Y158379D02*
X1301897D01*
G01X1304397Y157421D02*
Y159337D01*
G01X1303980Y160687D02*
X1304230Y160937D01*
X1304355Y161229D01*
X1304397Y161562D01*
X1304314Y161979D01*
X1304105Y162271D01*
X1303855Y162354D01*
X1303605Y162312D01*
X1303397Y162146D01*
X1302980Y161312D01*
X1302689Y160937D01*
X1302272Y160687D01*
X1301897Y160604D01*
Y162354D01*
G01X1307689Y153096D02*
X1307814Y152846D01*
X1307897Y152554D01*
Y152221D01*
X1307772Y151846D01*
X1307564Y151554D01*
X1307314Y151346D01*
X1306897Y151179D01*
X1306522Y151137D01*
X1306147Y151221D01*
X1305897Y151346D01*
X1305647Y151596D01*
X1305480Y151887D01*
X1305397Y152179D01*
Y152471D01*
X1305480Y152762D01*
X1305605Y153012D01*
X1305772Y153221D01*
G01X1305397Y155779D02*
X1307897D01*
X1306105Y154237D01*
Y156321D01*
G01X1307897Y158379D02*
X1305397D01*
G01X1307897Y157421D02*
Y159337D01*
G01X1305397Y161479D02*
X1307897D01*
X1307397Y160979D01*
G01X1305397D02*
Y161979D01*
G01X1284192Y115867D02*
X1284317Y115617D01*
X1284400Y115325D01*
Y114992D01*
X1284275Y114617D01*
X1284067Y114325D01*
X1283817Y114117D01*
X1283400Y113950D01*
X1283025Y113908D01*
X1282650Y113992D01*
X1282400Y114117D01*
X1282150Y114367D01*
X1281983Y114658D01*
X1281900Y114950D01*
Y115242D01*
X1281983Y115533D01*
X1282108Y115783D01*
X1282275Y115992D01*
G01X1281900Y118550D02*
X1284400D01*
X1282608Y117008D01*
Y119092D01*
G01X1284400Y121150D02*
X1281900D01*
G01X1284400Y120192D02*
Y122108D01*
G01X1282400Y123333D02*
X1282108Y123583D01*
X1281942Y123917D01*
X1281900Y124292D01*
X1281942Y124625D01*
X1282150Y124958D01*
X1282400Y125167D01*
X1282650Y125208D01*
X1282942Y125125D01*
X1283150Y124833D01*
X1283233Y124542D01*
Y124167D01*
G01Y124542D02*
X1283358Y124792D01*
X1283567Y125000D01*
X1283817Y125083D01*
X1284067Y125000D01*
X1284275Y124792D01*
X1284400Y124417D01*
X1284358Y124042D01*
X1284192Y123667D01*
G01X1302900Y102950D02*
X1304100D01*
Y114950D01*
X1302900D01*
G01X1289300Y102950D02*
X1288100D01*
Y114950D01*
X1289300D01*
G01X1288100Y108000D02*
X1287050D01*
Y137900D01*
X1289300D01*
G01X1302900D02*
X1305150D01*
Y108000D01*
X1304100D01*
G01X1320352Y142921D02*
X1320602Y143046D01*
X1320894Y143129D01*
X1321227D01*
X1321602Y143004D01*
X1321894Y142796D01*
X1322102Y142546D01*
X1322269Y142129D01*
X1322311Y141754D01*
X1322227Y141379D01*
X1322102Y141129D01*
X1321852Y140879D01*
X1321561Y140712D01*
X1321269Y140629D01*
X1320977D01*
X1320686Y140712D01*
X1320436Y140837D01*
X1320227Y141004D01*
G01X1319086Y141129D02*
X1318836Y140837D01*
X1318502Y140671D01*
X1318127Y140629D01*
X1317794Y140671D01*
X1317461Y140879D01*
X1317252Y141129D01*
X1317211Y141379D01*
X1317294Y141671D01*
X1317586Y141879D01*
X1317877Y141962D01*
X1318252D01*
G01X1317877D02*
X1317627Y142087D01*
X1317419Y142296D01*
X1317336Y142546D01*
X1317419Y142796D01*
X1317627Y143004D01*
X1318002Y143129D01*
X1318377Y143087D01*
X1318752Y142921D01*
G01X1315069Y143129D02*
Y140629D01*
G01X1316027Y143129D02*
X1314111D01*
G01X1312761Y142712D02*
X1312511Y142962D01*
X1312219Y143087D01*
X1311886Y143129D01*
X1311469Y143046D01*
X1311177Y142837D01*
X1311094Y142587D01*
X1311136Y142337D01*
X1311302Y142129D01*
X1312136Y141712D01*
X1312511Y141421D01*
X1312761Y141004D01*
X1312844Y140629D01*
X1311094D01*
G01X1341737Y216147D02*
X1344237D01*
Y217188D01*
X1344112Y217522D01*
X1343945Y217730D01*
X1343612Y217813D01*
X1343279Y217730D01*
X1343070Y217480D01*
X1342945Y217188D01*
Y216147D01*
G01Y217188D02*
X1341737Y217813D01*
G01X1343820Y219288D02*
X1344070Y219538D01*
X1344195Y219830D01*
X1344237Y220163D01*
X1344154Y220580D01*
X1343945Y220872D01*
X1343695Y220955D01*
X1343445Y220913D01*
X1343237Y220747D01*
X1342820Y219913D01*
X1342529Y219538D01*
X1342112Y219288D01*
X1341737Y219205D01*
Y220955D01*
G01X1344237Y222263D02*
X1342445D01*
X1342070Y222430D01*
X1341820Y222763D01*
X1341737Y223180D01*
X1341820Y223597D01*
X1342070Y223930D01*
X1342445Y224097D01*
X1344237D01*
G01X1341737Y226280D02*
X1344237D01*
X1343737Y225780D01*
G01X1341737D02*
Y226780D01*
G01X1342029Y228672D02*
X1341820Y228963D01*
X1341737Y229297D01*
X1341820Y229630D01*
X1342070Y229922D01*
X1342445Y230130D01*
X1342820Y230213D01*
X1343279D01*
X1343654Y230130D01*
X1343987Y229922D01*
X1344154Y229672D01*
X1344237Y229380D01*
X1344154Y229047D01*
X1343987Y228797D01*
X1343737Y228630D01*
X1343404Y228547D01*
X1343112Y228630D01*
X1342820Y228838D01*
X1342654Y229088D01*
X1342612Y229380D01*
X1342695Y229713D01*
X1342904Y229963D01*
X1343279Y230213D01*
G01X1337737Y216147D02*
X1340237D01*
Y217188D01*
X1340112Y217522D01*
X1339945Y217730D01*
X1339612Y217813D01*
X1339279Y217730D01*
X1339070Y217480D01*
X1338945Y217188D01*
Y216147D01*
G01Y217188D02*
X1337737Y217813D01*
G01X1339820Y219288D02*
X1340070Y219538D01*
X1340195Y219830D01*
X1340237Y220163D01*
X1340154Y220580D01*
X1339945Y220872D01*
X1339695Y220955D01*
X1339445Y220913D01*
X1339237Y220747D01*
X1338820Y219913D01*
X1338529Y219538D01*
X1338112Y219288D01*
X1337737Y219205D01*
Y220955D01*
G01X1340237Y222263D02*
X1338445D01*
X1338070Y222430D01*
X1337820Y222763D01*
X1337737Y223180D01*
X1337820Y223597D01*
X1338070Y223930D01*
X1338445Y224097D01*
X1340237D01*
G01X1337737Y226280D02*
X1340237D01*
X1339737Y225780D01*
G01X1337737D02*
Y226780D01*
G01Y229380D02*
X1337779Y229672D01*
X1337904Y230005D01*
X1338112Y230213D01*
X1338404Y230297D01*
X1338695Y230213D01*
X1338945Y229963D01*
X1339070Y229588D01*
Y229172D01*
X1339154Y228922D01*
X1339362Y228713D01*
X1339654Y228630D01*
X1339945Y228755D01*
X1340154Y229047D01*
X1340237Y229380D01*
X1340154Y229713D01*
X1339945Y230005D01*
X1339654Y230130D01*
X1339362Y230047D01*
X1339154Y229838D01*
X1339070Y229588D01*
Y229172D01*
X1338945Y228797D01*
X1338695Y228547D01*
X1338404Y228463D01*
X1338112Y228547D01*
X1337904Y228755D01*
X1337779Y229088D01*
X1337737Y229380D01*
G01X1304257Y216596D02*
X1306757D01*
Y217637D01*
X1306632Y217971D01*
X1306465Y218179D01*
X1306132Y218262D01*
X1305799Y218179D01*
X1305590Y217929D01*
X1305465Y217637D01*
Y216596D01*
G01Y217637D02*
X1304257Y218262D01*
G01X1306340Y219737D02*
X1306590Y219987D01*
X1306715Y220279D01*
X1306757Y220612D01*
X1306674Y221029D01*
X1306465Y221321D01*
X1306215Y221404D01*
X1305965Y221362D01*
X1305757Y221196D01*
X1305340Y220362D01*
X1305049Y219987D01*
X1304632Y219737D01*
X1304257Y219654D01*
Y221404D01*
G01X1306757Y222712D02*
X1304965D01*
X1304590Y222879D01*
X1304340Y223212D01*
X1304257Y223629D01*
X1304340Y224046D01*
X1304590Y224379D01*
X1304965Y224546D01*
X1306757D01*
G01X1304257Y226729D02*
X1306757D01*
X1306257Y226229D01*
G01X1304257D02*
Y227229D01*
G01Y230329D02*
X1306757D01*
X1304965Y228787D01*
Y230871D01*
G01X1308257Y216596D02*
X1310757D01*
Y217637D01*
X1310632Y217971D01*
X1310465Y218179D01*
X1310132Y218262D01*
X1309799Y218179D01*
X1309590Y217929D01*
X1309465Y217637D01*
Y216596D01*
G01Y217637D02*
X1308257Y218262D01*
G01X1310340Y219737D02*
X1310590Y219987D01*
X1310715Y220279D01*
X1310757Y220612D01*
X1310674Y221029D01*
X1310465Y221321D01*
X1310215Y221404D01*
X1309965Y221362D01*
X1309757Y221196D01*
X1309340Y220362D01*
X1309049Y219987D01*
X1308632Y219737D01*
X1308257Y219654D01*
Y221404D01*
G01X1310757Y222712D02*
X1308965D01*
X1308590Y222879D01*
X1308340Y223212D01*
X1308257Y223629D01*
X1308340Y224046D01*
X1308590Y224379D01*
X1308965Y224546D01*
X1310757D01*
G01X1308257Y226729D02*
X1310757D01*
X1310257Y226229D01*
G01X1308257D02*
Y227229D01*
G01X1308632Y228912D02*
X1308424Y229162D01*
X1308299Y229454D01*
X1308257Y229829D01*
X1308340Y230204D01*
X1308507Y230496D01*
X1308799Y230704D01*
X1309132Y230746D01*
X1309465Y230662D01*
X1309674Y230454D01*
X1309840Y230162D01*
X1309882Y229871D01*
X1309840Y229579D01*
X1309674Y229204D01*
X1310757Y229329D01*
Y230454D01*
G01X1312257Y216596D02*
X1314757D01*
Y217637D01*
X1314632Y217971D01*
X1314465Y218179D01*
X1314132Y218262D01*
X1313799Y218179D01*
X1313590Y217929D01*
X1313465Y217637D01*
Y216596D01*
G01Y217637D02*
X1312257Y218262D01*
G01X1314340Y219737D02*
X1314590Y219987D01*
X1314715Y220279D01*
X1314757Y220612D01*
X1314674Y221029D01*
X1314465Y221321D01*
X1314215Y221404D01*
X1313965Y221362D01*
X1313757Y221196D01*
X1313340Y220362D01*
X1313049Y219987D01*
X1312632Y219737D01*
X1312257Y219654D01*
Y221404D01*
G01X1314757Y222712D02*
X1312965D01*
X1312590Y222879D01*
X1312340Y223212D01*
X1312257Y223629D01*
X1312340Y224046D01*
X1312590Y224379D01*
X1312965Y224546D01*
X1314757D01*
G01X1312257Y226729D02*
X1314757D01*
X1314257Y226229D01*
G01X1312257D02*
Y227229D01*
G01X1313299Y229037D02*
X1313590Y229329D01*
X1313757Y229579D01*
X1313840Y229912D01*
X1313757Y230204D01*
X1313590Y230412D01*
X1313340Y230579D01*
X1313049Y230621D01*
X1312799Y230579D01*
X1312549Y230412D01*
X1312340Y230162D01*
X1312257Y229871D01*
X1312340Y229537D01*
X1312590Y229246D01*
X1312965Y229079D01*
X1313382Y229037D01*
X1313924Y229121D01*
X1314215Y229246D01*
X1314507Y229454D01*
X1314715Y229746D01*
X1314757Y230037D01*
X1314674Y230329D01*
X1314465Y230537D01*
G01X1316257Y216596D02*
X1318757D01*
Y217637D01*
X1318632Y217971D01*
X1318465Y218179D01*
X1318132Y218262D01*
X1317799Y218179D01*
X1317590Y217929D01*
X1317465Y217637D01*
Y216596D01*
G01Y217637D02*
X1316257Y218262D01*
G01X1318340Y219737D02*
X1318590Y219987D01*
X1318715Y220279D01*
X1318757Y220612D01*
X1318674Y221029D01*
X1318465Y221321D01*
X1318215Y221404D01*
X1317965Y221362D01*
X1317757Y221196D01*
X1317340Y220362D01*
X1317049Y219987D01*
X1316632Y219737D01*
X1316257Y219654D01*
Y221404D01*
G01X1318757Y222712D02*
X1316965D01*
X1316590Y222879D01*
X1316340Y223212D01*
X1316257Y223629D01*
X1316340Y224046D01*
X1316590Y224379D01*
X1316965Y224546D01*
X1318757D01*
G01X1316257Y226729D02*
X1318757D01*
X1318257Y226229D01*
G01X1316257D02*
Y227229D01*
G01Y229746D02*
X1316799Y229829D01*
X1317257Y229954D01*
X1317674Y230121D01*
X1318132Y230329D01*
X1318757Y230662D01*
Y228996D01*
G01X1303059Y214920D02*
X1303309Y215045D01*
X1303601Y215128D01*
X1303934D01*
X1304309Y215003D01*
X1304601Y214795D01*
X1304809Y214545D01*
X1304976Y214128D01*
X1305018Y213753D01*
X1304934Y213378D01*
X1304809Y213128D01*
X1304559Y212878D01*
X1304268Y212711D01*
X1303976Y212628D01*
X1303684D01*
X1303393Y212711D01*
X1303143Y212836D01*
X1302934Y213003D01*
G01X1300376Y212628D02*
Y215128D01*
X1301918Y213336D01*
X1299834D01*
G01X1298609Y212628D02*
Y215128D01*
X1297568D01*
X1297234Y215003D01*
X1297026Y214836D01*
X1296943Y214503D01*
X1297026Y214170D01*
X1297276Y213961D01*
X1297568Y213836D01*
X1298609D01*
G01X1297568D02*
X1296943Y212628D01*
G01X1295468Y214711D02*
X1295218Y214961D01*
X1294926Y215086D01*
X1294593Y215128D01*
X1294176Y215045D01*
X1293884Y214836D01*
X1293801Y214586D01*
X1293843Y214336D01*
X1294009Y214128D01*
X1294843Y213711D01*
X1295218Y213420D01*
X1295468Y213003D01*
X1295551Y212628D01*
X1293801D01*
G01X1329192Y190967D02*
X1329317Y190717D01*
X1329400Y190425D01*
Y190092D01*
X1329275Y189717D01*
X1329067Y189425D01*
X1328817Y189217D01*
X1328400Y189050D01*
X1328025Y189008D01*
X1327650Y189092D01*
X1327400Y189217D01*
X1327150Y189467D01*
X1326983Y189758D01*
X1326900Y190050D01*
Y190342D01*
X1326983Y190633D01*
X1327108Y190883D01*
X1327275Y191092D01*
G01X1327400Y192233D02*
X1327108Y192483D01*
X1326942Y192817D01*
X1326900Y193192D01*
X1326942Y193525D01*
X1327150Y193858D01*
X1327400Y194067D01*
X1327650Y194108D01*
X1327942Y194025D01*
X1328150Y193733D01*
X1328233Y193442D01*
Y193067D01*
G01Y193442D02*
X1328358Y193692D01*
X1328567Y193900D01*
X1328817Y193983D01*
X1329067Y193900D01*
X1329275Y193692D01*
X1329400Y193317D01*
X1329358Y192942D01*
X1329192Y192567D01*
G01X1326900Y195417D02*
X1329400D01*
Y196458D01*
X1329275Y196792D01*
X1329108Y197000D01*
X1328775Y197083D01*
X1328442Y197000D01*
X1328233Y196750D01*
X1328108Y196458D01*
Y195417D01*
G01Y196458D02*
X1326900Y197083D01*
G01Y199850D02*
X1329400D01*
X1327608Y198308D01*
Y200392D01*
G01X1309700Y174636D02*
X1305909D01*
Y187432D01*
X1309700D01*
G01X1322300Y174636D02*
X1325862D01*
Y187432D01*
X1322300D01*
G01X1325000Y210000D02*
X1322302D01*
G01X1307000D02*
X1309695D01*
G01X1307000D02*
Y187428D01*
G01X1325000Y210000D02*
Y187425D01*
G01X1320452Y161059D02*
X1320702Y161184D01*
X1320994Y161267D01*
X1321327D01*
X1321702Y161142D01*
X1321994Y160934D01*
X1322202Y160684D01*
X1322369Y160267D01*
X1322411Y159892D01*
X1322327Y159517D01*
X1322202Y159267D01*
X1321952Y159017D01*
X1321661Y158850D01*
X1321369Y158767D01*
X1321077D01*
X1320786Y158850D01*
X1320536Y158975D01*
X1320327Y159142D01*
G01X1319186Y159267D02*
X1318936Y158975D01*
X1318602Y158809D01*
X1318227Y158767D01*
X1317894Y158809D01*
X1317561Y159017D01*
X1317352Y159267D01*
X1317311Y159517D01*
X1317394Y159809D01*
X1317686Y160017D01*
X1317977Y160100D01*
X1318352D01*
G01X1317977D02*
X1317727Y160225D01*
X1317519Y160434D01*
X1317436Y160684D01*
X1317519Y160934D01*
X1317727Y161142D01*
X1318102Y161267D01*
X1318477Y161225D01*
X1318852Y161059D01*
G01X1315169Y161267D02*
Y158767D01*
G01X1316127Y161267D02*
X1314211D01*
G01X1312069Y158767D02*
Y161267D01*
X1312569Y160767D01*
G01Y158767D02*
X1311569D01*
G01X1325970Y218847D02*
X1328470D01*
Y219888D01*
X1328345Y220222D01*
X1328178Y220430D01*
X1327845Y220513D01*
X1327512Y220430D01*
X1327303Y220180D01*
X1327178Y219888D01*
Y218847D01*
G01Y219888D02*
X1325970Y220513D01*
G01Y223280D02*
X1328470D01*
X1326678Y221738D01*
Y223822D01*
G01X1325970Y225047D02*
X1328470D01*
Y226088D01*
X1328345Y226422D01*
X1328178Y226630D01*
X1327845Y226713D01*
X1327512Y226630D01*
X1327303Y226380D01*
X1327178Y226088D01*
Y225047D01*
G01Y226088D02*
X1325970Y226713D01*
G01X1326470Y228063D02*
X1326178Y228313D01*
X1326012Y228647D01*
X1325970Y229022D01*
X1326012Y229355D01*
X1326220Y229688D01*
X1326470Y229897D01*
X1326720Y229938D01*
X1327012Y229855D01*
X1327220Y229563D01*
X1327303Y229272D01*
Y228897D01*
G01Y229272D02*
X1327428Y229522D01*
X1327637Y229730D01*
X1327887Y229813D01*
X1328137Y229730D01*
X1328345Y229522D01*
X1328470Y229147D01*
X1328428Y228772D01*
X1328262Y228397D01*
G01X1295908Y257146D02*
Y259646D01*
X1294867D01*
X1294533Y259521D01*
X1294325Y259354D01*
X1294242Y259021D01*
X1294325Y258688D01*
X1294575Y258479D01*
X1294867Y258354D01*
X1295908D01*
G01X1294867D02*
X1294242Y257146D01*
G01X1292892Y257646D02*
X1292642Y257354D01*
X1292308Y257188D01*
X1291933Y257146D01*
X1291600Y257188D01*
X1291267Y257396D01*
X1291058Y257646D01*
X1291017Y257896D01*
X1291100Y258188D01*
X1291392Y258396D01*
X1291683Y258479D01*
X1292058D01*
G01X1291683D02*
X1291433Y258604D01*
X1291225Y258813D01*
X1291142Y259063D01*
X1291225Y259313D01*
X1291433Y259521D01*
X1291808Y259646D01*
X1292183Y259604D01*
X1292558Y259438D01*
G01X1289708Y257146D02*
Y259646D01*
X1288667D01*
X1288333Y259521D01*
X1288125Y259354D01*
X1288042Y259021D01*
X1288125Y258688D01*
X1288375Y258479D01*
X1288667Y258354D01*
X1289708D01*
G01X1288667D02*
X1288042Y257146D01*
G01X1285775D02*
Y259646D01*
X1286275Y259146D01*
G01Y257146D02*
X1285275D01*
G01X1282175D02*
Y259646D01*
X1283717Y257854D01*
X1281633D01*
G01X1296074Y253830D02*
Y256330D01*
X1295033D01*
X1294699Y256205D01*
X1294491Y256038D01*
X1294408Y255705D01*
X1294491Y255372D01*
X1294741Y255163D01*
X1295033Y255038D01*
X1296074D01*
G01X1295033D02*
X1294408Y253830D01*
G01X1293058Y254330D02*
X1292808Y254038D01*
X1292474Y253872D01*
X1292099Y253830D01*
X1291766Y253872D01*
X1291433Y254080D01*
X1291224Y254330D01*
X1291183Y254580D01*
X1291266Y254872D01*
X1291558Y255080D01*
X1291849Y255163D01*
X1292224D01*
G01X1291849D02*
X1291599Y255288D01*
X1291391Y255497D01*
X1291308Y255747D01*
X1291391Y255997D01*
X1291599Y256205D01*
X1291974Y256330D01*
X1292349Y256288D01*
X1292724Y256122D01*
G01X1289874Y253830D02*
Y256330D01*
X1288833D01*
X1288499Y256205D01*
X1288291Y256038D01*
X1288208Y255705D01*
X1288291Y255372D01*
X1288541Y255163D01*
X1288833Y255038D01*
X1289874D01*
G01X1288833D02*
X1288208Y253830D01*
G01X1286024D02*
X1285941Y254372D01*
X1285816Y254830D01*
X1285649Y255247D01*
X1285441Y255705D01*
X1285108Y256330D01*
X1286774D01*
G01X1296203Y250513D02*
Y253013D01*
X1295162D01*
X1294828Y252888D01*
X1294620Y252721D01*
X1294537Y252388D01*
X1294620Y252055D01*
X1294870Y251846D01*
X1295162Y251721D01*
X1296203D01*
G01X1295162D02*
X1294537Y250513D01*
G01X1293187Y251013D02*
X1292937Y250721D01*
X1292603Y250555D01*
X1292228Y250513D01*
X1291895Y250555D01*
X1291562Y250763D01*
X1291353Y251013D01*
X1291312Y251263D01*
X1291395Y251555D01*
X1291687Y251763D01*
X1291978Y251846D01*
X1292353D01*
G01X1291978D02*
X1291728Y251971D01*
X1291520Y252180D01*
X1291437Y252430D01*
X1291520Y252680D01*
X1291728Y252888D01*
X1292103Y253013D01*
X1292478Y252971D01*
X1292853Y252805D01*
G01X1290003Y250513D02*
Y253013D01*
X1289003D01*
X1288670Y252888D01*
X1288420Y252596D01*
X1288337Y252263D01*
X1288420Y251930D01*
X1288628Y251680D01*
X1289003Y251555D01*
X1290003D01*
G01X1286862D02*
X1286570Y251846D01*
X1286320Y252013D01*
X1285987Y252096D01*
X1285695Y252013D01*
X1285487Y251846D01*
X1285320Y251596D01*
X1285278Y251305D01*
X1285320Y251055D01*
X1285487Y250805D01*
X1285737Y250596D01*
X1286028Y250513D01*
X1286362Y250596D01*
X1286653Y250846D01*
X1286820Y251221D01*
X1286862Y251638D01*
X1286778Y252180D01*
X1286653Y252471D01*
X1286445Y252763D01*
X1286153Y252971D01*
X1285862Y253013D01*
X1285570Y252930D01*
X1285362Y252721D01*
G01X1282970Y253013D02*
X1283303Y252930D01*
X1283553Y252721D01*
X1283720Y252471D01*
X1283845Y252138D01*
X1283887Y251763D01*
X1283845Y251388D01*
X1283720Y251055D01*
X1283553Y250805D01*
X1283303Y250596D01*
X1282970Y250513D01*
X1282637Y250596D01*
X1282387Y250805D01*
X1282220Y251055D01*
X1282095Y251388D01*
X1282053Y251763D01*
X1282095Y252138D01*
X1282220Y252471D01*
X1282387Y252721D01*
X1282637Y252930D01*
X1282970Y253013D01*
G01X1296198Y275933D02*
Y278433D01*
X1295157D01*
X1294823Y278308D01*
X1294615Y278141D01*
X1294532Y277808D01*
X1294615Y277475D01*
X1294865Y277266D01*
X1295157Y277141D01*
X1296198D01*
G01X1295157D02*
X1294532Y275933D01*
G01X1291765D02*
Y278433D01*
X1293307Y276641D01*
X1291223D01*
G01X1289998Y275933D02*
Y278433D01*
X1288998D01*
X1288665Y278308D01*
X1288415Y278016D01*
X1288332Y277683D01*
X1288415Y277350D01*
X1288623Y277100D01*
X1288998Y276975D01*
X1289998D01*
G01X1286065Y275933D02*
Y278433D01*
X1286565Y277933D01*
G01Y275933D02*
X1285565D01*
G01X1283882Y276308D02*
X1283632Y276100D01*
X1283340Y275975D01*
X1282965Y275933D01*
X1282590Y276016D01*
X1282298Y276183D01*
X1282090Y276475D01*
X1282048Y276808D01*
X1282132Y277141D01*
X1282340Y277350D01*
X1282632Y277516D01*
X1282923Y277558D01*
X1283215Y277516D01*
X1283590Y277350D01*
X1283465Y278433D01*
X1282340D01*
G01X1296198Y271933D02*
Y274433D01*
X1295157D01*
X1294823Y274308D01*
X1294615Y274141D01*
X1294532Y273808D01*
X1294615Y273475D01*
X1294865Y273266D01*
X1295157Y273141D01*
X1296198D01*
G01X1295157D02*
X1294532Y271933D01*
G01X1291765D02*
Y274433D01*
X1293307Y272641D01*
X1291223D01*
G01X1289998Y271933D02*
Y274433D01*
X1288998D01*
X1288665Y274308D01*
X1288415Y274016D01*
X1288332Y273683D01*
X1288415Y273350D01*
X1288623Y273100D01*
X1288998Y272975D01*
X1289998D01*
G01X1286065Y271933D02*
Y274433D01*
X1286565Y273933D01*
G01Y271933D02*
X1285565D01*
G01X1283757Y274016D02*
X1283507Y274266D01*
X1283215Y274391D01*
X1282882Y274433D01*
X1282465Y274350D01*
X1282173Y274141D01*
X1282090Y273891D01*
X1282132Y273641D01*
X1282298Y273433D01*
X1283132Y273016D01*
X1283507Y272725D01*
X1283757Y272308D01*
X1283840Y271933D01*
X1282090D01*
G01X1296144Y268468D02*
Y270968D01*
X1295103D01*
X1294769Y270843D01*
X1294561Y270676D01*
X1294478Y270343D01*
X1294561Y270010D01*
X1294811Y269801D01*
X1295103Y269676D01*
X1296144D01*
G01X1295103D02*
X1294478Y268468D01*
G01X1291711D02*
Y270968D01*
X1293253Y269176D01*
X1291169D01*
G01X1289944Y268468D02*
Y270968D01*
X1288944D01*
X1288611Y270843D01*
X1288361Y270551D01*
X1288278Y270218D01*
X1288361Y269885D01*
X1288569Y269635D01*
X1288944Y269510D01*
X1289944D01*
G01X1286803Y270551D02*
X1286553Y270801D01*
X1286261Y270926D01*
X1285928Y270968D01*
X1285511Y270885D01*
X1285219Y270676D01*
X1285136Y270426D01*
X1285178Y270176D01*
X1285344Y269968D01*
X1286178Y269551D01*
X1286553Y269260D01*
X1286803Y268843D01*
X1286886Y268468D01*
X1285136D01*
G01X1282911Y270968D02*
X1283244Y270885D01*
X1283494Y270676D01*
X1283661Y270426D01*
X1283786Y270093D01*
X1283828Y269718D01*
X1283786Y269343D01*
X1283661Y269010D01*
X1283494Y268760D01*
X1283244Y268551D01*
X1282911Y268468D01*
X1282578Y268551D01*
X1282328Y268760D01*
X1282161Y269010D01*
X1282036Y269343D01*
X1281994Y269718D01*
X1282036Y270093D01*
X1282161Y270426D01*
X1282328Y270676D01*
X1282578Y270885D01*
X1282911Y270968D01*
G01X1296500Y265032D02*
Y267532D01*
X1295459D01*
X1295125Y267407D01*
X1294917Y267240D01*
X1294834Y266907D01*
X1294917Y266574D01*
X1295167Y266365D01*
X1295459Y266240D01*
X1296500D01*
G01X1295459D02*
X1294834Y265032D01*
G01X1293484Y265532D02*
X1293234Y265240D01*
X1292900Y265074D01*
X1292525Y265032D01*
X1292192Y265074D01*
X1291859Y265282D01*
X1291650Y265532D01*
X1291609Y265782D01*
X1291692Y266074D01*
X1291984Y266282D01*
X1292275Y266365D01*
X1292650D01*
G01X1292275D02*
X1292025Y266490D01*
X1291817Y266699D01*
X1291734Y266949D01*
X1291817Y267199D01*
X1292025Y267407D01*
X1292400Y267532D01*
X1292775Y267490D01*
X1293150Y267324D01*
G01X1290300Y265032D02*
Y267532D01*
X1289259D01*
X1288925Y267407D01*
X1288717Y267240D01*
X1288634Y266907D01*
X1288717Y266574D01*
X1288967Y266365D01*
X1289259Y266240D01*
X1290300D01*
G01X1289259D02*
X1288634Y265032D01*
G01X1286367D02*
Y267532D01*
X1286867Y267032D01*
G01Y265032D02*
X1285867D01*
G01X1284184Y265532D02*
X1283934Y265240D01*
X1283600Y265074D01*
X1283225Y265032D01*
X1282892Y265074D01*
X1282559Y265282D01*
X1282350Y265532D01*
X1282309Y265782D01*
X1282392Y266074D01*
X1282684Y266282D01*
X1282975Y266365D01*
X1283350D01*
G01X1282975D02*
X1282725Y266490D01*
X1282517Y266699D01*
X1282434Y266949D01*
X1282517Y267199D01*
X1282725Y267407D01*
X1283100Y267532D01*
X1283475Y267490D01*
X1283850Y267324D01*
G01X1334259Y246767D02*
X1334384Y246517D01*
X1334467Y246225D01*
Y245892D01*
X1334342Y245517D01*
X1334134Y245225D01*
X1333884Y245017D01*
X1333467Y244850D01*
X1333092Y244808D01*
X1332717Y244892D01*
X1332467Y245017D01*
X1332217Y245267D01*
X1332050Y245558D01*
X1331967Y245850D01*
Y246142D01*
X1332050Y246433D01*
X1332175Y246683D01*
X1332342Y246892D01*
G01X1334050Y248158D02*
X1334300Y248408D01*
X1334425Y248700D01*
X1334467Y249033D01*
X1334384Y249450D01*
X1334175Y249742D01*
X1333925Y249825D01*
X1333675Y249783D01*
X1333467Y249617D01*
X1333050Y248783D01*
X1332759Y248408D01*
X1332342Y248158D01*
X1331967Y248075D01*
Y249825D01*
G01X1334467Y251133D02*
X1332675D01*
X1332300Y251300D01*
X1332050Y251633D01*
X1331967Y252050D01*
X1332050Y252467D01*
X1332300Y252800D01*
X1332675Y252967D01*
X1334467D01*
G01X1331967Y255067D02*
X1332509Y255150D01*
X1332967Y255275D01*
X1333384Y255442D01*
X1333842Y255650D01*
X1334467Y255983D01*
Y254317D01*
G01X1338159Y246267D02*
X1338284Y246017D01*
X1338367Y245725D01*
Y245392D01*
X1338242Y245017D01*
X1338034Y244725D01*
X1337784Y244517D01*
X1337367Y244350D01*
X1336992Y244308D01*
X1336617Y244392D01*
X1336367Y244517D01*
X1336117Y244767D01*
X1335950Y245058D01*
X1335867Y245350D01*
Y245642D01*
X1335950Y245933D01*
X1336075Y246183D01*
X1336242Y246392D01*
G01X1337950Y247658D02*
X1338200Y247908D01*
X1338325Y248200D01*
X1338367Y248533D01*
X1338284Y248950D01*
X1338075Y249242D01*
X1337825Y249325D01*
X1337575Y249283D01*
X1337367Y249117D01*
X1336950Y248283D01*
X1336659Y247908D01*
X1336242Y247658D01*
X1335867Y247575D01*
Y249325D01*
G01X1338367Y250633D02*
X1336575D01*
X1336200Y250800D01*
X1335950Y251133D01*
X1335867Y251550D01*
X1335950Y251967D01*
X1336200Y252300D01*
X1336575Y252467D01*
X1338367D01*
G01X1335867Y254650D02*
X1335909Y254942D01*
X1336034Y255275D01*
X1336242Y255483D01*
X1336534Y255567D01*
X1336825Y255483D01*
X1337075Y255233D01*
X1337200Y254858D01*
Y254442D01*
X1337284Y254192D01*
X1337492Y253983D01*
X1337784Y253900D01*
X1338075Y254025D01*
X1338284Y254317D01*
X1338367Y254650D01*
X1338284Y254983D01*
X1338075Y255275D01*
X1337784Y255400D01*
X1337492Y255317D01*
X1337284Y255108D01*
X1337200Y254858D01*
Y254442D01*
X1337075Y254067D01*
X1336825Y253817D01*
X1336534Y253733D01*
X1336242Y253817D01*
X1336034Y254025D01*
X1335909Y254358D01*
X1335867Y254650D01*
G01X1343659Y245867D02*
X1343784Y245617D01*
X1343867Y245325D01*
Y244992D01*
X1343742Y244617D01*
X1343534Y244325D01*
X1343284Y244117D01*
X1342867Y243950D01*
X1342492Y243908D01*
X1342117Y243992D01*
X1341867Y244117D01*
X1341617Y244367D01*
X1341450Y244658D01*
X1341367Y244950D01*
Y245242D01*
X1341450Y245533D01*
X1341575Y245783D01*
X1341742Y245992D01*
G01X1343450Y247258D02*
X1343700Y247508D01*
X1343825Y247800D01*
X1343867Y248133D01*
X1343784Y248550D01*
X1343575Y248842D01*
X1343325Y248925D01*
X1343075Y248883D01*
X1342867Y248717D01*
X1342450Y247883D01*
X1342159Y247508D01*
X1341742Y247258D01*
X1341367Y247175D01*
Y248925D01*
G01X1343867Y250233D02*
X1342075D01*
X1341700Y250400D01*
X1341450Y250733D01*
X1341367Y251150D01*
X1341450Y251567D01*
X1341700Y251900D01*
X1342075Y252067D01*
X1343867D01*
G01X1341659Y253542D02*
X1341450Y253833D01*
X1341367Y254167D01*
X1341450Y254500D01*
X1341700Y254792D01*
X1342075Y255000D01*
X1342450Y255083D01*
X1342909D01*
X1343284Y255000D01*
X1343617Y254792D01*
X1343784Y254542D01*
X1343867Y254250D01*
X1343784Y253917D01*
X1343617Y253667D01*
X1343367Y253500D01*
X1343034Y253417D01*
X1342742Y253500D01*
X1342450Y253708D01*
X1342284Y253958D01*
X1342242Y254250D01*
X1342325Y254583D01*
X1342534Y254833D01*
X1342909Y255083D01*
G01X1317262Y245290D02*
X1317387Y245040D01*
X1317470Y244748D01*
Y244415D01*
X1317345Y244040D01*
X1317137Y243748D01*
X1316887Y243540D01*
X1316470Y243373D01*
X1316095Y243331D01*
X1315720Y243415D01*
X1315470Y243540D01*
X1315220Y243790D01*
X1315053Y244081D01*
X1314970Y244373D01*
Y244665D01*
X1315053Y244956D01*
X1315178Y245206D01*
X1315345Y245415D01*
G01X1317053Y246681D02*
X1317303Y246931D01*
X1317428Y247223D01*
X1317470Y247556D01*
X1317387Y247973D01*
X1317178Y248265D01*
X1316928Y248348D01*
X1316678Y248306D01*
X1316470Y248140D01*
X1316053Y247306D01*
X1315762Y246931D01*
X1315345Y246681D01*
X1314970Y246598D01*
Y248348D01*
G01X1317470Y249656D02*
X1315678D01*
X1315303Y249823D01*
X1315053Y250156D01*
X1314970Y250573D01*
X1315053Y250990D01*
X1315303Y251323D01*
X1315678Y251490D01*
X1317470D01*
G01X1314970Y254173D02*
X1317470D01*
X1315678Y252631D01*
Y254715D01*
G01X1321901Y246216D02*
X1322026Y245966D01*
X1322109Y245674D01*
Y245341D01*
X1321984Y244966D01*
X1321776Y244674D01*
X1321526Y244466D01*
X1321109Y244299D01*
X1320734Y244257D01*
X1320359Y244341D01*
X1320109Y244466D01*
X1319859Y244716D01*
X1319692Y245007D01*
X1319609Y245299D01*
Y245591D01*
X1319692Y245882D01*
X1319817Y246132D01*
X1319984Y246341D01*
G01X1321692Y247607D02*
X1321942Y247857D01*
X1322067Y248149D01*
X1322109Y248482D01*
X1322026Y248899D01*
X1321817Y249191D01*
X1321567Y249274D01*
X1321317Y249232D01*
X1321109Y249066D01*
X1320692Y248232D01*
X1320401Y247857D01*
X1319984Y247607D01*
X1319609Y247524D01*
Y249274D01*
G01X1322109Y250582D02*
X1320317D01*
X1319942Y250749D01*
X1319692Y251082D01*
X1319609Y251499D01*
X1319692Y251916D01*
X1319942Y252249D01*
X1320317Y252416D01*
X1322109D01*
G01X1319984Y253682D02*
X1319776Y253932D01*
X1319651Y254224D01*
X1319609Y254599D01*
X1319692Y254974D01*
X1319859Y255266D01*
X1320151Y255474D01*
X1320484Y255516D01*
X1320817Y255432D01*
X1321026Y255224D01*
X1321192Y254932D01*
X1321234Y254641D01*
X1321192Y254349D01*
X1321026Y253974D01*
X1322109Y254099D01*
Y255224D01*
G01X1327614Y246606D02*
X1327739Y246356D01*
X1327822Y246064D01*
Y245731D01*
X1327697Y245356D01*
X1327489Y245064D01*
X1327239Y244856D01*
X1326822Y244689D01*
X1326447Y244647D01*
X1326072Y244731D01*
X1325822Y244856D01*
X1325572Y245106D01*
X1325405Y245397D01*
X1325322Y245689D01*
Y245981D01*
X1325405Y246272D01*
X1325530Y246522D01*
X1325697Y246731D01*
G01X1327405Y247997D02*
X1327655Y248247D01*
X1327780Y248539D01*
X1327822Y248872D01*
X1327739Y249289D01*
X1327530Y249581D01*
X1327280Y249664D01*
X1327030Y249622D01*
X1326822Y249456D01*
X1326405Y248622D01*
X1326114Y248247D01*
X1325697Y247997D01*
X1325322Y247914D01*
Y249664D01*
G01X1327822Y250972D02*
X1326030D01*
X1325655Y251139D01*
X1325405Y251472D01*
X1325322Y251889D01*
X1325405Y252306D01*
X1325655Y252639D01*
X1326030Y252806D01*
X1327822D01*
G01X1326364Y254197D02*
X1326655Y254489D01*
X1326822Y254739D01*
X1326905Y255072D01*
X1326822Y255364D01*
X1326655Y255572D01*
X1326405Y255739D01*
X1326114Y255781D01*
X1325864Y255739D01*
X1325614Y255572D01*
X1325405Y255322D01*
X1325322Y255031D01*
X1325405Y254697D01*
X1325655Y254406D01*
X1326030Y254239D01*
X1326447Y254197D01*
X1326989Y254281D01*
X1327280Y254406D01*
X1327572Y254614D01*
X1327780Y254906D01*
X1327822Y255197D01*
X1327739Y255489D01*
X1327530Y255697D01*
G01X1313784Y245290D02*
X1313909Y245040D01*
X1313992Y244748D01*
Y244415D01*
X1313867Y244040D01*
X1313659Y243748D01*
X1313409Y243540D01*
X1312992Y243373D01*
X1312617Y243331D01*
X1312242Y243415D01*
X1311992Y243540D01*
X1311742Y243790D01*
X1311575Y244081D01*
X1311492Y244373D01*
Y244665D01*
X1311575Y244956D01*
X1311700Y245206D01*
X1311867Y245415D01*
G01X1313575Y246681D02*
X1313825Y246931D01*
X1313950Y247223D01*
X1313992Y247556D01*
X1313909Y247973D01*
X1313700Y248265D01*
X1313450Y248348D01*
X1313200Y248306D01*
X1312992Y248140D01*
X1312575Y247306D01*
X1312284Y246931D01*
X1311867Y246681D01*
X1311492Y246598D01*
Y248348D01*
G01X1313992Y249656D02*
X1312200D01*
X1311825Y249823D01*
X1311575Y250156D01*
X1311492Y250573D01*
X1311575Y250990D01*
X1311825Y251323D01*
X1312200Y251490D01*
X1313992D01*
G01X1311992Y252756D02*
X1311700Y253006D01*
X1311534Y253340D01*
X1311492Y253715D01*
X1311534Y254048D01*
X1311742Y254381D01*
X1311992Y254590D01*
X1312242Y254631D01*
X1312534Y254548D01*
X1312742Y254256D01*
X1312825Y253965D01*
Y253590D01*
G01Y253965D02*
X1312950Y254215D01*
X1313159Y254423D01*
X1313409Y254506D01*
X1313659Y254423D01*
X1313867Y254215D01*
X1313992Y253840D01*
X1313950Y253465D01*
X1313784Y253090D01*
G01X1380300Y312700D02*
X1421000D01*
Y297200D01*
X1329500D01*
Y312700D01*
X1340600D01*
G01X1330200Y318667D02*
X1332700D01*
Y319708D01*
X1332575Y320042D01*
X1332408Y320250D01*
X1332075Y320333D01*
X1331742Y320250D01*
X1331533Y320000D01*
X1331408Y319708D01*
Y318667D01*
G01Y319708D02*
X1330200Y320333D01*
G01X1330700Y321683D02*
X1330408Y321933D01*
X1330242Y322267D01*
X1330200Y322642D01*
X1330242Y322975D01*
X1330450Y323308D01*
X1330700Y323517D01*
X1330950Y323558D01*
X1331242Y323475D01*
X1331450Y323183D01*
X1331533Y322892D01*
Y322517D01*
G01Y322892D02*
X1331658Y323142D01*
X1331867Y323350D01*
X1332117Y323433D01*
X1332367Y323350D01*
X1332575Y323142D01*
X1332700Y322767D01*
X1332658Y322392D01*
X1332492Y322017D01*
G01X1330200Y324867D02*
X1332700D01*
Y325867D01*
X1332575Y326200D01*
X1332283Y326450D01*
X1331950Y326533D01*
X1331617Y326450D01*
X1331367Y326242D01*
X1331242Y325867D01*
Y324867D01*
G01X1332283Y328008D02*
X1332533Y328258D01*
X1332658Y328550D01*
X1332700Y328883D01*
X1332617Y329300D01*
X1332408Y329592D01*
X1332158Y329675D01*
X1331908Y329633D01*
X1331700Y329467D01*
X1331283Y328633D01*
X1330992Y328258D01*
X1330575Y328008D01*
X1330200Y327925D01*
Y329675D01*
G01X1330575Y330983D02*
X1330367Y331233D01*
X1330242Y331525D01*
X1330200Y331900D01*
X1330283Y332275D01*
X1330450Y332567D01*
X1330742Y332775D01*
X1331075Y332817D01*
X1331408Y332733D01*
X1331617Y332525D01*
X1331783Y332233D01*
X1331825Y331942D01*
X1331783Y331650D01*
X1331617Y331275D01*
X1332700Y331400D01*
Y332525D01*
G01X1318933Y326150D02*
Y328650D01*
X1317892D01*
X1317558Y328525D01*
X1317350Y328358D01*
X1317267Y328025D01*
X1317350Y327692D01*
X1317600Y327483D01*
X1317892Y327358D01*
X1318933D01*
G01X1317892D02*
X1317267Y326150D01*
G01X1315917Y326650D02*
X1315667Y326358D01*
X1315333Y326192D01*
X1314958Y326150D01*
X1314625Y326192D01*
X1314292Y326400D01*
X1314083Y326650D01*
X1314042Y326900D01*
X1314125Y327192D01*
X1314417Y327400D01*
X1314708Y327483D01*
X1315083D01*
G01X1314708D02*
X1314458Y327608D01*
X1314250Y327817D01*
X1314167Y328067D01*
X1314250Y328317D01*
X1314458Y328525D01*
X1314833Y328650D01*
X1315208Y328608D01*
X1315583Y328442D01*
G01X1312733Y326150D02*
Y328650D01*
X1311733D01*
X1311400Y328525D01*
X1311150Y328233D01*
X1311067Y327900D01*
X1311150Y327567D01*
X1311358Y327317D01*
X1311733Y327192D01*
X1312733D01*
G01X1309592Y328233D02*
X1309342Y328483D01*
X1309050Y328608D01*
X1308717Y328650D01*
X1308300Y328567D01*
X1308008Y328358D01*
X1307925Y328108D01*
X1307967Y327858D01*
X1308133Y327650D01*
X1308967Y327233D01*
X1309342Y326942D01*
X1309592Y326525D01*
X1309675Y326150D01*
X1307925D01*
G01X1305700D02*
Y328650D01*
X1306200Y328150D01*
G01Y326150D02*
X1305200D01*
G01X1319033Y329700D02*
Y332200D01*
X1317992D01*
X1317658Y332075D01*
X1317450Y331908D01*
X1317367Y331575D01*
X1317450Y331242D01*
X1317700Y331033D01*
X1317992Y330908D01*
X1319033D01*
G01X1317992D02*
X1317367Y329700D01*
G01X1316017Y330200D02*
X1315767Y329908D01*
X1315433Y329742D01*
X1315058Y329700D01*
X1314725Y329742D01*
X1314392Y329950D01*
X1314183Y330200D01*
X1314142Y330450D01*
X1314225Y330742D01*
X1314517Y330950D01*
X1314808Y331033D01*
X1315183D01*
G01X1314808D02*
X1314558Y331158D01*
X1314350Y331367D01*
X1314267Y331617D01*
X1314350Y331867D01*
X1314558Y332075D01*
X1314933Y332200D01*
X1315308Y332158D01*
X1315683Y331992D01*
G01X1312833Y329700D02*
Y332200D01*
X1311833D01*
X1311500Y332075D01*
X1311250Y331783D01*
X1311167Y331450D01*
X1311250Y331117D01*
X1311458Y330867D01*
X1311833Y330742D01*
X1312833D01*
G01X1308900Y329700D02*
Y332200D01*
X1309400Y331700D01*
G01Y329700D02*
X1308400D01*
G01X1305800D02*
X1305508Y329742D01*
X1305175Y329867D01*
X1304967Y330075D01*
X1304883Y330367D01*
X1304967Y330658D01*
X1305217Y330908D01*
X1305592Y331033D01*
X1306008D01*
X1306258Y331117D01*
X1306467Y331325D01*
X1306550Y331617D01*
X1306425Y331908D01*
X1306133Y332117D01*
X1305800Y332200D01*
X1305467Y332117D01*
X1305175Y331908D01*
X1305050Y331617D01*
X1305133Y331325D01*
X1305342Y331117D01*
X1305592Y331033D01*
X1306008D01*
X1306383Y330908D01*
X1306633Y330658D01*
X1306717Y330367D01*
X1306633Y330075D01*
X1306425Y329867D01*
X1306092Y329742D01*
X1305800Y329700D01*
G01X1325900Y311167D02*
X1328400D01*
Y312208D01*
X1328275Y312542D01*
X1328108Y312750D01*
X1327775Y312833D01*
X1327442Y312750D01*
X1327233Y312500D01*
X1327108Y312208D01*
Y311167D01*
G01Y312208D02*
X1325900Y312833D01*
G01X1326400Y314183D02*
X1326108Y314433D01*
X1325942Y314767D01*
X1325900Y315142D01*
X1325942Y315475D01*
X1326150Y315808D01*
X1326400Y316017D01*
X1326650Y316058D01*
X1326942Y315975D01*
X1327150Y315683D01*
X1327233Y315392D01*
Y315017D01*
G01Y315392D02*
X1327358Y315642D01*
X1327567Y315850D01*
X1327817Y315933D01*
X1328067Y315850D01*
X1328275Y315642D01*
X1328400Y315267D01*
X1328358Y314892D01*
X1328192Y314517D01*
G01X1325900Y317367D02*
X1328400D01*
Y318367D01*
X1328275Y318700D01*
X1327983Y318950D01*
X1327650Y319033D01*
X1327317Y318950D01*
X1327067Y318742D01*
X1326942Y318367D01*
Y317367D01*
G01X1327983Y320508D02*
X1328233Y320758D01*
X1328358Y321050D01*
X1328400Y321383D01*
X1328317Y321800D01*
X1328108Y322092D01*
X1327858Y322175D01*
X1327608Y322133D01*
X1327400Y321967D01*
X1326983Y321133D01*
X1326692Y320758D01*
X1326275Y320508D01*
X1325900Y320425D01*
Y322175D01*
G01X1328400Y324400D02*
X1328317Y324067D01*
X1328108Y323817D01*
X1327858Y323650D01*
X1327525Y323525D01*
X1327150Y323483D01*
X1326775Y323525D01*
X1326442Y323650D01*
X1326192Y323817D01*
X1325983Y324067D01*
X1325900Y324400D01*
X1325983Y324733D01*
X1326192Y324983D01*
X1326442Y325150D01*
X1326775Y325275D01*
X1327150Y325317D01*
X1327525Y325275D01*
X1327858Y325150D01*
X1328108Y324983D01*
X1328317Y324733D01*
X1328400Y324400D01*
G01X1319183Y322550D02*
Y325050D01*
X1318142D01*
X1317808Y324925D01*
X1317600Y324758D01*
X1317517Y324425D01*
X1317600Y324092D01*
X1317850Y323883D01*
X1318142Y323758D01*
X1319183D01*
G01X1318142D02*
X1317517Y322550D01*
G01X1316167Y323050D02*
X1315917Y322758D01*
X1315583Y322592D01*
X1315208Y322550D01*
X1314875Y322592D01*
X1314542Y322800D01*
X1314333Y323050D01*
X1314292Y323300D01*
X1314375Y323592D01*
X1314667Y323800D01*
X1314958Y323883D01*
X1315333D01*
G01X1314958D02*
X1314708Y324008D01*
X1314500Y324217D01*
X1314417Y324467D01*
X1314500Y324717D01*
X1314708Y324925D01*
X1315083Y325050D01*
X1315458Y325008D01*
X1315833Y324842D01*
G01X1312983Y322550D02*
Y325050D01*
X1311983D01*
X1311650Y324925D01*
X1311400Y324633D01*
X1311317Y324300D01*
X1311400Y323967D01*
X1311608Y323717D01*
X1311983Y323592D01*
X1312983D01*
G01X1309842Y324633D02*
X1309592Y324883D01*
X1309300Y325008D01*
X1308967Y325050D01*
X1308550Y324967D01*
X1308258Y324758D01*
X1308175Y324508D01*
X1308217Y324258D01*
X1308383Y324050D01*
X1309217Y323633D01*
X1309592Y323342D01*
X1309842Y322925D01*
X1309925Y322550D01*
X1308175D01*
G01X1306742Y323592D02*
X1306450Y323883D01*
X1306200Y324050D01*
X1305867Y324133D01*
X1305575Y324050D01*
X1305367Y323883D01*
X1305200Y323633D01*
X1305158Y323342D01*
X1305200Y323092D01*
X1305367Y322842D01*
X1305617Y322633D01*
X1305908Y322550D01*
X1306242Y322633D01*
X1306533Y322883D01*
X1306700Y323258D01*
X1306742Y323675D01*
X1306658Y324217D01*
X1306533Y324508D01*
X1306325Y324800D01*
X1306033Y325008D01*
X1305742Y325050D01*
X1305450Y324967D01*
X1305242Y324758D01*
G01X1295680Y340442D02*
X1298180D01*
Y341483D01*
X1298055Y341817D01*
X1297888Y342025D01*
X1297555Y342108D01*
X1297222Y342025D01*
X1297013Y341775D01*
X1296888Y341483D01*
Y340442D01*
G01Y341483D02*
X1295680Y342108D01*
G01X1296180Y343458D02*
X1295888Y343708D01*
X1295722Y344042D01*
X1295680Y344417D01*
X1295722Y344750D01*
X1295930Y345083D01*
X1296180Y345292D01*
X1296430Y345333D01*
X1296722Y345250D01*
X1296930Y344958D01*
X1297013Y344667D01*
Y344292D01*
G01Y344667D02*
X1297138Y344917D01*
X1297347Y345125D01*
X1297597Y345208D01*
X1297847Y345125D01*
X1298055Y344917D01*
X1298180Y344542D01*
X1298138Y344167D01*
X1297972Y343792D01*
G01X1295680Y346642D02*
X1298180D01*
Y347642D01*
X1298055Y347975D01*
X1297763Y348225D01*
X1297430Y348308D01*
X1297097Y348225D01*
X1296847Y348017D01*
X1296722Y347642D01*
Y346642D01*
G01X1295680Y350575D02*
X1298180D01*
X1297680Y350075D01*
G01X1295680D02*
Y351075D01*
G01X1296180Y352758D02*
X1295888Y353008D01*
X1295722Y353342D01*
X1295680Y353717D01*
X1295722Y354050D01*
X1295930Y354383D01*
X1296180Y354592D01*
X1296430Y354633D01*
X1296722Y354550D01*
X1296930Y354258D01*
X1297013Y353967D01*
Y353592D01*
G01Y353967D02*
X1297138Y354217D01*
X1297347Y354425D01*
X1297597Y354508D01*
X1297847Y354425D01*
X1298055Y354217D01*
X1298180Y353842D01*
X1298138Y353467D01*
X1297972Y353092D01*
G01X1314565Y339564D02*
Y342064D01*
X1313524D01*
X1313190Y341939D01*
X1312982Y341772D01*
X1312899Y341439D01*
X1312982Y341106D01*
X1313232Y340897D01*
X1313524Y340772D01*
X1314565D01*
G01X1313524D02*
X1312899Y339564D01*
G01X1311549Y340064D02*
X1311299Y339772D01*
X1310965Y339606D01*
X1310590Y339564D01*
X1310257Y339606D01*
X1309924Y339814D01*
X1309715Y340064D01*
X1309674Y340314D01*
X1309757Y340606D01*
X1310049Y340814D01*
X1310340Y340897D01*
X1310715D01*
G01X1310340D02*
X1310090Y341022D01*
X1309882Y341231D01*
X1309799Y341481D01*
X1309882Y341731D01*
X1310090Y341939D01*
X1310465Y342064D01*
X1310840Y342022D01*
X1311215Y341856D01*
G01X1308365Y339564D02*
Y342064D01*
X1307365D01*
X1307032Y341939D01*
X1306782Y341647D01*
X1306699Y341314D01*
X1306782Y340981D01*
X1306990Y340731D01*
X1307365Y340606D01*
X1308365D01*
G01X1304432Y339564D02*
Y342064D01*
X1304932Y341564D01*
G01Y339564D02*
X1303932D01*
G01X1302249Y339939D02*
X1301999Y339731D01*
X1301707Y339606D01*
X1301332Y339564D01*
X1300957Y339647D01*
X1300665Y339814D01*
X1300457Y340106D01*
X1300415Y340439D01*
X1300499Y340772D01*
X1300707Y340981D01*
X1300999Y341147D01*
X1301290Y341189D01*
X1301582Y341147D01*
X1301957Y340981D01*
X1301832Y342064D01*
X1300707D01*
G01X1301536Y324441D02*
X1304036D01*
Y325482D01*
X1303911Y325816D01*
X1303744Y326024D01*
X1303411Y326107D01*
X1303078Y326024D01*
X1302869Y325774D01*
X1302744Y325482D01*
Y324441D01*
G01Y325482D02*
X1301536Y326107D01*
G01X1302036Y327457D02*
X1301744Y327707D01*
X1301578Y328041D01*
X1301536Y328416D01*
X1301578Y328749D01*
X1301786Y329082D01*
X1302036Y329291D01*
X1302286Y329332D01*
X1302578Y329249D01*
X1302786Y328957D01*
X1302869Y328666D01*
Y328291D01*
G01Y328666D02*
X1302994Y328916D01*
X1303203Y329124D01*
X1303453Y329207D01*
X1303703Y329124D01*
X1303911Y328916D01*
X1304036Y328541D01*
X1303994Y328166D01*
X1303828Y327791D01*
G01X1301536Y330641D02*
X1304036D01*
Y331641D01*
X1303911Y331974D01*
X1303619Y332224D01*
X1303286Y332307D01*
X1302953Y332224D01*
X1302703Y332016D01*
X1302578Y331641D01*
Y330641D01*
G01X1301536Y334574D02*
X1304036D01*
X1303536Y334074D01*
G01X1301536D02*
Y335074D01*
G01Y337591D02*
X1302078Y337674D01*
X1302536Y337799D01*
X1302953Y337966D01*
X1303411Y338174D01*
X1304036Y338507D01*
Y336841D01*
G01X1293467Y324237D02*
X1295967D01*
Y325278D01*
X1295842Y325612D01*
X1295675Y325820D01*
X1295342Y325903D01*
X1295009Y325820D01*
X1294800Y325570D01*
X1294675Y325278D01*
Y324237D01*
G01Y325278D02*
X1293467Y325903D01*
G01X1293967Y327253D02*
X1293675Y327503D01*
X1293509Y327837D01*
X1293467Y328212D01*
X1293509Y328545D01*
X1293717Y328878D01*
X1293967Y329087D01*
X1294217Y329128D01*
X1294509Y329045D01*
X1294717Y328753D01*
X1294800Y328462D01*
Y328087D01*
G01Y328462D02*
X1294925Y328712D01*
X1295134Y328920D01*
X1295384Y329003D01*
X1295634Y328920D01*
X1295842Y328712D01*
X1295967Y328337D01*
X1295925Y327962D01*
X1295759Y327587D01*
G01X1293467Y330437D02*
X1295967D01*
Y331437D01*
X1295842Y331770D01*
X1295550Y332020D01*
X1295217Y332103D01*
X1294884Y332020D01*
X1294634Y331812D01*
X1294509Y331437D01*
Y330437D01*
G01X1293842Y333453D02*
X1293634Y333703D01*
X1293509Y333995D01*
X1293467Y334370D01*
X1293550Y334745D01*
X1293717Y335037D01*
X1294009Y335245D01*
X1294342Y335287D01*
X1294675Y335203D01*
X1294884Y334995D01*
X1295050Y334703D01*
X1295092Y334412D01*
X1295050Y334120D01*
X1294884Y333745D01*
X1295967Y333870D01*
Y334995D01*
G01X1294509Y336678D02*
X1294800Y336970D01*
X1294967Y337220D01*
X1295050Y337553D01*
X1294967Y337845D01*
X1294800Y338053D01*
X1294550Y338220D01*
X1294259Y338262D01*
X1294009Y338220D01*
X1293759Y338053D01*
X1293550Y337803D01*
X1293467Y337512D01*
X1293550Y337178D01*
X1293800Y336887D01*
X1294175Y336720D01*
X1294592Y336678D01*
X1295134Y336762D01*
X1295425Y336887D01*
X1295717Y337095D01*
X1295925Y337387D01*
X1295967Y337678D01*
X1295884Y337970D01*
X1295675Y338178D01*
G01X1297521Y324550D02*
X1300021D01*
Y325591D01*
X1299896Y325925D01*
X1299729Y326133D01*
X1299396Y326216D01*
X1299063Y326133D01*
X1298854Y325883D01*
X1298729Y325591D01*
Y324550D01*
G01Y325591D02*
X1297521Y326216D01*
G01X1298021Y327566D02*
X1297729Y327816D01*
X1297563Y328150D01*
X1297521Y328525D01*
X1297563Y328858D01*
X1297771Y329191D01*
X1298021Y329400D01*
X1298271Y329441D01*
X1298563Y329358D01*
X1298771Y329066D01*
X1298854Y328775D01*
Y328400D01*
G01Y328775D02*
X1298979Y329025D01*
X1299188Y329233D01*
X1299438Y329316D01*
X1299688Y329233D01*
X1299896Y329025D01*
X1300021Y328650D01*
X1299979Y328275D01*
X1299813Y327900D01*
G01X1297521Y330750D02*
X1300021D01*
Y331750D01*
X1299896Y332083D01*
X1299604Y332333D01*
X1299271Y332416D01*
X1298938Y332333D01*
X1298688Y332125D01*
X1298563Y331750D01*
Y330750D01*
G01X1297896Y333766D02*
X1297688Y334016D01*
X1297563Y334308D01*
X1297521Y334683D01*
X1297604Y335058D01*
X1297771Y335350D01*
X1298063Y335558D01*
X1298396Y335600D01*
X1298729Y335516D01*
X1298938Y335308D01*
X1299104Y335016D01*
X1299146Y334725D01*
X1299104Y334433D01*
X1298938Y334058D01*
X1300021Y334183D01*
Y335308D01*
G01X1297521Y338283D02*
X1300021D01*
X1298229Y336741D01*
Y338825D01*
G01X1288079Y292041D02*
X1288204Y291791D01*
X1288287Y291499D01*
Y291166D01*
X1288162Y290791D01*
X1287954Y290499D01*
X1287704Y290291D01*
X1287287Y290124D01*
X1286912Y290082D01*
X1286537Y290166D01*
X1286287Y290291D01*
X1286037Y290541D01*
X1285870Y290832D01*
X1285787Y291124D01*
Y291416D01*
X1285870Y291707D01*
X1285995Y291957D01*
X1286162Y292166D01*
G01X1286287Y293307D02*
X1285995Y293557D01*
X1285829Y293891D01*
X1285787Y294266D01*
X1285829Y294599D01*
X1286037Y294932D01*
X1286287Y295141D01*
X1286537Y295182D01*
X1286829Y295099D01*
X1287037Y294807D01*
X1287120Y294516D01*
Y294141D01*
G01Y294516D02*
X1287245Y294766D01*
X1287454Y294974D01*
X1287704Y295057D01*
X1287954Y294974D01*
X1288162Y294766D01*
X1288287Y294391D01*
X1288245Y294016D01*
X1288079Y293641D01*
G01X1285787Y296491D02*
X1288287D01*
Y297491D01*
X1288162Y297824D01*
X1287870Y298074D01*
X1287537Y298157D01*
X1287204Y298074D01*
X1286954Y297866D01*
X1286829Y297491D01*
Y296491D01*
G01X1286287Y299507D02*
X1285995Y299757D01*
X1285829Y300091D01*
X1285787Y300466D01*
X1285829Y300799D01*
X1286037Y301132D01*
X1286287Y301341D01*
X1286537Y301382D01*
X1286829Y301299D01*
X1287037Y301007D01*
X1287120Y300716D01*
Y300341D01*
G01Y300716D02*
X1287245Y300966D01*
X1287454Y301174D01*
X1287704Y301257D01*
X1287954Y301174D01*
X1288162Y300966D01*
X1288287Y300591D01*
X1288245Y300216D01*
X1288079Y299841D01*
G01X1286829Y302732D02*
X1287120Y303024D01*
X1287287Y303274D01*
X1287370Y303607D01*
X1287287Y303899D01*
X1287120Y304107D01*
X1286870Y304274D01*
X1286579Y304316D01*
X1286329Y304274D01*
X1286079Y304107D01*
X1285870Y303857D01*
X1285787Y303566D01*
X1285870Y303232D01*
X1286120Y302941D01*
X1286495Y302774D01*
X1286912Y302732D01*
X1287454Y302816D01*
X1287745Y302941D01*
X1288037Y303149D01*
X1288245Y303441D01*
X1288287Y303732D01*
X1288204Y304024D01*
X1287995Y304232D01*
G01X1284092Y308817D02*
X1284217Y308567D01*
X1284300Y308275D01*
Y307942D01*
X1284175Y307567D01*
X1283967Y307275D01*
X1283717Y307067D01*
X1283300Y306900D01*
X1282925Y306858D01*
X1282550Y306942D01*
X1282300Y307067D01*
X1282050Y307317D01*
X1281883Y307608D01*
X1281800Y307900D01*
Y308192D01*
X1281883Y308483D01*
X1282008Y308733D01*
X1282175Y308942D01*
G01X1282300Y310083D02*
X1282008Y310333D01*
X1281842Y310667D01*
X1281800Y311042D01*
X1281842Y311375D01*
X1282050Y311708D01*
X1282300Y311917D01*
X1282550Y311958D01*
X1282842Y311875D01*
X1283050Y311583D01*
X1283133Y311292D01*
Y310917D01*
G01Y311292D02*
X1283258Y311542D01*
X1283467Y311750D01*
X1283717Y311833D01*
X1283967Y311750D01*
X1284175Y311542D01*
X1284300Y311167D01*
X1284258Y310792D01*
X1284092Y310417D01*
G01X1281800Y313267D02*
X1284300D01*
Y314267D01*
X1284175Y314600D01*
X1283883Y314850D01*
X1283550Y314933D01*
X1283217Y314850D01*
X1282967Y314642D01*
X1282842Y314267D01*
Y313267D01*
G01X1282300Y316283D02*
X1282008Y316533D01*
X1281842Y316867D01*
X1281800Y317242D01*
X1281842Y317575D01*
X1282050Y317908D01*
X1282300Y318117D01*
X1282550Y318158D01*
X1282842Y318075D01*
X1283050Y317783D01*
X1283133Y317492D01*
Y317117D01*
G01Y317492D02*
X1283258Y317742D01*
X1283467Y317950D01*
X1283717Y318033D01*
X1283967Y317950D01*
X1284175Y317742D01*
X1284300Y317367D01*
X1284258Y316992D01*
X1284092Y316617D01*
G01X1282175Y319383D02*
X1281967Y319633D01*
X1281842Y319925D01*
X1281800Y320300D01*
X1281883Y320675D01*
X1282050Y320967D01*
X1282342Y321175D01*
X1282675Y321217D01*
X1283008Y321133D01*
X1283217Y320925D01*
X1283383Y320633D01*
X1283425Y320342D01*
X1283383Y320050D01*
X1283217Y319675D01*
X1284300Y319800D01*
Y320925D01*
G01X1284079Y292041D02*
X1284204Y291791D01*
X1284287Y291499D01*
Y291166D01*
X1284162Y290791D01*
X1283954Y290499D01*
X1283704Y290291D01*
X1283287Y290124D01*
X1282912Y290082D01*
X1282537Y290166D01*
X1282287Y290291D01*
X1282037Y290541D01*
X1281870Y290832D01*
X1281787Y291124D01*
Y291416D01*
X1281870Y291707D01*
X1281995Y291957D01*
X1282162Y292166D01*
G01X1282287Y293307D02*
X1281995Y293557D01*
X1281829Y293891D01*
X1281787Y294266D01*
X1281829Y294599D01*
X1282037Y294932D01*
X1282287Y295141D01*
X1282537Y295182D01*
X1282829Y295099D01*
X1283037Y294807D01*
X1283120Y294516D01*
Y294141D01*
G01Y294516D02*
X1283245Y294766D01*
X1283454Y294974D01*
X1283704Y295057D01*
X1283954Y294974D01*
X1284162Y294766D01*
X1284287Y294391D01*
X1284245Y294016D01*
X1284079Y293641D01*
G01X1281787Y296491D02*
X1284287D01*
Y297491D01*
X1284162Y297824D01*
X1283870Y298074D01*
X1283537Y298157D01*
X1283204Y298074D01*
X1282954Y297866D01*
X1282829Y297491D01*
Y296491D01*
G01X1282287Y299507D02*
X1281995Y299757D01*
X1281829Y300091D01*
X1281787Y300466D01*
X1281829Y300799D01*
X1282037Y301132D01*
X1282287Y301341D01*
X1282537Y301382D01*
X1282829Y301299D01*
X1283037Y301007D01*
X1283120Y300716D01*
Y300341D01*
G01Y300716D02*
X1283245Y300966D01*
X1283454Y301174D01*
X1283704Y301257D01*
X1283954Y301174D01*
X1284162Y300966D01*
X1284287Y300591D01*
X1284245Y300216D01*
X1284079Y299841D01*
G01X1281787Y304024D02*
X1284287D01*
X1282495Y302482D01*
Y304566D01*
G01X1292092Y308817D02*
X1292217Y308567D01*
X1292300Y308275D01*
Y307942D01*
X1292175Y307567D01*
X1291967Y307275D01*
X1291717Y307067D01*
X1291300Y306900D01*
X1290925Y306858D01*
X1290550Y306942D01*
X1290300Y307067D01*
X1290050Y307317D01*
X1289883Y307608D01*
X1289800Y307900D01*
Y308192D01*
X1289883Y308483D01*
X1290008Y308733D01*
X1290175Y308942D01*
G01X1290300Y310083D02*
X1290008Y310333D01*
X1289842Y310667D01*
X1289800Y311042D01*
X1289842Y311375D01*
X1290050Y311708D01*
X1290300Y311917D01*
X1290550Y311958D01*
X1290842Y311875D01*
X1291050Y311583D01*
X1291133Y311292D01*
Y310917D01*
G01Y311292D02*
X1291258Y311542D01*
X1291467Y311750D01*
X1291717Y311833D01*
X1291967Y311750D01*
X1292175Y311542D01*
X1292300Y311167D01*
X1292258Y310792D01*
X1292092Y310417D01*
G01X1289800Y313267D02*
X1292300D01*
Y314267D01*
X1292175Y314600D01*
X1291883Y314850D01*
X1291550Y314933D01*
X1291217Y314850D01*
X1290967Y314642D01*
X1290842Y314267D01*
Y313267D01*
G01X1289800Y317700D02*
X1292300D01*
X1290508Y316158D01*
Y318242D01*
G01X1292300Y320300D02*
X1292217Y319967D01*
X1292008Y319717D01*
X1291758Y319550D01*
X1291425Y319425D01*
X1291050Y319383D01*
X1290675Y319425D01*
X1290342Y319550D01*
X1290092Y319717D01*
X1289883Y319967D01*
X1289800Y320300D01*
X1289883Y320633D01*
X1290092Y320883D01*
X1290342Y321050D01*
X1290675Y321175D01*
X1291050Y321217D01*
X1291425Y321175D01*
X1291758Y321050D01*
X1292008Y320883D01*
X1292217Y320633D01*
X1292300Y320300D01*
G01X1296092Y308817D02*
X1296217Y308567D01*
X1296300Y308275D01*
Y307942D01*
X1296175Y307567D01*
X1295967Y307275D01*
X1295717Y307067D01*
X1295300Y306900D01*
X1294925Y306858D01*
X1294550Y306942D01*
X1294300Y307067D01*
X1294050Y307317D01*
X1293883Y307608D01*
X1293800Y307900D01*
Y308192D01*
X1293883Y308483D01*
X1294008Y308733D01*
X1294175Y308942D01*
G01X1294300Y310083D02*
X1294008Y310333D01*
X1293842Y310667D01*
X1293800Y311042D01*
X1293842Y311375D01*
X1294050Y311708D01*
X1294300Y311917D01*
X1294550Y311958D01*
X1294842Y311875D01*
X1295050Y311583D01*
X1295133Y311292D01*
Y310917D01*
G01Y311292D02*
X1295258Y311542D01*
X1295467Y311750D01*
X1295717Y311833D01*
X1295967Y311750D01*
X1296175Y311542D01*
X1296300Y311167D01*
X1296258Y310792D01*
X1296092Y310417D01*
G01X1293800Y313267D02*
X1296300D01*
Y314267D01*
X1296175Y314600D01*
X1295883Y314850D01*
X1295550Y314933D01*
X1295217Y314850D01*
X1294967Y314642D01*
X1294842Y314267D01*
Y313267D01*
G01X1294300Y316283D02*
X1294008Y316533D01*
X1293842Y316867D01*
X1293800Y317242D01*
X1293842Y317575D01*
X1294050Y317908D01*
X1294300Y318117D01*
X1294550Y318158D01*
X1294842Y318075D01*
X1295050Y317783D01*
X1295133Y317492D01*
Y317117D01*
G01Y317492D02*
X1295258Y317742D01*
X1295467Y317950D01*
X1295717Y318033D01*
X1295967Y317950D01*
X1296175Y317742D01*
X1296300Y317367D01*
X1296258Y316992D01*
X1296092Y316617D01*
G01X1294092Y319592D02*
X1293883Y319883D01*
X1293800Y320217D01*
X1293883Y320550D01*
X1294133Y320842D01*
X1294508Y321050D01*
X1294883Y321133D01*
X1295342D01*
X1295717Y321050D01*
X1296050Y320842D01*
X1296217Y320592D01*
X1296300Y320300D01*
X1296217Y319967D01*
X1296050Y319717D01*
X1295800Y319550D01*
X1295467Y319467D01*
X1295175Y319550D01*
X1294883Y319758D01*
X1294717Y320008D01*
X1294675Y320300D01*
X1294758Y320633D01*
X1294967Y320883D01*
X1295342Y321133D01*
G01X1296079Y292041D02*
X1296204Y291791D01*
X1296287Y291499D01*
Y291166D01*
X1296162Y290791D01*
X1295954Y290499D01*
X1295704Y290291D01*
X1295287Y290124D01*
X1294912Y290082D01*
X1294537Y290166D01*
X1294287Y290291D01*
X1294037Y290541D01*
X1293870Y290832D01*
X1293787Y291124D01*
Y291416D01*
X1293870Y291707D01*
X1293995Y291957D01*
X1294162Y292166D01*
G01X1294287Y293307D02*
X1293995Y293557D01*
X1293829Y293891D01*
X1293787Y294266D01*
X1293829Y294599D01*
X1294037Y294932D01*
X1294287Y295141D01*
X1294537Y295182D01*
X1294829Y295099D01*
X1295037Y294807D01*
X1295120Y294516D01*
Y294141D01*
G01Y294516D02*
X1295245Y294766D01*
X1295454Y294974D01*
X1295704Y295057D01*
X1295954Y294974D01*
X1296162Y294766D01*
X1296287Y294391D01*
X1296245Y294016D01*
X1296079Y293641D01*
G01X1293787Y296491D02*
X1296287D01*
Y297491D01*
X1296162Y297824D01*
X1295870Y298074D01*
X1295537Y298157D01*
X1295204Y298074D01*
X1294954Y297866D01*
X1294829Y297491D01*
Y296491D01*
G01X1294287Y299507D02*
X1293995Y299757D01*
X1293829Y300091D01*
X1293787Y300466D01*
X1293829Y300799D01*
X1294037Y301132D01*
X1294287Y301341D01*
X1294537Y301382D01*
X1294829Y301299D01*
X1295037Y301007D01*
X1295120Y300716D01*
Y300341D01*
G01Y300716D02*
X1295245Y300966D01*
X1295454Y301174D01*
X1295704Y301257D01*
X1295954Y301174D01*
X1296162Y300966D01*
X1296287Y300591D01*
X1296245Y300216D01*
X1296079Y299841D01*
G01X1293787Y303524D02*
X1293829Y303816D01*
X1293954Y304149D01*
X1294162Y304357D01*
X1294454Y304441D01*
X1294745Y304357D01*
X1294995Y304107D01*
X1295120Y303732D01*
Y303316D01*
X1295204Y303066D01*
X1295412Y302857D01*
X1295704Y302774D01*
X1295995Y302899D01*
X1296204Y303191D01*
X1296287Y303524D01*
X1296204Y303857D01*
X1295995Y304149D01*
X1295704Y304274D01*
X1295412Y304191D01*
X1295204Y303982D01*
X1295120Y303732D01*
Y303316D01*
X1294995Y302941D01*
X1294745Y302691D01*
X1294454Y302607D01*
X1294162Y302691D01*
X1293954Y302899D01*
X1293829Y303232D01*
X1293787Y303524D01*
G01X1292079Y292041D02*
X1292204Y291791D01*
X1292287Y291499D01*
Y291166D01*
X1292162Y290791D01*
X1291954Y290499D01*
X1291704Y290291D01*
X1291287Y290124D01*
X1290912Y290082D01*
X1290537Y290166D01*
X1290287Y290291D01*
X1290037Y290541D01*
X1289870Y290832D01*
X1289787Y291124D01*
Y291416D01*
X1289870Y291707D01*
X1289995Y291957D01*
X1290162Y292166D01*
G01X1290287Y293307D02*
X1289995Y293557D01*
X1289829Y293891D01*
X1289787Y294266D01*
X1289829Y294599D01*
X1290037Y294932D01*
X1290287Y295141D01*
X1290537Y295182D01*
X1290829Y295099D01*
X1291037Y294807D01*
X1291120Y294516D01*
Y294141D01*
G01Y294516D02*
X1291245Y294766D01*
X1291454Y294974D01*
X1291704Y295057D01*
X1291954Y294974D01*
X1292162Y294766D01*
X1292287Y294391D01*
X1292245Y294016D01*
X1292079Y293641D01*
G01X1289787Y296491D02*
X1292287D01*
Y297491D01*
X1292162Y297824D01*
X1291870Y298074D01*
X1291537Y298157D01*
X1291204Y298074D01*
X1290954Y297866D01*
X1290829Y297491D01*
Y296491D01*
G01X1289787Y300924D02*
X1292287D01*
X1290495Y299382D01*
Y301466D01*
G01X1289787Y303524D02*
X1292287D01*
X1291787Y303024D01*
G01X1289787D02*
Y304024D01*
G01X1288092Y308817D02*
X1288217Y308567D01*
X1288300Y308275D01*
Y307942D01*
X1288175Y307567D01*
X1287967Y307275D01*
X1287717Y307067D01*
X1287300Y306900D01*
X1286925Y306858D01*
X1286550Y306942D01*
X1286300Y307067D01*
X1286050Y307317D01*
X1285883Y307608D01*
X1285800Y307900D01*
Y308192D01*
X1285883Y308483D01*
X1286008Y308733D01*
X1286175Y308942D01*
G01X1286300Y310083D02*
X1286008Y310333D01*
X1285842Y310667D01*
X1285800Y311042D01*
X1285842Y311375D01*
X1286050Y311708D01*
X1286300Y311917D01*
X1286550Y311958D01*
X1286842Y311875D01*
X1287050Y311583D01*
X1287133Y311292D01*
Y310917D01*
G01Y311292D02*
X1287258Y311542D01*
X1287467Y311750D01*
X1287717Y311833D01*
X1287967Y311750D01*
X1288175Y311542D01*
X1288300Y311167D01*
X1288258Y310792D01*
X1288092Y310417D01*
G01X1285800Y313267D02*
X1288300D01*
Y314267D01*
X1288175Y314600D01*
X1287883Y314850D01*
X1287550Y314933D01*
X1287217Y314850D01*
X1286967Y314642D01*
X1286842Y314267D01*
Y313267D01*
G01X1286300Y316283D02*
X1286008Y316533D01*
X1285842Y316867D01*
X1285800Y317242D01*
X1285842Y317575D01*
X1286050Y317908D01*
X1286300Y318117D01*
X1286550Y318158D01*
X1286842Y318075D01*
X1287050Y317783D01*
X1287133Y317492D01*
Y317117D01*
G01Y317492D02*
X1287258Y317742D01*
X1287467Y317950D01*
X1287717Y318033D01*
X1287967Y317950D01*
X1288175Y317742D01*
X1288300Y317367D01*
X1288258Y316992D01*
X1288092Y316617D01*
G01X1285800Y320217D02*
X1286342Y320300D01*
X1286800Y320425D01*
X1287217Y320592D01*
X1287675Y320800D01*
X1288300Y321133D01*
Y319467D01*
G01X1322692Y314967D02*
X1322817Y314717D01*
X1322900Y314425D01*
Y314092D01*
X1322775Y313717D01*
X1322567Y313425D01*
X1322317Y313217D01*
X1321900Y313050D01*
X1321525Y313008D01*
X1321150Y313092D01*
X1320900Y313217D01*
X1320650Y313467D01*
X1320483Y313758D01*
X1320400Y314050D01*
Y314342D01*
X1320483Y314633D01*
X1320608Y314883D01*
X1320775Y315092D01*
G01X1320900Y316233D02*
X1320608Y316483D01*
X1320442Y316817D01*
X1320400Y317192D01*
X1320442Y317525D01*
X1320650Y317858D01*
X1320900Y318067D01*
X1321150Y318108D01*
X1321442Y318025D01*
X1321650Y317733D01*
X1321733Y317442D01*
Y317067D01*
G01Y317442D02*
X1321858Y317692D01*
X1322067Y317900D01*
X1322317Y317983D01*
X1322567Y317900D01*
X1322775Y317692D01*
X1322900Y317317D01*
X1322858Y316942D01*
X1322692Y316567D01*
G01X1320400Y319417D02*
X1322900D01*
Y320417D01*
X1322775Y320750D01*
X1322483Y321000D01*
X1322150Y321083D01*
X1321817Y321000D01*
X1321567Y320792D01*
X1321442Y320417D01*
Y319417D01*
G01Y322558D02*
X1321733Y322850D01*
X1321900Y323100D01*
X1321983Y323433D01*
X1321900Y323725D01*
X1321733Y323933D01*
X1321483Y324100D01*
X1321192Y324142D01*
X1320942Y324100D01*
X1320692Y323933D01*
X1320483Y323683D01*
X1320400Y323392D01*
X1320483Y323058D01*
X1320733Y322767D01*
X1321108Y322600D01*
X1321525Y322558D01*
X1322067Y322642D01*
X1322358Y322767D01*
X1322650Y322975D01*
X1322858Y323267D01*
X1322900Y323558D01*
X1322817Y323850D01*
X1322608Y324058D01*
G01X1304433Y360700D02*
Y363200D01*
X1303392D01*
X1303058Y363075D01*
X1302850Y362908D01*
X1302767Y362575D01*
X1302850Y362242D01*
X1303100Y362033D01*
X1303392Y361908D01*
X1304433D01*
G01X1303392D02*
X1302767Y360700D01*
G01X1301417Y361200D02*
X1301167Y360908D01*
X1300833Y360742D01*
X1300458Y360700D01*
X1300125Y360742D01*
X1299792Y360950D01*
X1299583Y361200D01*
X1299542Y361450D01*
X1299625Y361742D01*
X1299917Y361950D01*
X1300208Y362033D01*
X1300583D01*
G01X1300208D02*
X1299958Y362158D01*
X1299750Y362367D01*
X1299667Y362617D01*
X1299750Y362867D01*
X1299958Y363075D01*
X1300333Y363200D01*
X1300708Y363158D01*
X1301083Y362992D01*
G01X1298358Y360700D02*
Y363200D01*
X1296442Y360700D01*
Y363200D01*
G01X1294300Y360700D02*
Y363200D01*
X1294800Y362700D01*
G01Y360700D02*
X1293800D01*
G01X1291908Y360992D02*
X1291617Y360783D01*
X1291283Y360700D01*
X1290950Y360783D01*
X1290658Y361033D01*
X1290450Y361408D01*
X1290367Y361783D01*
Y362242D01*
X1290450Y362617D01*
X1290658Y362950D01*
X1290908Y363117D01*
X1291200Y363200D01*
X1291533Y363117D01*
X1291783Y362950D01*
X1291950Y362700D01*
X1292033Y362367D01*
X1291950Y362075D01*
X1291742Y361783D01*
X1291492Y361617D01*
X1291200Y361575D01*
X1290867Y361658D01*
X1290617Y361867D01*
X1290367Y362242D01*
G01X1314915Y346664D02*
Y349164D01*
X1313874D01*
X1313540Y349039D01*
X1313332Y348872D01*
X1313249Y348539D01*
X1313332Y348206D01*
X1313582Y347997D01*
X1313874Y347872D01*
X1314915D01*
G01X1313874D02*
X1313249Y346664D01*
G01X1311899Y347164D02*
X1311649Y346872D01*
X1311315Y346706D01*
X1310940Y346664D01*
X1310607Y346706D01*
X1310274Y346914D01*
X1310065Y347164D01*
X1310024Y347414D01*
X1310107Y347706D01*
X1310399Y347914D01*
X1310690Y347997D01*
X1311065D01*
G01X1310690D02*
X1310440Y348122D01*
X1310232Y348331D01*
X1310149Y348581D01*
X1310232Y348831D01*
X1310440Y349039D01*
X1310815Y349164D01*
X1311190Y349122D01*
X1311565Y348956D01*
G01X1308715Y346664D02*
Y349164D01*
X1307715D01*
X1307382Y349039D01*
X1307132Y348747D01*
X1307049Y348414D01*
X1307132Y348081D01*
X1307340Y347831D01*
X1307715Y347706D01*
X1308715D01*
G01X1304782Y346664D02*
Y349164D01*
X1305282Y348664D01*
G01Y346664D02*
X1304282D01*
G01X1314565Y343064D02*
Y345564D01*
X1313524D01*
X1313190Y345439D01*
X1312982Y345272D01*
X1312899Y344939D01*
X1312982Y344606D01*
X1313232Y344397D01*
X1313524Y344272D01*
X1314565D01*
G01X1313524D02*
X1312899Y343064D01*
G01X1311549Y343564D02*
X1311299Y343272D01*
X1310965Y343106D01*
X1310590Y343064D01*
X1310257Y343106D01*
X1309924Y343314D01*
X1309715Y343564D01*
X1309674Y343814D01*
X1309757Y344106D01*
X1310049Y344314D01*
X1310340Y344397D01*
X1310715D01*
G01X1310340D02*
X1310090Y344522D01*
X1309882Y344731D01*
X1309799Y344981D01*
X1309882Y345231D01*
X1310090Y345439D01*
X1310465Y345564D01*
X1310840Y345522D01*
X1311215Y345356D01*
G01X1308365Y343064D02*
Y345564D01*
X1307365D01*
X1307032Y345439D01*
X1306782Y345147D01*
X1306699Y344814D01*
X1306782Y344481D01*
X1306990Y344231D01*
X1307365Y344106D01*
X1308365D01*
G01X1304432Y343064D02*
Y345564D01*
X1304932Y345064D01*
G01Y343064D02*
X1303932D01*
G01X1301332D02*
Y345564D01*
X1301832Y345064D01*
G01Y343064D02*
X1300832D01*
G01X1341195Y358352D02*
Y360852D01*
X1340154D01*
X1339820Y360727D01*
X1339612Y360560D01*
X1339529Y360227D01*
X1339612Y359894D01*
X1339862Y359685D01*
X1340154Y359560D01*
X1341195D01*
G01X1340154D02*
X1339529Y358352D01*
G01X1338054D02*
Y360852D01*
X1336470D01*
G01X1337054Y359644D02*
X1338054D01*
G01X1334162Y358352D02*
Y360852D01*
X1334662Y360352D01*
G01Y358352D02*
X1333662D01*
G01X1331979Y358852D02*
X1331729Y358560D01*
X1331395Y358394D01*
X1331020Y358352D01*
X1330687Y358394D01*
X1330354Y358602D01*
X1330145Y358852D01*
X1330104Y359102D01*
X1330187Y359394D01*
X1330479Y359602D01*
X1330770Y359685D01*
X1331145D01*
G01X1330770D02*
X1330520Y359810D01*
X1330312Y360019D01*
X1330229Y360269D01*
X1330312Y360519D01*
X1330520Y360727D01*
X1330895Y360852D01*
X1331270Y360810D01*
X1331645Y360644D01*
G01X1312980Y354394D02*
X1313105Y354144D01*
X1313188Y353852D01*
Y353519D01*
X1313063Y353144D01*
X1312855Y352852D01*
X1312605Y352644D01*
X1312188Y352477D01*
X1311813Y352435D01*
X1311438Y352519D01*
X1311188Y352644D01*
X1310938Y352894D01*
X1310771Y353185D01*
X1310688Y353477D01*
Y353769D01*
X1310771Y354060D01*
X1310896Y354310D01*
X1311063Y354519D01*
G01X1311188Y355660D02*
X1310896Y355910D01*
X1310730Y356244D01*
X1310688Y356619D01*
X1310730Y356952D01*
X1310938Y357285D01*
X1311188Y357494D01*
X1311438Y357535D01*
X1311730Y357452D01*
X1311938Y357160D01*
X1312021Y356869D01*
Y356494D01*
G01Y356869D02*
X1312146Y357119D01*
X1312355Y357327D01*
X1312605Y357410D01*
X1312855Y357327D01*
X1313063Y357119D01*
X1313188Y356744D01*
X1313146Y356369D01*
X1312980Y355994D01*
G01X1310688Y358719D02*
X1313188D01*
X1310688Y360635D01*
X1313188D01*
G01X1311188Y361860D02*
X1310896Y362110D01*
X1310730Y362444D01*
X1310688Y362819D01*
X1310730Y363152D01*
X1310938Y363485D01*
X1311188Y363694D01*
X1311438Y363735D01*
X1311730Y363652D01*
X1311938Y363360D01*
X1312021Y363069D01*
Y362694D01*
G01Y363069D02*
X1312146Y363319D01*
X1312355Y363527D01*
X1312605Y363610D01*
X1312855Y363527D01*
X1313063Y363319D01*
X1313188Y362944D01*
X1313146Y362569D01*
X1312980Y362194D01*
G01X1310980Y365169D02*
X1310771Y365460D01*
X1310688Y365794D01*
X1310771Y366127D01*
X1311021Y366419D01*
X1311396Y366627D01*
X1311771Y366710D01*
X1312230D01*
X1312605Y366627D01*
X1312938Y366419D01*
X1313105Y366169D01*
X1313188Y365877D01*
X1313105Y365544D01*
X1312938Y365294D01*
X1312688Y365127D01*
X1312355Y365044D01*
X1312063Y365127D01*
X1311771Y365335D01*
X1311605Y365585D01*
X1311563Y365877D01*
X1311646Y366210D01*
X1311855Y366460D01*
X1312230Y366710D01*
G01X1311083Y371792D02*
X1311333Y371917D01*
X1311625Y372000D01*
X1311958D01*
X1312333Y371875D01*
X1312625Y371667D01*
X1312833Y371417D01*
X1313000Y371000D01*
X1313042Y370625D01*
X1312958Y370250D01*
X1312833Y370000D01*
X1312583Y369750D01*
X1312292Y369583D01*
X1312000Y369500D01*
X1311708D01*
X1311417Y369583D01*
X1311167Y369708D01*
X1310958Y369875D01*
G01X1309817Y370000D02*
X1309567Y369708D01*
X1309233Y369542D01*
X1308858Y369500D01*
X1308525Y369542D01*
X1308192Y369750D01*
X1307983Y370000D01*
X1307942Y370250D01*
X1308025Y370542D01*
X1308317Y370750D01*
X1308608Y370833D01*
X1308983D01*
G01X1308608D02*
X1308358Y370958D01*
X1308150Y371167D01*
X1308067Y371417D01*
X1308150Y371667D01*
X1308358Y371875D01*
X1308733Y372000D01*
X1309108Y371958D01*
X1309483Y371792D01*
G01X1306758Y369500D02*
Y372000D01*
X1304842Y369500D01*
Y372000D01*
G01X1303617Y370000D02*
X1303367Y369708D01*
X1303033Y369542D01*
X1302658Y369500D01*
X1302325Y369542D01*
X1301992Y369750D01*
X1301783Y370000D01*
X1301742Y370250D01*
X1301825Y370542D01*
X1302117Y370750D01*
X1302408Y370833D01*
X1302783D01*
G01X1302408D02*
X1302158Y370958D01*
X1301950Y371167D01*
X1301867Y371417D01*
X1301950Y371667D01*
X1302158Y371875D01*
X1302533Y372000D01*
X1302908Y371958D01*
X1303283Y371792D01*
G01X1299600Y369500D02*
X1299308Y369542D01*
X1298975Y369667D01*
X1298767Y369875D01*
X1298683Y370167D01*
X1298767Y370458D01*
X1299017Y370708D01*
X1299392Y370833D01*
X1299808D01*
X1300058Y370917D01*
X1300267Y371125D01*
X1300350Y371417D01*
X1300225Y371708D01*
X1299933Y371917D01*
X1299600Y372000D01*
X1299267Y371917D01*
X1298975Y371708D01*
X1298850Y371417D01*
X1298933Y371125D01*
X1299142Y370917D01*
X1299392Y370833D01*
X1299808D01*
X1300183Y370708D01*
X1300433Y370458D01*
X1300517Y370167D01*
X1300433Y369875D01*
X1300225Y369667D01*
X1299892Y369542D01*
X1299600Y369500D01*
G01X1352000Y362000D02*
X1329425D01*
G01X1352000Y380000D02*
X1329428D01*
G01X1316636Y364700D02*
Y361138D01*
X1329432D01*
Y364700D01*
G01X1316636Y377300D02*
Y381091D01*
X1329432D01*
Y377300D01*
G01X1311083Y391792D02*
X1311333Y391917D01*
X1311625Y392000D01*
X1311958D01*
X1312333Y391875D01*
X1312625Y391667D01*
X1312833Y391417D01*
X1313000Y391000D01*
X1313042Y390625D01*
X1312958Y390250D01*
X1312833Y390000D01*
X1312583Y389750D01*
X1312292Y389583D01*
X1312000Y389500D01*
X1311708D01*
X1311417Y389583D01*
X1311167Y389708D01*
X1310958Y389875D01*
G01X1309817Y390000D02*
X1309567Y389708D01*
X1309233Y389542D01*
X1308858Y389500D01*
X1308525Y389542D01*
X1308192Y389750D01*
X1307983Y390000D01*
X1307942Y390250D01*
X1308025Y390542D01*
X1308317Y390750D01*
X1308608Y390833D01*
X1308983D01*
G01X1308608D02*
X1308358Y390958D01*
X1308150Y391167D01*
X1308067Y391417D01*
X1308150Y391667D01*
X1308358Y391875D01*
X1308733Y392000D01*
X1309108Y391958D01*
X1309483Y391792D01*
G01X1306758Y389500D02*
Y392000D01*
X1304842Y389500D01*
Y392000D01*
G01X1303617Y390000D02*
X1303367Y389708D01*
X1303033Y389542D01*
X1302658Y389500D01*
X1302325Y389542D01*
X1301992Y389750D01*
X1301783Y390000D01*
X1301742Y390250D01*
X1301825Y390542D01*
X1302117Y390750D01*
X1302408Y390833D01*
X1302783D01*
G01X1302408D02*
X1302158Y390958D01*
X1301950Y391167D01*
X1301867Y391417D01*
X1301950Y391667D01*
X1302158Y391875D01*
X1302533Y392000D01*
X1302908Y391958D01*
X1303283Y391792D01*
G01X1300517Y389875D02*
X1300267Y389667D01*
X1299975Y389542D01*
X1299600Y389500D01*
X1299225Y389583D01*
X1298933Y389750D01*
X1298725Y390042D01*
X1298683Y390375D01*
X1298767Y390708D01*
X1298975Y390917D01*
X1299267Y391083D01*
X1299558Y391125D01*
X1299850Y391083D01*
X1300225Y390917D01*
X1300100Y392000D01*
X1298975D01*
G01X1352000Y382000D02*
X1329425D01*
G01X1352000Y400000D02*
X1329428D01*
G01X1316636Y384700D02*
Y381138D01*
X1329432D01*
Y384700D01*
G01X1316636Y397300D02*
Y401091D01*
X1329432D01*
Y397300D01*
G01X1352000Y402000D02*
X1329425D01*
G01X1316636Y404700D02*
Y401138D01*
X1329432D01*
Y404700D01*
G01X1326583Y359542D02*
X1326833Y359667D01*
X1327125Y359750D01*
X1327458D01*
X1327833Y359625D01*
X1328125Y359417D01*
X1328333Y359167D01*
X1328500Y358750D01*
X1328542Y358375D01*
X1328458Y358000D01*
X1328333Y357750D01*
X1328083Y357500D01*
X1327792Y357333D01*
X1327500Y357250D01*
X1327208D01*
X1326917Y357333D01*
X1326667Y357458D01*
X1326458Y357625D01*
G01X1325192Y357250D02*
Y359750D01*
X1323608D01*
G01X1324192Y358542D02*
X1325192D01*
G01X1321300Y357250D02*
Y359750D01*
X1321800Y359250D01*
G01Y357250D02*
X1320800D01*
G01X1319117Y357750D02*
X1318867Y357458D01*
X1318533Y357292D01*
X1318158Y357250D01*
X1317825Y357292D01*
X1317492Y357500D01*
X1317283Y357750D01*
X1317242Y358000D01*
X1317325Y358292D01*
X1317617Y358500D01*
X1317908Y358583D01*
X1318283D01*
G01X1317908D02*
X1317658Y358708D01*
X1317450Y358917D01*
X1317367Y359167D01*
X1317450Y359417D01*
X1317658Y359625D01*
X1318033Y359750D01*
X1318408Y359708D01*
X1318783Y359542D01*
G01X1332483Y444400D02*
Y446900D01*
X1331442D01*
X1331108Y446775D01*
X1330900Y446608D01*
X1330817Y446275D01*
X1330900Y445942D01*
X1331150Y445733D01*
X1331442Y445608D01*
X1332483D01*
G01X1331442D02*
X1330817Y444400D01*
G01X1329467Y444900D02*
X1329217Y444608D01*
X1328883Y444442D01*
X1328508Y444400D01*
X1328175Y444442D01*
X1327842Y444650D01*
X1327633Y444900D01*
X1327592Y445150D01*
X1327675Y445442D01*
X1327967Y445650D01*
X1328258Y445733D01*
X1328633D01*
G01X1328258D02*
X1328008Y445858D01*
X1327800Y446067D01*
X1327717Y446317D01*
X1327800Y446567D01*
X1328008Y446775D01*
X1328383Y446900D01*
X1328758Y446858D01*
X1329133Y446692D01*
G01X1326408Y444400D02*
Y446900D01*
X1324492Y444400D01*
Y446900D01*
G01X1323142Y446483D02*
X1322892Y446733D01*
X1322600Y446858D01*
X1322267Y446900D01*
X1321850Y446817D01*
X1321558Y446608D01*
X1321475Y446358D01*
X1321517Y446108D01*
X1321683Y445900D01*
X1322517Y445483D01*
X1322892Y445192D01*
X1323142Y444775D01*
X1323225Y444400D01*
X1321475D01*
G01X1319958Y444692D02*
X1319667Y444483D01*
X1319333Y444400D01*
X1319000Y444483D01*
X1318708Y444733D01*
X1318500Y445108D01*
X1318417Y445483D01*
Y445942D01*
X1318500Y446317D01*
X1318708Y446650D01*
X1318958Y446817D01*
X1319250Y446900D01*
X1319583Y446817D01*
X1319833Y446650D01*
X1320000Y446400D01*
X1320083Y446067D01*
X1320000Y445775D01*
X1319792Y445483D01*
X1319542Y445317D01*
X1319250Y445275D01*
X1318917Y445358D01*
X1318667Y445567D01*
X1318417Y445942D01*
G01X1353483Y446092D02*
X1353733Y446217D01*
X1354025Y446300D01*
X1354358D01*
X1354733Y446175D01*
X1355025Y445967D01*
X1355233Y445717D01*
X1355400Y445300D01*
X1355442Y444925D01*
X1355358Y444550D01*
X1355233Y444300D01*
X1354983Y444050D01*
X1354692Y443883D01*
X1354400Y443800D01*
X1354108D01*
X1353817Y443883D01*
X1353567Y444008D01*
X1353358Y444175D01*
G01X1352217Y444300D02*
X1351967Y444008D01*
X1351633Y443842D01*
X1351258Y443800D01*
X1350925Y443842D01*
X1350592Y444050D01*
X1350383Y444300D01*
X1350342Y444550D01*
X1350425Y444842D01*
X1350717Y445050D01*
X1351008Y445133D01*
X1351383D01*
G01X1351008D02*
X1350758Y445258D01*
X1350550Y445467D01*
X1350467Y445717D01*
X1350550Y445967D01*
X1350758Y446175D01*
X1351133Y446300D01*
X1351508Y446258D01*
X1351883Y446092D01*
G01X1349283Y443800D02*
Y446300D01*
X1348200Y444217D01*
X1347117Y446300D01*
Y443800D01*
G01X1344600D02*
Y446300D01*
X1346142Y444508D01*
X1344058D01*
G01X1342792Y444842D02*
X1342500Y445133D01*
X1342250Y445300D01*
X1341917Y445383D01*
X1341625Y445300D01*
X1341417Y445133D01*
X1341250Y444883D01*
X1341208Y444592D01*
X1341250Y444342D01*
X1341417Y444092D01*
X1341667Y443883D01*
X1341958Y443800D01*
X1342292Y443883D01*
X1342583Y444133D01*
X1342750Y444508D01*
X1342792Y444925D01*
X1342708Y445467D01*
X1342583Y445758D01*
X1342375Y446050D01*
X1342083Y446258D01*
X1341792Y446300D01*
X1341500Y446217D01*
X1341292Y446008D01*
G01X1311083Y411792D02*
X1311333Y411917D01*
X1311625Y412000D01*
X1311958D01*
X1312333Y411875D01*
X1312625Y411667D01*
X1312833Y411417D01*
X1313000Y411000D01*
X1313042Y410625D01*
X1312958Y410250D01*
X1312833Y410000D01*
X1312583Y409750D01*
X1312292Y409583D01*
X1312000Y409500D01*
X1311708D01*
X1311417Y409583D01*
X1311167Y409708D01*
X1310958Y409875D01*
G01X1309817Y410000D02*
X1309567Y409708D01*
X1309233Y409542D01*
X1308858Y409500D01*
X1308525Y409542D01*
X1308192Y409750D01*
X1307983Y410000D01*
X1307942Y410250D01*
X1308025Y410542D01*
X1308317Y410750D01*
X1308608Y410833D01*
X1308983D01*
G01X1308608D02*
X1308358Y410958D01*
X1308150Y411167D01*
X1308067Y411417D01*
X1308150Y411667D01*
X1308358Y411875D01*
X1308733Y412000D01*
X1309108Y411958D01*
X1309483Y411792D01*
G01X1306758Y409500D02*
Y412000D01*
X1304842Y409500D01*
Y412000D01*
G01X1303492Y411583D02*
X1303242Y411833D01*
X1302950Y411958D01*
X1302617Y412000D01*
X1302200Y411917D01*
X1301908Y411708D01*
X1301825Y411458D01*
X1301867Y411208D01*
X1302033Y411000D01*
X1302867Y410583D01*
X1303242Y410292D01*
X1303492Y409875D01*
X1303575Y409500D01*
X1301825D01*
G01X1300392Y410542D02*
X1300100Y410833D01*
X1299850Y411000D01*
X1299517Y411083D01*
X1299225Y411000D01*
X1299017Y410833D01*
X1298850Y410583D01*
X1298808Y410292D01*
X1298850Y410042D01*
X1299017Y409792D01*
X1299267Y409583D01*
X1299558Y409500D01*
X1299892Y409583D01*
X1300183Y409833D01*
X1300350Y410208D01*
X1300392Y410625D01*
X1300308Y411167D01*
X1300183Y411458D01*
X1299975Y411750D01*
X1299683Y411958D01*
X1299392Y412000D01*
X1299100Y411917D01*
X1298892Y411708D01*
G01X1352000Y420000D02*
X1329428D01*
G01X1316636Y417300D02*
Y421091D01*
X1329432D01*
Y417300D01*
G01X1329237Y461930D02*
X1329487Y462055D01*
X1329779Y462138D01*
X1330112D01*
X1330487Y462013D01*
X1330779Y461805D01*
X1330987Y461555D01*
X1331154Y461138D01*
X1331196Y460763D01*
X1331112Y460388D01*
X1330987Y460138D01*
X1330737Y459888D01*
X1330446Y459721D01*
X1330154Y459638D01*
X1329862D01*
X1329571Y459721D01*
X1329321Y459846D01*
X1329112Y460013D01*
G01X1326554Y459638D02*
Y462138D01*
X1328096Y460346D01*
X1326012D01*
G01X1325037Y459638D02*
Y462138D01*
X1323954Y460055D01*
X1322871Y462138D01*
Y459638D01*
G01X1320937D02*
X1320854Y460180D01*
X1320729Y460638D01*
X1320562Y461055D01*
X1320354Y461513D01*
X1320021Y462138D01*
X1321687D01*
G01X1304717Y467166D02*
Y463604D01*
X1317513D01*
Y467166D01*
G01X1340081Y464466D02*
Y467164D01*
G01Y464466D02*
X1317506D01*
G01X1330270Y510459D02*
X1330395Y510209D01*
X1330478Y509917D01*
Y509584D01*
X1330353Y509209D01*
X1330145Y508917D01*
X1329895Y508709D01*
X1329478Y508542D01*
X1329103Y508500D01*
X1328728Y508584D01*
X1328478Y508709D01*
X1328228Y508959D01*
X1328061Y509250D01*
X1327978Y509542D01*
Y509834D01*
X1328061Y510125D01*
X1328186Y510375D01*
X1328353Y510584D01*
G01X1328478Y511725D02*
X1328186Y511975D01*
X1328020Y512309D01*
X1327978Y512684D01*
X1328020Y513017D01*
X1328228Y513350D01*
X1328478Y513559D01*
X1328728Y513600D01*
X1329020Y513517D01*
X1329228Y513225D01*
X1329311Y512934D01*
Y512559D01*
G01Y512934D02*
X1329436Y513184D01*
X1329645Y513392D01*
X1329895Y513475D01*
X1330145Y513392D01*
X1330353Y513184D01*
X1330478Y512809D01*
X1330436Y512434D01*
X1330270Y512059D01*
G01X1327978Y514659D02*
X1330478D01*
X1328395Y515742D01*
X1330478Y516825D01*
X1327978D01*
G01Y518842D02*
X1330478D01*
X1329978Y518342D01*
G01X1327978D02*
Y519342D01*
G01X1330478Y521942D02*
X1330395Y521609D01*
X1330186Y521359D01*
X1329936Y521192D01*
X1329603Y521067D01*
X1329228Y521025D01*
X1328853Y521067D01*
X1328520Y521192D01*
X1328270Y521359D01*
X1328061Y521609D01*
X1327978Y521942D01*
X1328061Y522275D01*
X1328270Y522525D01*
X1328520Y522692D01*
X1328853Y522817D01*
X1329228Y522859D01*
X1329603Y522817D01*
X1329936Y522692D01*
X1330186Y522525D01*
X1330395Y522275D01*
X1330478Y521942D01*
G01X1304717Y479766D02*
Y483557D01*
X1317513D01*
Y479766D01*
G01X1340081Y482466D02*
Y479771D01*
G01Y482466D02*
X1317509D01*
G01X1330205Y504075D02*
X1330455Y504200D01*
X1330747Y504283D01*
X1331080D01*
X1331455Y504158D01*
X1331747Y503950D01*
X1331955Y503700D01*
X1332122Y503283D01*
X1332164Y502908D01*
X1332080Y502533D01*
X1331955Y502283D01*
X1331705Y502033D01*
X1331414Y501866D01*
X1331122Y501783D01*
X1330830D01*
X1330539Y501866D01*
X1330289Y501991D01*
X1330080Y502158D01*
G01X1327522Y501783D02*
Y504283D01*
X1329064Y502491D01*
X1326980D01*
G01X1326005Y501783D02*
Y504283D01*
X1324922Y502200D01*
X1323839Y504283D01*
Y501783D01*
G01X1322614Y502825D02*
X1322322Y503116D01*
X1322072Y503283D01*
X1321739Y503366D01*
X1321447Y503283D01*
X1321239Y503116D01*
X1321072Y502866D01*
X1321030Y502575D01*
X1321072Y502325D01*
X1321239Y502075D01*
X1321489Y501866D01*
X1321780Y501783D01*
X1322114Y501866D01*
X1322405Y502116D01*
X1322572Y502491D01*
X1322614Y502908D01*
X1322530Y503450D01*
X1322405Y503741D01*
X1322197Y504033D01*
X1321905Y504241D01*
X1321614Y504283D01*
X1321322Y504200D01*
X1321114Y503991D01*
G01X1305808Y497983D02*
Y501774D01*
X1318604D01*
Y497983D01*
G01X1305808Y485383D02*
Y481821D01*
X1318604D01*
Y485383D01*
G01X1341172Y482683D02*
Y485381D01*
G01Y500683D02*
Y497988D01*
G01Y500683D02*
X1318600D01*
G01X1341172Y482683D02*
X1318597D01*
G01X1320533Y522492D02*
X1320783Y522617D01*
X1321075Y522700D01*
X1321408D01*
X1321783Y522575D01*
X1322075Y522367D01*
X1322283Y522117D01*
X1322450Y521700D01*
X1322492Y521325D01*
X1322408Y520950D01*
X1322283Y520700D01*
X1322033Y520450D01*
X1321742Y520283D01*
X1321450Y520200D01*
X1321158D01*
X1320867Y520283D01*
X1320617Y520408D01*
X1320408Y520575D01*
G01X1317850Y520200D02*
Y522700D01*
X1319392Y520908D01*
X1317308D01*
G01X1316333Y520200D02*
Y522700D01*
X1315250Y520617D01*
X1314167Y522700D01*
Y520200D01*
G01X1312150D02*
Y522700D01*
X1312650Y522200D01*
G01Y520200D02*
X1311650D01*
G01X1300300Y526300D02*
Y525100D01*
X1312300D01*
Y526300D01*
G01X1335250D02*
Y524050D01*
X1305350D01*
Y525100D01*
G01X1343847Y526372D02*
X1343972Y526122D01*
X1344055Y525830D01*
Y525497D01*
X1343930Y525122D01*
X1343722Y524830D01*
X1343472Y524622D01*
X1343055Y524455D01*
X1342680Y524413D01*
X1342305Y524497D01*
X1342055Y524622D01*
X1341805Y524872D01*
X1341638Y525163D01*
X1341555Y525455D01*
Y525747D01*
X1341638Y526038D01*
X1341763Y526288D01*
X1341930Y526497D01*
G01X1343638Y527763D02*
X1343888Y528013D01*
X1344013Y528305D01*
X1344055Y528638D01*
X1343972Y529055D01*
X1343763Y529347D01*
X1343513Y529430D01*
X1343263Y529388D01*
X1343055Y529222D01*
X1342638Y528388D01*
X1342347Y528013D01*
X1341930Y527763D01*
X1341555Y527680D01*
Y529430D01*
G01X1343638Y530863D02*
X1343888Y531113D01*
X1344013Y531405D01*
X1344055Y531738D01*
X1343972Y532155D01*
X1343763Y532447D01*
X1343513Y532530D01*
X1343263Y532488D01*
X1343055Y532322D01*
X1342638Y531488D01*
X1342347Y531113D01*
X1341930Y530863D01*
X1341555Y530780D01*
Y532530D01*
G01X1344055Y533505D02*
X1341555Y534088D01*
X1344055Y534755D01*
X1341555Y535422D01*
X1344055Y536005D01*
G01X1341555Y537772D02*
X1342097Y537855D01*
X1342555Y537980D01*
X1342972Y538147D01*
X1343430Y538355D01*
X1344055Y538688D01*
Y537022D01*
G01X1338283Y581692D02*
X1338533Y581817D01*
X1338825Y581900D01*
X1339158D01*
X1339533Y581775D01*
X1339825Y581567D01*
X1340033Y581317D01*
X1340200Y580900D01*
X1340242Y580525D01*
X1340158Y580150D01*
X1340033Y579900D01*
X1339783Y579650D01*
X1339492Y579483D01*
X1339200Y579400D01*
X1338908D01*
X1338617Y579483D01*
X1338367Y579608D01*
X1338158Y579775D01*
G01X1337017Y579900D02*
X1336767Y579608D01*
X1336433Y579442D01*
X1336058Y579400D01*
X1335725Y579442D01*
X1335392Y579650D01*
X1335183Y579900D01*
X1335142Y580150D01*
X1335225Y580442D01*
X1335517Y580650D01*
X1335808Y580733D01*
X1336183D01*
G01X1335808D02*
X1335558Y580858D01*
X1335350Y581067D01*
X1335267Y581317D01*
X1335350Y581567D01*
X1335558Y581775D01*
X1335933Y581900D01*
X1336308Y581858D01*
X1336683Y581692D01*
G01X1333833Y581900D02*
Y579400D01*
X1332167D01*
G01X1329900D02*
Y581900D01*
X1330400Y581400D01*
G01Y579400D02*
X1329400D01*
G01X1326300D02*
Y581900D01*
X1327842Y580108D01*
X1325758D01*
G01X1308636Y585700D02*
Y582138D01*
X1321432D01*
Y585700D01*
G01X1344000Y583000D02*
X1321425D01*
G01X1334833Y570592D02*
X1335083Y570717D01*
X1335375Y570800D01*
X1335708D01*
X1336083Y570675D01*
X1336375Y570467D01*
X1336583Y570217D01*
X1336750Y569800D01*
X1336792Y569425D01*
X1336708Y569050D01*
X1336583Y568800D01*
X1336333Y568550D01*
X1336042Y568383D01*
X1335750Y568300D01*
X1335458D01*
X1335167Y568383D01*
X1334917Y568508D01*
X1334708Y568675D01*
G01X1332150Y568300D02*
Y570800D01*
X1333692Y569008D01*
X1331608D01*
G01X1330383Y570800D02*
Y568300D01*
X1328717D01*
G01X1327367Y568675D02*
X1327117Y568467D01*
X1326825Y568342D01*
X1326450Y568300D01*
X1326075Y568383D01*
X1325783Y568550D01*
X1325575Y568842D01*
X1325533Y569175D01*
X1325617Y569508D01*
X1325825Y569717D01*
X1326117Y569883D01*
X1326408Y569925D01*
X1326700Y569883D01*
X1327075Y569717D01*
X1326950Y570800D01*
X1325825D01*
G01X1301136Y562800D02*
Y566591D01*
X1313932D01*
Y562800D01*
G01X1301136Y550200D02*
Y546638D01*
X1313932D01*
Y550200D01*
G01X1336500Y547500D02*
Y550198D01*
G01Y565500D02*
Y562805D01*
G01Y565500D02*
X1313928D01*
G01X1336500Y547500D02*
X1313925D01*
G01X1300300Y539900D02*
Y541100D01*
X1312300D01*
Y539900D01*
G01X1305350Y541100D02*
Y542150D01*
X1335250D01*
Y539900D01*
G01X1297800Y610467D02*
X1300300D01*
Y611508D01*
X1300175Y611842D01*
X1300008Y612050D01*
X1299675Y612133D01*
X1299342Y612050D01*
X1299133Y611800D01*
X1299008Y611508D01*
Y610467D01*
G01Y611508D02*
X1297800Y612133D01*
G01Y614900D02*
X1300300D01*
X1298508Y613358D01*
Y615442D01*
G01X1300300Y616667D02*
X1297800D01*
Y618333D01*
G01Y621100D02*
X1300300D01*
X1298508Y619558D01*
Y621642D01*
G01X1308636Y598300D02*
Y602091D01*
X1321432D01*
Y598300D01*
G01X1344000Y601000D02*
X1321428D01*
G01X1335933Y624192D02*
X1336183Y624317D01*
X1336475Y624400D01*
X1336808D01*
X1337183Y624275D01*
X1337475Y624067D01*
X1337683Y623817D01*
X1337850Y623400D01*
X1337892Y623025D01*
X1337808Y622650D01*
X1337683Y622400D01*
X1337433Y622150D01*
X1337142Y621983D01*
X1336850Y621900D01*
X1336558D01*
X1336267Y621983D01*
X1336017Y622108D01*
X1335808Y622275D01*
G01X1334667Y622400D02*
X1334417Y622108D01*
X1334083Y621942D01*
X1333708Y621900D01*
X1333375Y621942D01*
X1333042Y622150D01*
X1332833Y622400D01*
X1332792Y622650D01*
X1332875Y622942D01*
X1333167Y623150D01*
X1333458Y623233D01*
X1333833D01*
G01X1333458D02*
X1333208Y623358D01*
X1333000Y623567D01*
X1332917Y623817D01*
X1333000Y624067D01*
X1333208Y624275D01*
X1333583Y624400D01*
X1333958Y624358D01*
X1334333Y624192D01*
G01X1331483Y624400D02*
Y621900D01*
X1329817D01*
G01X1328342Y622942D02*
X1328050Y623233D01*
X1327800Y623400D01*
X1327467Y623483D01*
X1327175Y623400D01*
X1326967Y623233D01*
X1326800Y622983D01*
X1326758Y622692D01*
X1326800Y622442D01*
X1326967Y622192D01*
X1327217Y621983D01*
X1327508Y621900D01*
X1327842Y621983D01*
X1328133Y622233D01*
X1328300Y622608D01*
X1328342Y623025D01*
X1328258Y623567D01*
X1328133Y623858D01*
X1327925Y624150D01*
X1327633Y624358D01*
X1327342Y624400D01*
X1327050Y624317D01*
X1326842Y624108D01*
G01X1344000Y603000D02*
X1321425D01*
G01X1344000Y621000D02*
X1321428D01*
G01X1308636Y605700D02*
Y602138D01*
X1321432D01*
Y605700D01*
G01X1308636Y618300D02*
Y622091D01*
X1321432D01*
Y618300D01*
G01X1383310Y-5925D02*
X1383560Y-5800D01*
X1383852Y-5717D01*
X1384185D01*
X1384560Y-5842D01*
X1384852Y-6050D01*
X1385060Y-6300D01*
X1385227Y-6717D01*
X1385269Y-7092D01*
X1385185Y-7467D01*
X1385060Y-7717D01*
X1384810Y-7967D01*
X1384519Y-8134D01*
X1384227Y-8217D01*
X1383935D01*
X1383644Y-8134D01*
X1383394Y-8009D01*
X1383185Y-7842D01*
G01X1382044Y-7717D02*
X1381794Y-8009D01*
X1381460Y-8175D01*
X1381085Y-8217D01*
X1380752Y-8175D01*
X1380419Y-7967D01*
X1380210Y-7717D01*
X1380169Y-7467D01*
X1380252Y-7175D01*
X1380544Y-6967D01*
X1380835Y-6884D01*
X1381210D01*
G01X1380835D02*
X1380585Y-6759D01*
X1380377Y-6550D01*
X1380294Y-6300D01*
X1380377Y-6050D01*
X1380585Y-5842D01*
X1380960Y-5717D01*
X1381335Y-5759D01*
X1381710Y-5925D01*
G01X1378944Y-5717D02*
Y-7509D01*
X1378777Y-7884D01*
X1378444Y-8134D01*
X1378027Y-8217D01*
X1377610Y-8134D01*
X1377277Y-7884D01*
X1377110Y-7509D01*
Y-5717D01*
G01X1375719Y-7175D02*
X1375427Y-6884D01*
X1375177Y-6717D01*
X1374844Y-6634D01*
X1374552Y-6717D01*
X1374344Y-6884D01*
X1374177Y-7134D01*
X1374135Y-7425D01*
X1374177Y-7675D01*
X1374344Y-7925D01*
X1374594Y-8134D01*
X1374885Y-8217D01*
X1375219Y-8134D01*
X1375510Y-7884D01*
X1375677Y-7509D01*
X1375719Y-7092D01*
X1375635Y-6550D01*
X1375510Y-6259D01*
X1375302Y-5967D01*
X1375010Y-5759D01*
X1374719Y-5717D01*
X1374427Y-5800D01*
X1374219Y-6009D01*
G01X1382380Y-12674D02*
X1382630Y-12549D01*
X1382922Y-12466D01*
X1383255D01*
X1383630Y-12591D01*
X1383922Y-12799D01*
X1384130Y-13049D01*
X1384297Y-13466D01*
X1384339Y-13841D01*
X1384255Y-14216D01*
X1384130Y-14466D01*
X1383880Y-14716D01*
X1383589Y-14883D01*
X1383297Y-14966D01*
X1383005D01*
X1382714Y-14883D01*
X1382464Y-14758D01*
X1382255Y-14591D01*
G01X1381114Y-14466D02*
X1380864Y-14758D01*
X1380530Y-14924D01*
X1380155Y-14966D01*
X1379822Y-14924D01*
X1379489Y-14716D01*
X1379280Y-14466D01*
X1379239Y-14216D01*
X1379322Y-13924D01*
X1379614Y-13716D01*
X1379905Y-13633D01*
X1380280D01*
G01X1379905D02*
X1379655Y-13508D01*
X1379447Y-13299D01*
X1379364Y-13049D01*
X1379447Y-12799D01*
X1379655Y-12591D01*
X1380030Y-12466D01*
X1380405Y-12508D01*
X1380780Y-12674D01*
G01X1378014Y-12466D02*
Y-14258D01*
X1377847Y-14633D01*
X1377514Y-14883D01*
X1377097Y-14966D01*
X1376680Y-14883D01*
X1376347Y-14633D01*
X1376180Y-14258D01*
Y-12466D01*
G01X1374080Y-14966D02*
X1373997Y-14424D01*
X1373872Y-13966D01*
X1373705Y-13549D01*
X1373497Y-13091D01*
X1373164Y-12466D01*
X1374830D01*
G01X1381428Y-18383D02*
X1381678Y-18258D01*
X1381970Y-18175D01*
X1382303D01*
X1382678Y-18300D01*
X1382970Y-18508D01*
X1383178Y-18758D01*
X1383345Y-19175D01*
X1383387Y-19550D01*
X1383303Y-19925D01*
X1383178Y-20175D01*
X1382928Y-20425D01*
X1382637Y-20592D01*
X1382345Y-20675D01*
X1382053D01*
X1381762Y-20592D01*
X1381512Y-20467D01*
X1381303Y-20300D01*
G01X1380162Y-20175D02*
X1379912Y-20467D01*
X1379578Y-20633D01*
X1379203Y-20675D01*
X1378870Y-20633D01*
X1378537Y-20425D01*
X1378328Y-20175D01*
X1378287Y-19925D01*
X1378370Y-19633D01*
X1378662Y-19425D01*
X1378953Y-19342D01*
X1379328D01*
G01X1378953D02*
X1378703Y-19217D01*
X1378495Y-19008D01*
X1378412Y-18758D01*
X1378495Y-18508D01*
X1378703Y-18300D01*
X1379078Y-18175D01*
X1379453Y-18217D01*
X1379828Y-18383D01*
G01X1377062Y-18175D02*
Y-19967D01*
X1376895Y-20342D01*
X1376562Y-20592D01*
X1376145Y-20675D01*
X1375728Y-20592D01*
X1375395Y-20342D01*
X1375228Y-19967D01*
Y-18175D01*
G01X1373753Y-20383D02*
X1373462Y-20592D01*
X1373128Y-20675D01*
X1372795Y-20592D01*
X1372503Y-20342D01*
X1372295Y-19967D01*
X1372212Y-19592D01*
Y-19133D01*
X1372295Y-18758D01*
X1372503Y-18425D01*
X1372753Y-18258D01*
X1373045Y-18175D01*
X1373378Y-18258D01*
X1373628Y-18425D01*
X1373795Y-18675D01*
X1373878Y-19008D01*
X1373795Y-19300D01*
X1373587Y-19592D01*
X1373337Y-19758D01*
X1373045Y-19800D01*
X1372712Y-19717D01*
X1372462Y-19508D01*
X1372212Y-19133D01*
G01X1383583Y19292D02*
X1383833Y19417D01*
X1384125Y19500D01*
X1384458D01*
X1384833Y19375D01*
X1385125Y19167D01*
X1385333Y18917D01*
X1385500Y18500D01*
X1385542Y18125D01*
X1385458Y17750D01*
X1385333Y17500D01*
X1385083Y17250D01*
X1384792Y17083D01*
X1384500Y17000D01*
X1384208D01*
X1383917Y17083D01*
X1383667Y17208D01*
X1383458Y17375D01*
G01X1382317Y17500D02*
X1382067Y17208D01*
X1381733Y17042D01*
X1381358Y17000D01*
X1381025Y17042D01*
X1380692Y17250D01*
X1380483Y17500D01*
X1380442Y17750D01*
X1380525Y18042D01*
X1380817Y18250D01*
X1381108Y18333D01*
X1381483D01*
G01X1381108D02*
X1380858Y18458D01*
X1380650Y18667D01*
X1380567Y18917D01*
X1380650Y19167D01*
X1380858Y19375D01*
X1381233Y19500D01*
X1381608Y19458D01*
X1381983Y19292D01*
G01X1379217Y19500D02*
Y17708D01*
X1379050Y17333D01*
X1378717Y17083D01*
X1378300Y17000D01*
X1377883Y17083D01*
X1377550Y17333D01*
X1377383Y17708D01*
Y19500D01*
G01X1374700Y17000D02*
Y19500D01*
X1376242Y17708D01*
X1374158D01*
G01X1383583Y23292D02*
X1383833Y23417D01*
X1384125Y23500D01*
X1384458D01*
X1384833Y23375D01*
X1385125Y23167D01*
X1385333Y22917D01*
X1385500Y22500D01*
X1385542Y22125D01*
X1385458Y21750D01*
X1385333Y21500D01*
X1385083Y21250D01*
X1384792Y21083D01*
X1384500Y21000D01*
X1384208D01*
X1383917Y21083D01*
X1383667Y21208D01*
X1383458Y21375D01*
G01X1382317Y21500D02*
X1382067Y21208D01*
X1381733Y21042D01*
X1381358Y21000D01*
X1381025Y21042D01*
X1380692Y21250D01*
X1380483Y21500D01*
X1380442Y21750D01*
X1380525Y22042D01*
X1380817Y22250D01*
X1381108Y22333D01*
X1381483D01*
G01X1381108D02*
X1380858Y22458D01*
X1380650Y22667D01*
X1380567Y22917D01*
X1380650Y23167D01*
X1380858Y23375D01*
X1381233Y23500D01*
X1381608Y23458D01*
X1381983Y23292D01*
G01X1379217Y23500D02*
Y21708D01*
X1379050Y21333D01*
X1378717Y21083D01*
X1378300Y21000D01*
X1377883Y21083D01*
X1377550Y21333D01*
X1377383Y21708D01*
Y23500D01*
G01X1376117Y21500D02*
X1375867Y21208D01*
X1375533Y21042D01*
X1375158Y21000D01*
X1374825Y21042D01*
X1374492Y21250D01*
X1374283Y21500D01*
X1374242Y21750D01*
X1374325Y22042D01*
X1374617Y22250D01*
X1374908Y22333D01*
X1375283D01*
G01X1374908D02*
X1374658Y22458D01*
X1374450Y22667D01*
X1374367Y22917D01*
X1374450Y23167D01*
X1374658Y23375D01*
X1375033Y23500D01*
X1375408Y23458D01*
X1375783Y23292D01*
G01X1384035Y34522D02*
X1384285Y34647D01*
X1384577Y34730D01*
X1384910D01*
X1385285Y34605D01*
X1385577Y34397D01*
X1385785Y34147D01*
X1385952Y33730D01*
X1385994Y33355D01*
X1385910Y32980D01*
X1385785Y32730D01*
X1385535Y32480D01*
X1385244Y32313D01*
X1384952Y32230D01*
X1384660D01*
X1384369Y32313D01*
X1384119Y32438D01*
X1383910Y32605D01*
G01X1382769Y32730D02*
X1382519Y32438D01*
X1382185Y32272D01*
X1381810Y32230D01*
X1381477Y32272D01*
X1381144Y32480D01*
X1380935Y32730D01*
X1380894Y32980D01*
X1380977Y33272D01*
X1381269Y33480D01*
X1381560Y33563D01*
X1381935D01*
G01X1381560D02*
X1381310Y33688D01*
X1381102Y33897D01*
X1381019Y34147D01*
X1381102Y34397D01*
X1381310Y34605D01*
X1381685Y34730D01*
X1382060Y34688D01*
X1382435Y34522D01*
G01X1379669Y34730D02*
Y32938D01*
X1379502Y32563D01*
X1379169Y32313D01*
X1378752Y32230D01*
X1378335Y32313D01*
X1378002Y32563D01*
X1377835Y32938D01*
Y34730D01*
G01X1376444Y34313D02*
X1376194Y34563D01*
X1375902Y34688D01*
X1375569Y34730D01*
X1375152Y34647D01*
X1374860Y34438D01*
X1374777Y34188D01*
X1374819Y33938D01*
X1374985Y33730D01*
X1375819Y33313D01*
X1376194Y33022D01*
X1376444Y32605D01*
X1376527Y32230D01*
X1374777D01*
G01X1392433Y500D02*
Y3000D01*
X1391392D01*
X1391058Y2875D01*
X1390850Y2708D01*
X1390767Y2375D01*
X1390850Y2042D01*
X1391100Y1833D01*
X1391392Y1708D01*
X1392433D01*
G01X1391392D02*
X1390767Y500D01*
G01X1389417Y1000D02*
X1389167Y708D01*
X1388833Y542D01*
X1388458Y500D01*
X1388125Y542D01*
X1387792Y750D01*
X1387583Y1000D01*
X1387542Y1250D01*
X1387625Y1542D01*
X1387917Y1750D01*
X1388208Y1833D01*
X1388583D01*
G01X1388208D02*
X1387958Y1958D01*
X1387750Y2167D01*
X1387667Y2417D01*
X1387750Y2667D01*
X1387958Y2875D01*
X1388333Y3000D01*
X1388708Y2958D01*
X1389083Y2792D01*
G01X1386317Y3000D02*
Y1208D01*
X1386150Y833D01*
X1385817Y583D01*
X1385400Y500D01*
X1384983Y583D01*
X1384650Y833D01*
X1384483Y1208D01*
Y3000D01*
G01X1383008Y792D02*
X1382717Y583D01*
X1382383Y500D01*
X1382050Y583D01*
X1381758Y833D01*
X1381550Y1208D01*
X1381467Y1583D01*
Y2042D01*
X1381550Y2417D01*
X1381758Y2750D01*
X1382008Y2917D01*
X1382300Y3000D01*
X1382633Y2917D01*
X1382883Y2750D01*
X1383050Y2500D01*
X1383133Y2167D01*
X1383050Y1875D01*
X1382842Y1583D01*
X1382592Y1417D01*
X1382300Y1375D01*
X1381967Y1458D01*
X1381717Y1667D01*
X1381467Y2042D01*
G01X1344000Y-17000D02*
Y-14302D01*
G01Y1000D02*
Y-1695D01*
G01Y22000D02*
Y19305D01*
G01Y4000D02*
Y6698D01*
G01X1391093Y9692D02*
X1391343Y9817D01*
X1391635Y9900D01*
X1391968D01*
X1392343Y9775D01*
X1392635Y9567D01*
X1392843Y9317D01*
X1393010Y8900D01*
X1393052Y8525D01*
X1392968Y8150D01*
X1392843Y7900D01*
X1392593Y7650D01*
X1392302Y7483D01*
X1392010Y7400D01*
X1391718D01*
X1391427Y7483D01*
X1391177Y7608D01*
X1390968Y7775D01*
G01X1388993Y7400D02*
X1388910Y7942D01*
X1388785Y8400D01*
X1388618Y8817D01*
X1388410Y9275D01*
X1388077Y9900D01*
X1389743D01*
G01X1385560Y8650D02*
X1384727D01*
Y7900D01*
X1384977Y7650D01*
X1385268Y7483D01*
X1385685Y7400D01*
X1386102Y7483D01*
X1386393Y7650D01*
X1386643Y7900D01*
X1386810Y8192D01*
X1386893Y8525D01*
Y8817D01*
X1386810Y9067D01*
X1386643Y9358D01*
X1386393Y9608D01*
X1386143Y9775D01*
X1385810Y9900D01*
X1385518D01*
X1385185Y9817D01*
X1384935Y9650D01*
G01X1382210Y7400D02*
Y9900D01*
X1383752Y8108D01*
X1381668D01*
G01X1380402Y9483D02*
X1380152Y9733D01*
X1379860Y9858D01*
X1379527Y9900D01*
X1379110Y9817D01*
X1378818Y9608D01*
X1378735Y9358D01*
X1378777Y9108D01*
X1378943Y8900D01*
X1379777Y8483D01*
X1380152Y8192D01*
X1380402Y7775D01*
X1380485Y7400D01*
X1378735D01*
G01X1392602Y82188D02*
X1392852Y82313D01*
X1393144Y82396D01*
X1393477D01*
X1393852Y82271D01*
X1394144Y82063D01*
X1394352Y81813D01*
X1394519Y81396D01*
X1394561Y81021D01*
X1394477Y80646D01*
X1394352Y80396D01*
X1394102Y80146D01*
X1393811Y79979D01*
X1393519Y79896D01*
X1393227D01*
X1392936Y79979D01*
X1392686Y80104D01*
X1392477Y80271D01*
G01X1391336Y80396D02*
X1391086Y80104D01*
X1390752Y79938D01*
X1390377Y79896D01*
X1390044Y79938D01*
X1389711Y80146D01*
X1389502Y80396D01*
X1389461Y80646D01*
X1389544Y80938D01*
X1389836Y81146D01*
X1390127Y81229D01*
X1390502D01*
G01X1390127D02*
X1389877Y81354D01*
X1389669Y81563D01*
X1389586Y81813D01*
X1389669Y82063D01*
X1389877Y82271D01*
X1390252Y82396D01*
X1390627Y82354D01*
X1391002Y82188D01*
G01X1387319Y82396D02*
Y79896D01*
G01X1388277Y82396D02*
X1386361D01*
G01X1384219Y79896D02*
Y82396D01*
X1384719Y81896D01*
G01Y79896D02*
X1383719D01*
G01X1380619D02*
Y82396D01*
X1382161Y80604D01*
X1380077D01*
G01X1374700Y48067D02*
X1377200D01*
Y49108D01*
X1377075Y49442D01*
X1376908Y49650D01*
X1376575Y49733D01*
X1376242Y49650D01*
X1376033Y49400D01*
X1375908Y49108D01*
Y48067D01*
G01Y49108D02*
X1374700Y49733D01*
G01X1375200Y51083D02*
X1374908Y51333D01*
X1374742Y51667D01*
X1374700Y52042D01*
X1374742Y52375D01*
X1374950Y52708D01*
X1375200Y52917D01*
X1375450Y52958D01*
X1375742Y52875D01*
X1375950Y52583D01*
X1376033Y52292D01*
Y51917D01*
G01Y52292D02*
X1376158Y52542D01*
X1376367Y52750D01*
X1376617Y52833D01*
X1376867Y52750D01*
X1377075Y52542D01*
X1377200Y52167D01*
X1377158Y51792D01*
X1376992Y51417D01*
G01X1377200Y55100D02*
X1374700D01*
G01X1377200Y54142D02*
Y56058D01*
G01X1374700Y58200D02*
X1377200D01*
X1376700Y57700D01*
G01X1374700D02*
Y58700D01*
G01X1375200Y60383D02*
X1374908Y60633D01*
X1374742Y60967D01*
X1374700Y61342D01*
X1374742Y61675D01*
X1374950Y62008D01*
X1375200Y62217D01*
X1375450Y62258D01*
X1375742Y62175D01*
X1375950Y61883D01*
X1376033Y61592D01*
Y61217D01*
G01Y61592D02*
X1376158Y61842D01*
X1376367Y62050D01*
X1376617Y62133D01*
X1376867Y62050D01*
X1377075Y61842D01*
X1377200Y61467D01*
X1377158Y61092D01*
X1376992Y60717D01*
G01X1385483Y35667D02*
Y38167D01*
X1384442D01*
X1384108Y38042D01*
X1383900Y37875D01*
X1383817Y37542D01*
X1383900Y37209D01*
X1384150Y37000D01*
X1384442Y36875D01*
X1385483D01*
G01X1384442D02*
X1383817Y35667D01*
G01X1382467Y36167D02*
X1382217Y35875D01*
X1381883Y35709D01*
X1381508Y35667D01*
X1381175Y35709D01*
X1380842Y35917D01*
X1380633Y36167D01*
X1380592Y36417D01*
X1380675Y36709D01*
X1380967Y36917D01*
X1381258Y37000D01*
X1381633D01*
G01X1381258D02*
X1381008Y37125D01*
X1380800Y37334D01*
X1380717Y37584D01*
X1380800Y37834D01*
X1381008Y38042D01*
X1381383Y38167D01*
X1381758Y38125D01*
X1382133Y37959D01*
G01X1379367Y38167D02*
Y36375D01*
X1379200Y36000D01*
X1378867Y35750D01*
X1378450Y35667D01*
X1378033Y35750D01*
X1377700Y36000D01*
X1377533Y36375D01*
Y38167D01*
G01X1376142Y36709D02*
X1375850Y37000D01*
X1375600Y37167D01*
X1375267Y37250D01*
X1374975Y37167D01*
X1374767Y37000D01*
X1374600Y36750D01*
X1374558Y36459D01*
X1374600Y36209D01*
X1374767Y35959D01*
X1375017Y35750D01*
X1375308Y35667D01*
X1375642Y35750D01*
X1375933Y36000D01*
X1376100Y36375D01*
X1376142Y36792D01*
X1376058Y37334D01*
X1375933Y37625D01*
X1375725Y37917D01*
X1375433Y38125D01*
X1375142Y38167D01*
X1374850Y38084D01*
X1374642Y37875D01*
G01X1358689Y45531D02*
X1358939Y45656D01*
X1359231Y45739D01*
X1359564D01*
X1359939Y45614D01*
X1360231Y45406D01*
X1360439Y45156D01*
X1360606Y44739D01*
X1360648Y44364D01*
X1360564Y43989D01*
X1360439Y43739D01*
X1360189Y43489D01*
X1359898Y43322D01*
X1359606Y43239D01*
X1359314D01*
X1359023Y43322D01*
X1358773Y43447D01*
X1358564Y43614D01*
G01X1356589Y43239D02*
X1356506Y43781D01*
X1356381Y44239D01*
X1356214Y44656D01*
X1356006Y45114D01*
X1355673Y45739D01*
X1357339D01*
G01X1353156Y44489D02*
X1352323D01*
Y43739D01*
X1352573Y43489D01*
X1352864Y43322D01*
X1353281Y43239D01*
X1353698Y43322D01*
X1353989Y43489D01*
X1354239Y43739D01*
X1354406Y44031D01*
X1354489Y44364D01*
Y44656D01*
X1354406Y44906D01*
X1354239Y45197D01*
X1353989Y45447D01*
X1353739Y45614D01*
X1353406Y45739D01*
X1353114D01*
X1352781Y45656D01*
X1352531Y45489D01*
G01X1351223Y43739D02*
X1350973Y43447D01*
X1350639Y43281D01*
X1350264Y43239D01*
X1349931Y43281D01*
X1349598Y43489D01*
X1349389Y43739D01*
X1349348Y43989D01*
X1349431Y44281D01*
X1349723Y44489D01*
X1350014Y44572D01*
X1350389D01*
G01X1350014D02*
X1349764Y44697D01*
X1349556Y44906D01*
X1349473Y45156D01*
X1349556Y45406D01*
X1349764Y45614D01*
X1350139Y45739D01*
X1350514Y45697D01*
X1350889Y45531D01*
G01X1348123Y43614D02*
X1347873Y43406D01*
X1347581Y43281D01*
X1347206Y43239D01*
X1346831Y43322D01*
X1346539Y43489D01*
X1346331Y43781D01*
X1346289Y44114D01*
X1346373Y44447D01*
X1346581Y44656D01*
X1346873Y44822D01*
X1347164Y44864D01*
X1347456Y44822D01*
X1347831Y44656D01*
X1347706Y45739D01*
X1346581D01*
G01X1393264Y86046D02*
X1393514Y86171D01*
X1393806Y86254D01*
X1394139D01*
X1394514Y86129D01*
X1394806Y85921D01*
X1395014Y85671D01*
X1395181Y85254D01*
X1395223Y84879D01*
X1395139Y84504D01*
X1395014Y84254D01*
X1394764Y84004D01*
X1394473Y83837D01*
X1394181Y83754D01*
X1393889D01*
X1393598Y83837D01*
X1393348Y83962D01*
X1393139Y84129D01*
G01X1391873Y85837D02*
X1391623Y86087D01*
X1391331Y86212D01*
X1390998Y86254D01*
X1390581Y86171D01*
X1390289Y85962D01*
X1390206Y85712D01*
X1390248Y85462D01*
X1390414Y85254D01*
X1391248Y84837D01*
X1391623Y84546D01*
X1391873Y84129D01*
X1391956Y83754D01*
X1390206D01*
G01X1388773Y85837D02*
X1388523Y86087D01*
X1388231Y86212D01*
X1387898Y86254D01*
X1387481Y86171D01*
X1387189Y85962D01*
X1387106Y85712D01*
X1387148Y85462D01*
X1387314Y85254D01*
X1388148Y84837D01*
X1388523Y84546D01*
X1388773Y84129D01*
X1388856Y83754D01*
X1387106D01*
G01X1386131Y86254D02*
X1385548Y83754D01*
X1384881Y86254D01*
X1384214Y83754D01*
X1383631Y86254D01*
G01X1381781Y83754D02*
Y86254D01*
X1382281Y85754D01*
G01Y83754D02*
X1381281D01*
G01X1378681Y86254D02*
X1379014Y86171D01*
X1379264Y85962D01*
X1379431Y85712D01*
X1379556Y85379D01*
X1379598Y85004D01*
X1379556Y84629D01*
X1379431Y84296D01*
X1379264Y84046D01*
X1379014Y83837D01*
X1378681Y83754D01*
X1378348Y83837D01*
X1378098Y84046D01*
X1377931Y84296D01*
X1377806Y84629D01*
X1377764Y85004D01*
X1377806Y85379D01*
X1377931Y85712D01*
X1378098Y85962D01*
X1378348Y86171D01*
X1378681Y86254D01*
G01X1372053Y105360D02*
X1372303Y105485D01*
X1372595Y105568D01*
X1372928D01*
X1373303Y105443D01*
X1373595Y105235D01*
X1373803Y104985D01*
X1373970Y104568D01*
X1374012Y104193D01*
X1373928Y103818D01*
X1373803Y103568D01*
X1373553Y103318D01*
X1373262Y103151D01*
X1372970Y103068D01*
X1372678D01*
X1372387Y103151D01*
X1372137Y103276D01*
X1371928Y103443D01*
G01X1370787Y103568D02*
X1370537Y103276D01*
X1370203Y103110D01*
X1369828Y103068D01*
X1369495Y103110D01*
X1369162Y103318D01*
X1368953Y103568D01*
X1368912Y103818D01*
X1368995Y104110D01*
X1369287Y104318D01*
X1369578Y104401D01*
X1369953D01*
G01X1369578D02*
X1369328Y104526D01*
X1369120Y104735D01*
X1369037Y104985D01*
X1369120Y105235D01*
X1369328Y105443D01*
X1369703Y105568D01*
X1370078Y105526D01*
X1370453Y105360D01*
G01X1366770Y105568D02*
Y103068D01*
G01X1367728Y105568D02*
X1365812D01*
G01X1363670Y103068D02*
Y105568D01*
X1364170Y105068D01*
G01Y103068D02*
X1363170D01*
G01X1361362Y105151D02*
X1361112Y105401D01*
X1360820Y105526D01*
X1360487Y105568D01*
X1360070Y105485D01*
X1359778Y105276D01*
X1359695Y105026D01*
X1359737Y104776D01*
X1359903Y104568D01*
X1360737Y104151D01*
X1361112Y103860D01*
X1361362Y103443D01*
X1361445Y103068D01*
X1359695D01*
G01X1388292Y113067D02*
X1388417Y112817D01*
X1388500Y112525D01*
Y112192D01*
X1388375Y111817D01*
X1388167Y111525D01*
X1387917Y111317D01*
X1387500Y111150D01*
X1387125Y111108D01*
X1386750Y111192D01*
X1386500Y111317D01*
X1386250Y111567D01*
X1386083Y111858D01*
X1386000Y112150D01*
Y112442D01*
X1386083Y112733D01*
X1386208Y112983D01*
X1386375Y113192D01*
G01X1386500Y114333D02*
X1386208Y114583D01*
X1386042Y114917D01*
X1386000Y115292D01*
X1386042Y115625D01*
X1386250Y115958D01*
X1386500Y116167D01*
X1386750Y116208D01*
X1387042Y116125D01*
X1387250Y115833D01*
X1387333Y115542D01*
Y115167D01*
G01Y115542D02*
X1387458Y115792D01*
X1387667Y116000D01*
X1387917Y116083D01*
X1388167Y116000D01*
X1388375Y115792D01*
X1388500Y115417D01*
X1388458Y115042D01*
X1388292Y114667D01*
G01X1388500Y118350D02*
X1386000D01*
G01X1388500Y117392D02*
Y119308D01*
G01X1386000Y121450D02*
X1386042Y121742D01*
X1386167Y122075D01*
X1386375Y122283D01*
X1386667Y122367D01*
X1386958Y122283D01*
X1387208Y122033D01*
X1387333Y121658D01*
Y121242D01*
X1387417Y120992D01*
X1387625Y120783D01*
X1387917Y120700D01*
X1388208Y120825D01*
X1388417Y121117D01*
X1388500Y121450D01*
X1388417Y121783D01*
X1388208Y122075D01*
X1387917Y122200D01*
X1387625Y122117D01*
X1387417Y121908D01*
X1387333Y121658D01*
Y121242D01*
X1387208Y120867D01*
X1386958Y120617D01*
X1386667Y120533D01*
X1386375Y120617D01*
X1386167Y120825D01*
X1386042Y121158D01*
X1386000Y121450D01*
G01X1371792Y112317D02*
X1371917Y112067D01*
X1372000Y111775D01*
Y111442D01*
X1371875Y111067D01*
X1371667Y110775D01*
X1371417Y110567D01*
X1371000Y110400D01*
X1370625Y110358D01*
X1370250Y110442D01*
X1370000Y110567D01*
X1369750Y110817D01*
X1369583Y111108D01*
X1369500Y111400D01*
Y111692D01*
X1369583Y111983D01*
X1369708Y112233D01*
X1369875Y112442D01*
G01X1370000Y113583D02*
X1369708Y113833D01*
X1369542Y114167D01*
X1369500Y114542D01*
X1369542Y114875D01*
X1369750Y115208D01*
X1370000Y115417D01*
X1370250Y115458D01*
X1370542Y115375D01*
X1370750Y115083D01*
X1370833Y114792D01*
Y114417D01*
G01Y114792D02*
X1370958Y115042D01*
X1371167Y115250D01*
X1371417Y115333D01*
X1371667Y115250D01*
X1371875Y115042D01*
X1372000Y114667D01*
X1371958Y114292D01*
X1371792Y113917D01*
G01X1372000Y117600D02*
X1369500D01*
G01X1372000Y116642D02*
Y118558D01*
G01X1369500Y120700D02*
X1372000D01*
X1371500Y120200D01*
G01X1369500D02*
Y121200D01*
G01X1372000Y123800D02*
X1371917Y123467D01*
X1371708Y123217D01*
X1371458Y123050D01*
X1371125Y122925D01*
X1370750Y122883D01*
X1370375Y122925D01*
X1370042Y123050D01*
X1369792Y123217D01*
X1369583Y123467D01*
X1369500Y123800D01*
X1369583Y124133D01*
X1369792Y124383D01*
X1370042Y124550D01*
X1370375Y124675D01*
X1370750Y124717D01*
X1371125Y124675D01*
X1371458Y124550D01*
X1371708Y124383D01*
X1371917Y124133D01*
X1372000Y123800D01*
G01X1400700Y139364D02*
X1397138D01*
Y126568D01*
X1400700D01*
G01X1398000Y104000D02*
X1400698D01*
G01X1398000D02*
Y126575D01*
G01X1394010Y136647D02*
X1394135Y136397D01*
X1394218Y136105D01*
Y135772D01*
X1394093Y135397D01*
X1393885Y135105D01*
X1393635Y134897D01*
X1393218Y134730D01*
X1392843Y134688D01*
X1392468Y134772D01*
X1392218Y134897D01*
X1391968Y135147D01*
X1391801Y135438D01*
X1391718Y135730D01*
Y136022D01*
X1391801Y136313D01*
X1391926Y136563D01*
X1392093Y136772D01*
G01X1392218Y137913D02*
X1391926Y138163D01*
X1391760Y138497D01*
X1391718Y138872D01*
X1391760Y139205D01*
X1391968Y139538D01*
X1392218Y139747D01*
X1392468Y139788D01*
X1392760Y139705D01*
X1392968Y139413D01*
X1393051Y139122D01*
Y138747D01*
G01Y139122D02*
X1393176Y139372D01*
X1393385Y139580D01*
X1393635Y139663D01*
X1393885Y139580D01*
X1394093Y139372D01*
X1394218Y138997D01*
X1394176Y138622D01*
X1394010Y138247D01*
G01X1394218Y141930D02*
X1391718D01*
G01X1394218Y140972D02*
Y142888D01*
G01X1392218Y144113D02*
X1391926Y144363D01*
X1391760Y144697D01*
X1391718Y145072D01*
X1391760Y145405D01*
X1391968Y145738D01*
X1392218Y145947D01*
X1392468Y145988D01*
X1392760Y145905D01*
X1392968Y145613D01*
X1393051Y145322D01*
Y144947D01*
G01Y145322D02*
X1393176Y145572D01*
X1393385Y145780D01*
X1393635Y145863D01*
X1393885Y145780D01*
X1394093Y145572D01*
X1394218Y145197D01*
X1394176Y144822D01*
X1394010Y144447D01*
G01X1390364Y130700D02*
Y126909D01*
X1377568D01*
Y130700D01*
G01X1390364Y143300D02*
Y146862D01*
X1377568D01*
Y143300D01*
G01X1355000Y146000D02*
Y143302D01*
G01Y128000D02*
Y130695D01*
G01Y128000D02*
X1377572D01*
G01X1355000Y146000D02*
X1377575D01*
G01X1414096Y189483D02*
Y191983D01*
X1413055D01*
X1412721Y191858D01*
X1412513Y191691D01*
X1412430Y191358D01*
X1412513Y191025D01*
X1412763Y190816D01*
X1413055Y190691D01*
X1414096D01*
G01X1413055D02*
X1412430Y189483D01*
G01X1410955Y191566D02*
X1410705Y191816D01*
X1410413Y191941D01*
X1410080Y191983D01*
X1409663Y191900D01*
X1409371Y191691D01*
X1409288Y191441D01*
X1409330Y191191D01*
X1409496Y190983D01*
X1410330Y190566D01*
X1410705Y190275D01*
X1410955Y189858D01*
X1411038Y189483D01*
X1409288D01*
G01X1407063Y191983D02*
Y189483D01*
G01X1408021Y191983D02*
X1406105D01*
G01X1404755Y190525D02*
X1404463Y190816D01*
X1404213Y190983D01*
X1403880Y191066D01*
X1403588Y190983D01*
X1403380Y190816D01*
X1403213Y190566D01*
X1403171Y190275D01*
X1403213Y190025D01*
X1403380Y189775D01*
X1403630Y189566D01*
X1403921Y189483D01*
X1404255Y189566D01*
X1404546Y189816D01*
X1404713Y190191D01*
X1404755Y190608D01*
X1404671Y191150D01*
X1404546Y191441D01*
X1404338Y191733D01*
X1404046Y191941D01*
X1403755Y191983D01*
X1403463Y191900D01*
X1403255Y191691D01*
G01X1400946Y189483D02*
X1400863Y190025D01*
X1400738Y190483D01*
X1400571Y190900D01*
X1400363Y191358D01*
X1400030Y191983D01*
X1401696D01*
G01X1398977Y187867D02*
Y190367D01*
X1397936D01*
X1397602Y190242D01*
X1397394Y190075D01*
X1397311Y189742D01*
X1397394Y189409D01*
X1397644Y189200D01*
X1397936Y189075D01*
X1398977D01*
G01X1397936D02*
X1397311Y187867D01*
G01X1395836Y189950D02*
X1395586Y190200D01*
X1395294Y190325D01*
X1394961Y190367D01*
X1394544Y190284D01*
X1394252Y190075D01*
X1394169Y189825D01*
X1394211Y189575D01*
X1394377Y189367D01*
X1395211Y188950D01*
X1395586Y188659D01*
X1395836Y188242D01*
X1395919Y187867D01*
X1394169D01*
G01X1391944Y190367D02*
Y187867D01*
G01X1392902Y190367D02*
X1390986D01*
G01X1389761Y188367D02*
X1389511Y188075D01*
X1389177Y187909D01*
X1388802Y187867D01*
X1388469Y187909D01*
X1388136Y188117D01*
X1387927Y188367D01*
X1387886Y188617D01*
X1387969Y188909D01*
X1388261Y189117D01*
X1388552Y189200D01*
X1388927D01*
G01X1388552D02*
X1388302Y189325D01*
X1388094Y189534D01*
X1388011Y189784D01*
X1388094Y190034D01*
X1388302Y190242D01*
X1388677Y190367D01*
X1389052Y190325D01*
X1389427Y190159D01*
G01X1385744Y187867D02*
X1385452Y187909D01*
X1385119Y188034D01*
X1384911Y188242D01*
X1384827Y188534D01*
X1384911Y188825D01*
X1385161Y189075D01*
X1385536Y189200D01*
X1385952D01*
X1386202Y189284D01*
X1386411Y189492D01*
X1386494Y189784D01*
X1386369Y190075D01*
X1386077Y190284D01*
X1385744Y190367D01*
X1385411Y190284D01*
X1385119Y190075D01*
X1384994Y189784D01*
X1385077Y189492D01*
X1385286Y189284D01*
X1385536Y189200D01*
X1385952D01*
X1386327Y189075D01*
X1386577Y188825D01*
X1386661Y188534D01*
X1386577Y188242D01*
X1386369Y188034D01*
X1386036Y187909D01*
X1385744Y187867D01*
G01X1381650Y216017D02*
X1384150D01*
Y217058D01*
X1384025Y217392D01*
X1383858Y217600D01*
X1383525Y217683D01*
X1383192Y217600D01*
X1382983Y217350D01*
X1382858Y217058D01*
Y216017D01*
G01Y217058D02*
X1381650Y217683D01*
G01X1383733Y219158D02*
X1383983Y219408D01*
X1384108Y219700D01*
X1384150Y220033D01*
X1384067Y220450D01*
X1383858Y220742D01*
X1383608Y220825D01*
X1383358Y220783D01*
X1383150Y220617D01*
X1382733Y219783D01*
X1382442Y219408D01*
X1382025Y219158D01*
X1381650Y219075D01*
Y220825D01*
G01X1384150Y222133D02*
X1382358D01*
X1381983Y222300D01*
X1381733Y222633D01*
X1381650Y223050D01*
X1381733Y223467D01*
X1381983Y223800D01*
X1382358Y223967D01*
X1384150D01*
G01X1383733Y225358D02*
X1383983Y225608D01*
X1384108Y225900D01*
X1384150Y226233D01*
X1384067Y226650D01*
X1383858Y226942D01*
X1383608Y227025D01*
X1383358Y226983D01*
X1383150Y226817D01*
X1382733Y225983D01*
X1382442Y225608D01*
X1382025Y225358D01*
X1381650Y225275D01*
Y227025D01*
G01X1381942Y228542D02*
X1381733Y228833D01*
X1381650Y229167D01*
X1381733Y229500D01*
X1381983Y229792D01*
X1382358Y230000D01*
X1382733Y230083D01*
X1383192D01*
X1383567Y230000D01*
X1383900Y229792D01*
X1384067Y229542D01*
X1384150Y229250D01*
X1384067Y228917D01*
X1383900Y228667D01*
X1383650Y228500D01*
X1383317Y228417D01*
X1383025Y228500D01*
X1382733Y228708D01*
X1382567Y228958D01*
X1382525Y229250D01*
X1382608Y229583D01*
X1382817Y229833D01*
X1383192Y230083D01*
G01X1414096Y181483D02*
Y183983D01*
X1413055D01*
X1412721Y183858D01*
X1412513Y183691D01*
X1412430Y183358D01*
X1412513Y183025D01*
X1412763Y182816D01*
X1413055Y182691D01*
X1414096D01*
G01X1413055D02*
X1412430Y181483D01*
G01X1410955Y183566D02*
X1410705Y183816D01*
X1410413Y183941D01*
X1410080Y183983D01*
X1409663Y183900D01*
X1409371Y183691D01*
X1409288Y183441D01*
X1409330Y183191D01*
X1409496Y182983D01*
X1410330Y182566D01*
X1410705Y182275D01*
X1410955Y181858D01*
X1411038Y181483D01*
X1409288D01*
G01X1407063Y183983D02*
Y181483D01*
G01X1408021Y183983D02*
X1406105D01*
G01X1404755Y182525D02*
X1404463Y182816D01*
X1404213Y182983D01*
X1403880Y183066D01*
X1403588Y182983D01*
X1403380Y182816D01*
X1403213Y182566D01*
X1403171Y182275D01*
X1403213Y182025D01*
X1403380Y181775D01*
X1403630Y181566D01*
X1403921Y181483D01*
X1404255Y181566D01*
X1404546Y181816D01*
X1404713Y182191D01*
X1404755Y182608D01*
X1404671Y183150D01*
X1404546Y183441D01*
X1404338Y183733D01*
X1404046Y183941D01*
X1403755Y183983D01*
X1403463Y183900D01*
X1403255Y183691D01*
G01X1401780Y181858D02*
X1401530Y181650D01*
X1401238Y181525D01*
X1400863Y181483D01*
X1400488Y181566D01*
X1400196Y181733D01*
X1399988Y182025D01*
X1399946Y182358D01*
X1400030Y182691D01*
X1400238Y182900D01*
X1400530Y183066D01*
X1400821Y183108D01*
X1401113Y183066D01*
X1401488Y182900D01*
X1401363Y183983D01*
X1400238D01*
G01X1414096Y185483D02*
Y187983D01*
X1413055D01*
X1412721Y187858D01*
X1412513Y187691D01*
X1412430Y187358D01*
X1412513Y187025D01*
X1412763Y186816D01*
X1413055Y186691D01*
X1414096D01*
G01X1413055D02*
X1412430Y185483D01*
G01X1410955Y187566D02*
X1410705Y187816D01*
X1410413Y187941D01*
X1410080Y187983D01*
X1409663Y187900D01*
X1409371Y187691D01*
X1409288Y187441D01*
X1409330Y187191D01*
X1409496Y186983D01*
X1410330Y186566D01*
X1410705Y186275D01*
X1410955Y185858D01*
X1411038Y185483D01*
X1409288D01*
G01X1407063Y187983D02*
Y185483D01*
G01X1408021Y187983D02*
X1406105D01*
G01X1404755Y186525D02*
X1404463Y186816D01*
X1404213Y186983D01*
X1403880Y187066D01*
X1403588Y186983D01*
X1403380Y186816D01*
X1403213Y186566D01*
X1403171Y186275D01*
X1403213Y186025D01*
X1403380Y185775D01*
X1403630Y185566D01*
X1403921Y185483D01*
X1404255Y185566D01*
X1404546Y185816D01*
X1404713Y186191D01*
X1404755Y186608D01*
X1404671Y187150D01*
X1404546Y187441D01*
X1404338Y187733D01*
X1404046Y187941D01*
X1403755Y187983D01*
X1403463Y187900D01*
X1403255Y187691D01*
G01X1401655Y186525D02*
X1401363Y186816D01*
X1401113Y186983D01*
X1400780Y187066D01*
X1400488Y186983D01*
X1400280Y186816D01*
X1400113Y186566D01*
X1400071Y186275D01*
X1400113Y186025D01*
X1400280Y185775D01*
X1400530Y185566D01*
X1400821Y185483D01*
X1401155Y185566D01*
X1401446Y185816D01*
X1401613Y186191D01*
X1401655Y186608D01*
X1401571Y187150D01*
X1401446Y187441D01*
X1401238Y187733D01*
X1400946Y187941D01*
X1400655Y187983D01*
X1400363Y187900D01*
X1400155Y187691D01*
G01X1398854Y183917D02*
Y186417D01*
X1397813D01*
X1397479Y186292D01*
X1397271Y186125D01*
X1397188Y185792D01*
X1397271Y185459D01*
X1397521Y185250D01*
X1397813Y185125D01*
X1398854D01*
G01X1397813D02*
X1397188Y183917D01*
G01X1395713Y186000D02*
X1395463Y186250D01*
X1395171Y186375D01*
X1394838Y186417D01*
X1394421Y186334D01*
X1394129Y186125D01*
X1394046Y185875D01*
X1394088Y185625D01*
X1394254Y185417D01*
X1395088Y185000D01*
X1395463Y184709D01*
X1395713Y184292D01*
X1395796Y183917D01*
X1394046D01*
G01X1391821Y186417D02*
Y183917D01*
G01X1392779Y186417D02*
X1390863D01*
G01X1389513Y184959D02*
X1389221Y185250D01*
X1388971Y185417D01*
X1388638Y185500D01*
X1388346Y185417D01*
X1388138Y185250D01*
X1387971Y185000D01*
X1387929Y184709D01*
X1387971Y184459D01*
X1388138Y184209D01*
X1388388Y184000D01*
X1388679Y183917D01*
X1389013Y184000D01*
X1389304Y184250D01*
X1389471Y184625D01*
X1389513Y185042D01*
X1389429Y185584D01*
X1389304Y185875D01*
X1389096Y186167D01*
X1388804Y186375D01*
X1388513Y186417D01*
X1388221Y186334D01*
X1388013Y186125D01*
G01X1386413Y186000D02*
X1386163Y186250D01*
X1385871Y186375D01*
X1385538Y186417D01*
X1385121Y186334D01*
X1384829Y186125D01*
X1384746Y185875D01*
X1384788Y185625D01*
X1384954Y185417D01*
X1385788Y185000D01*
X1386163Y184709D01*
X1386413Y184292D01*
X1386496Y183917D01*
X1384746D01*
G01X1398854Y179917D02*
Y182417D01*
X1397813D01*
X1397479Y182292D01*
X1397271Y182125D01*
X1397188Y181792D01*
X1397271Y181459D01*
X1397521Y181250D01*
X1397813Y181125D01*
X1398854D01*
G01X1397813D02*
X1397188Y179917D01*
G01X1395713Y182000D02*
X1395463Y182250D01*
X1395171Y182375D01*
X1394838Y182417D01*
X1394421Y182334D01*
X1394129Y182125D01*
X1394046Y181875D01*
X1394088Y181625D01*
X1394254Y181417D01*
X1395088Y181000D01*
X1395463Y180709D01*
X1395713Y180292D01*
X1395796Y179917D01*
X1394046D01*
G01X1391821Y182417D02*
Y179917D01*
G01X1392779Y182417D02*
X1390863D01*
G01X1389638Y180417D02*
X1389388Y180125D01*
X1389054Y179959D01*
X1388679Y179917D01*
X1388346Y179959D01*
X1388013Y180167D01*
X1387804Y180417D01*
X1387763Y180667D01*
X1387846Y180959D01*
X1388138Y181167D01*
X1388429Y181250D01*
X1388804D01*
G01X1388429D02*
X1388179Y181375D01*
X1387971Y181584D01*
X1387888Y181834D01*
X1387971Y182084D01*
X1388179Y182292D01*
X1388554Y182417D01*
X1388929Y182375D01*
X1389304Y182209D01*
G01X1386538Y180417D02*
X1386288Y180125D01*
X1385954Y179959D01*
X1385579Y179917D01*
X1385246Y179959D01*
X1384913Y180167D01*
X1384704Y180417D01*
X1384663Y180667D01*
X1384746Y180959D01*
X1385038Y181167D01*
X1385329Y181250D01*
X1385704D01*
G01X1385329D02*
X1385079Y181375D01*
X1384871Y181584D01*
X1384788Y181834D01*
X1384871Y182084D01*
X1385079Y182292D01*
X1385454Y182417D01*
X1385829Y182375D01*
X1386204Y182209D01*
G01X1398617Y176450D02*
Y178950D01*
X1397576D01*
X1397242Y178825D01*
X1397034Y178658D01*
X1396951Y178325D01*
X1397034Y177992D01*
X1397284Y177783D01*
X1397576Y177658D01*
X1398617D01*
G01X1397576D02*
X1396951Y176450D01*
G01X1395476Y178533D02*
X1395226Y178783D01*
X1394934Y178908D01*
X1394601Y178950D01*
X1394184Y178867D01*
X1393892Y178658D01*
X1393809Y178408D01*
X1393851Y178158D01*
X1394017Y177950D01*
X1394851Y177533D01*
X1395226Y177242D01*
X1395476Y176825D01*
X1395559Y176450D01*
X1393809D01*
G01X1391584Y178950D02*
Y176450D01*
G01X1392542Y178950D02*
X1390626D01*
G01X1389401Y176950D02*
X1389151Y176658D01*
X1388817Y176492D01*
X1388442Y176450D01*
X1388109Y176492D01*
X1387776Y176700D01*
X1387567Y176950D01*
X1387526Y177200D01*
X1387609Y177492D01*
X1387901Y177700D01*
X1388192Y177783D01*
X1388567D01*
G01X1388192D02*
X1387942Y177908D01*
X1387734Y178117D01*
X1387651Y178367D01*
X1387734Y178617D01*
X1387942Y178825D01*
X1388317Y178950D01*
X1388692Y178908D01*
X1389067Y178742D01*
G01X1385384Y178950D02*
X1385717Y178867D01*
X1385967Y178658D01*
X1386134Y178408D01*
X1386259Y178075D01*
X1386301Y177700D01*
X1386259Y177325D01*
X1386134Y176992D01*
X1385967Y176742D01*
X1385717Y176533D01*
X1385384Y176450D01*
X1385051Y176533D01*
X1384801Y176742D01*
X1384634Y176992D01*
X1384509Y177325D01*
X1384467Y177700D01*
X1384509Y178075D01*
X1384634Y178408D01*
X1384801Y178658D01*
X1385051Y178867D01*
X1385384Y178950D01*
G01X1398617Y172450D02*
Y174950D01*
X1397576D01*
X1397242Y174825D01*
X1397034Y174658D01*
X1396951Y174325D01*
X1397034Y173992D01*
X1397284Y173783D01*
X1397576Y173658D01*
X1398617D01*
G01X1397576D02*
X1396951Y172450D01*
G01X1395476Y174533D02*
X1395226Y174783D01*
X1394934Y174908D01*
X1394601Y174950D01*
X1394184Y174867D01*
X1393892Y174658D01*
X1393809Y174408D01*
X1393851Y174158D01*
X1394017Y173950D01*
X1394851Y173533D01*
X1395226Y173242D01*
X1395476Y172825D01*
X1395559Y172450D01*
X1393809D01*
G01X1391584Y174950D02*
Y172450D01*
G01X1392542Y174950D02*
X1390626D01*
G01X1389401Y172825D02*
X1389151Y172617D01*
X1388859Y172492D01*
X1388484Y172450D01*
X1388109Y172533D01*
X1387817Y172700D01*
X1387609Y172992D01*
X1387567Y173325D01*
X1387651Y173658D01*
X1387859Y173867D01*
X1388151Y174033D01*
X1388442Y174075D01*
X1388734Y174033D01*
X1389109Y173867D01*
X1388984Y174950D01*
X1387859D01*
G01X1385384Y172450D02*
X1385092Y172492D01*
X1384759Y172617D01*
X1384551Y172825D01*
X1384467Y173117D01*
X1384551Y173408D01*
X1384801Y173658D01*
X1385176Y173783D01*
X1385592D01*
X1385842Y173867D01*
X1386051Y174075D01*
X1386134Y174367D01*
X1386009Y174658D01*
X1385717Y174867D01*
X1385384Y174950D01*
X1385051Y174867D01*
X1384759Y174658D01*
X1384634Y174367D01*
X1384717Y174075D01*
X1384926Y173867D01*
X1385176Y173783D01*
X1385592D01*
X1385967Y173658D01*
X1386217Y173408D01*
X1386301Y173117D01*
X1386217Y172825D01*
X1386009Y172617D01*
X1385676Y172492D01*
X1385384Y172450D01*
G01X1414096Y193483D02*
Y195983D01*
X1413055D01*
X1412721Y195858D01*
X1412513Y195691D01*
X1412430Y195358D01*
X1412513Y195025D01*
X1412763Y194816D01*
X1413055Y194691D01*
X1414096D01*
G01X1413055D02*
X1412430Y193483D01*
G01X1410246D02*
X1410163Y194025D01*
X1410038Y194483D01*
X1409871Y194900D01*
X1409663Y195358D01*
X1409330Y195983D01*
X1410996D01*
G01X1407980Y193483D02*
Y195983D01*
X1407146D01*
X1406813Y195858D01*
X1406563Y195691D01*
X1406355Y195441D01*
X1406188Y195150D01*
X1406146Y194733D01*
X1406188Y194316D01*
X1406355Y194025D01*
X1406563Y193775D01*
X1406813Y193608D01*
X1407146Y193483D01*
X1407980D01*
G01X1403463D02*
Y195983D01*
X1405005Y194191D01*
X1402921D01*
G01X1400863Y193483D02*
Y195983D01*
X1401363Y195483D01*
G01Y193483D02*
X1400363D01*
G01X1398977Y191867D02*
Y194367D01*
X1397936D01*
X1397602Y194242D01*
X1397394Y194075D01*
X1397311Y193742D01*
X1397394Y193409D01*
X1397644Y193200D01*
X1397936Y193075D01*
X1398977D01*
G01X1397936D02*
X1397311Y191867D01*
G01X1395836Y193950D02*
X1395586Y194200D01*
X1395294Y194325D01*
X1394961Y194367D01*
X1394544Y194284D01*
X1394252Y194075D01*
X1394169Y193825D01*
X1394211Y193575D01*
X1394377Y193367D01*
X1395211Y192950D01*
X1395586Y192659D01*
X1395836Y192242D01*
X1395919Y191867D01*
X1394169D01*
G01X1391944Y194367D02*
Y191867D01*
G01X1392902Y194367D02*
X1390986D01*
G01X1388927Y191867D02*
X1388844Y192409D01*
X1388719Y192867D01*
X1388552Y193284D01*
X1388344Y193742D01*
X1388011Y194367D01*
X1389677D01*
G01X1385744Y191867D02*
Y194367D01*
X1386244Y193867D01*
G01Y191867D02*
X1385244D01*
G01X1398977Y199867D02*
Y202367D01*
X1397936D01*
X1397602Y202242D01*
X1397394Y202075D01*
X1397311Y201742D01*
X1397394Y201409D01*
X1397644Y201200D01*
X1397936Y201075D01*
X1398977D01*
G01X1397936D02*
X1397311Y199867D01*
G01X1395127D02*
X1395044Y200409D01*
X1394919Y200867D01*
X1394752Y201284D01*
X1394544Y201742D01*
X1394211Y202367D01*
X1395877D01*
G01X1392861Y199867D02*
Y202367D01*
X1392027D01*
X1391694Y202242D01*
X1391444Y202075D01*
X1391236Y201825D01*
X1391069Y201534D01*
X1391027Y201117D01*
X1391069Y200700D01*
X1391236Y200409D01*
X1391444Y200159D01*
X1391694Y199992D01*
X1392027Y199867D01*
X1392861D01*
G01X1389636Y201950D02*
X1389386Y202200D01*
X1389094Y202325D01*
X1388761Y202367D01*
X1388344Y202284D01*
X1388052Y202075D01*
X1387969Y201825D01*
X1388011Y201575D01*
X1388177Y201367D01*
X1389011Y200950D01*
X1389386Y200659D01*
X1389636Y200242D01*
X1389719Y199867D01*
X1387969D01*
G01X1385244D02*
Y202367D01*
X1386786Y200575D01*
X1384702D01*
G01X1398977Y195867D02*
Y198367D01*
X1397936D01*
X1397602Y198242D01*
X1397394Y198075D01*
X1397311Y197742D01*
X1397394Y197409D01*
X1397644Y197200D01*
X1397936Y197075D01*
X1398977D01*
G01X1397936D02*
X1397311Y195867D01*
G01X1395127D02*
X1395044Y196409D01*
X1394919Y196867D01*
X1394752Y197284D01*
X1394544Y197742D01*
X1394211Y198367D01*
X1395877D01*
G01X1392861Y195867D02*
Y198367D01*
X1392027D01*
X1391694Y198242D01*
X1391444Y198075D01*
X1391236Y197825D01*
X1391069Y197534D01*
X1391027Y197117D01*
X1391069Y196700D01*
X1391236Y196409D01*
X1391444Y196159D01*
X1391694Y195992D01*
X1392027Y195867D01*
X1392861D01*
G01X1388344D02*
Y198367D01*
X1389886Y196575D01*
X1387802D01*
G01X1386661Y196367D02*
X1386411Y196075D01*
X1386077Y195909D01*
X1385702Y195867D01*
X1385369Y195909D01*
X1385036Y196117D01*
X1384827Y196367D01*
X1384786Y196617D01*
X1384869Y196909D01*
X1385161Y197117D01*
X1385452Y197200D01*
X1385827D01*
G01X1385452D02*
X1385202Y197325D01*
X1384994Y197534D01*
X1384911Y197784D01*
X1384994Y198034D01*
X1385202Y198242D01*
X1385577Y198367D01*
X1385952Y198325D01*
X1386327Y198159D01*
G01X1369737Y216147D02*
X1372237D01*
Y217188D01*
X1372112Y217522D01*
X1371945Y217730D01*
X1371612Y217813D01*
X1371279Y217730D01*
X1371070Y217480D01*
X1370945Y217188D01*
Y216147D01*
G01Y217188D02*
X1369737Y217813D01*
G01X1371820Y219288D02*
X1372070Y219538D01*
X1372195Y219830D01*
X1372237Y220163D01*
X1372154Y220580D01*
X1371945Y220872D01*
X1371695Y220955D01*
X1371445Y220913D01*
X1371237Y220747D01*
X1370820Y219913D01*
X1370529Y219538D01*
X1370112Y219288D01*
X1369737Y219205D01*
Y220955D01*
G01X1372237Y222263D02*
X1370445D01*
X1370070Y222430D01*
X1369820Y222763D01*
X1369737Y223180D01*
X1369820Y223597D01*
X1370070Y223930D01*
X1370445Y224097D01*
X1372237D01*
G01X1371820Y225488D02*
X1372070Y225738D01*
X1372195Y226030D01*
X1372237Y226363D01*
X1372154Y226780D01*
X1371945Y227072D01*
X1371695Y227155D01*
X1371445Y227113D01*
X1371237Y226947D01*
X1370820Y226113D01*
X1370529Y225738D01*
X1370112Y225488D01*
X1369737Y225405D01*
Y227155D01*
G01X1370779Y228588D02*
X1371070Y228880D01*
X1371237Y229130D01*
X1371320Y229463D01*
X1371237Y229755D01*
X1371070Y229963D01*
X1370820Y230130D01*
X1370529Y230172D01*
X1370279Y230130D01*
X1370029Y229963D01*
X1369820Y229713D01*
X1369737Y229422D01*
X1369820Y229088D01*
X1370070Y228797D01*
X1370445Y228630D01*
X1370862Y228588D01*
X1371404Y228672D01*
X1371695Y228797D01*
X1371987Y229005D01*
X1372195Y229297D01*
X1372237Y229588D01*
X1372154Y229880D01*
X1371945Y230088D01*
G01X1361737Y216147D02*
X1364237D01*
Y217188D01*
X1364112Y217522D01*
X1363945Y217730D01*
X1363612Y217813D01*
X1363279Y217730D01*
X1363070Y217480D01*
X1362945Y217188D01*
Y216147D01*
G01Y217188D02*
X1361737Y217813D01*
G01X1363820Y219288D02*
X1364070Y219538D01*
X1364195Y219830D01*
X1364237Y220163D01*
X1364154Y220580D01*
X1363945Y220872D01*
X1363695Y220955D01*
X1363445Y220913D01*
X1363237Y220747D01*
X1362820Y219913D01*
X1362529Y219538D01*
X1362112Y219288D01*
X1361737Y219205D01*
Y220955D01*
G01X1364237Y222263D02*
X1362445D01*
X1362070Y222430D01*
X1361820Y222763D01*
X1361737Y223180D01*
X1361820Y223597D01*
X1362070Y223930D01*
X1362445Y224097D01*
X1364237D01*
G01X1363820Y225488D02*
X1364070Y225738D01*
X1364195Y226030D01*
X1364237Y226363D01*
X1364154Y226780D01*
X1363945Y227072D01*
X1363695Y227155D01*
X1363445Y227113D01*
X1363237Y226947D01*
X1362820Y226113D01*
X1362529Y225738D01*
X1362112Y225488D01*
X1361737Y225405D01*
Y227155D01*
G01Y229880D02*
X1364237D01*
X1362445Y228338D01*
Y230422D01*
G01X1365737Y216147D02*
X1368237D01*
Y217188D01*
X1368112Y217522D01*
X1367945Y217730D01*
X1367612Y217813D01*
X1367279Y217730D01*
X1367070Y217480D01*
X1366945Y217188D01*
Y216147D01*
G01Y217188D02*
X1365737Y217813D01*
G01X1367820Y219288D02*
X1368070Y219538D01*
X1368195Y219830D01*
X1368237Y220163D01*
X1368154Y220580D01*
X1367945Y220872D01*
X1367695Y220955D01*
X1367445Y220913D01*
X1367237Y220747D01*
X1366820Y219913D01*
X1366529Y219538D01*
X1366112Y219288D01*
X1365737Y219205D01*
Y220955D01*
G01X1368237Y222263D02*
X1366445D01*
X1366070Y222430D01*
X1365820Y222763D01*
X1365737Y223180D01*
X1365820Y223597D01*
X1366070Y223930D01*
X1366445Y224097D01*
X1368237D01*
G01X1367820Y225488D02*
X1368070Y225738D01*
X1368195Y226030D01*
X1368237Y226363D01*
X1368154Y226780D01*
X1367945Y227072D01*
X1367695Y227155D01*
X1367445Y227113D01*
X1367237Y226947D01*
X1366820Y226113D01*
X1366529Y225738D01*
X1366112Y225488D01*
X1365737Y225405D01*
Y227155D01*
G01X1366112Y228463D02*
X1365904Y228713D01*
X1365779Y229005D01*
X1365737Y229380D01*
X1365820Y229755D01*
X1365987Y230047D01*
X1366279Y230255D01*
X1366612Y230297D01*
X1366945Y230213D01*
X1367154Y230005D01*
X1367320Y229713D01*
X1367362Y229422D01*
X1367320Y229130D01*
X1367154Y228755D01*
X1368237Y228880D01*
Y230005D01*
G01X1357737Y216147D02*
X1360237D01*
Y217188D01*
X1360112Y217522D01*
X1359945Y217730D01*
X1359612Y217813D01*
X1359279Y217730D01*
X1359070Y217480D01*
X1358945Y217188D01*
Y216147D01*
G01Y217188D02*
X1357737Y217813D01*
G01X1359820Y219288D02*
X1360070Y219538D01*
X1360195Y219830D01*
X1360237Y220163D01*
X1360154Y220580D01*
X1359945Y220872D01*
X1359695Y220955D01*
X1359445Y220913D01*
X1359237Y220747D01*
X1358820Y219913D01*
X1358529Y219538D01*
X1358112Y219288D01*
X1357737Y219205D01*
Y220955D01*
G01X1360237Y222263D02*
X1358445D01*
X1358070Y222430D01*
X1357820Y222763D01*
X1357737Y223180D01*
X1357820Y223597D01*
X1358070Y223930D01*
X1358445Y224097D01*
X1360237D01*
G01X1359820Y225488D02*
X1360070Y225738D01*
X1360195Y226030D01*
X1360237Y226363D01*
X1360154Y226780D01*
X1359945Y227072D01*
X1359695Y227155D01*
X1359445Y227113D01*
X1359237Y226947D01*
X1358820Y226113D01*
X1358529Y225738D01*
X1358112Y225488D01*
X1357737Y225405D01*
Y227155D01*
G01X1358237Y228463D02*
X1357945Y228713D01*
X1357779Y229047D01*
X1357737Y229422D01*
X1357779Y229755D01*
X1357987Y230088D01*
X1358237Y230297D01*
X1358487Y230338D01*
X1358779Y230255D01*
X1358987Y229963D01*
X1359070Y229672D01*
Y229297D01*
G01Y229672D02*
X1359195Y229922D01*
X1359404Y230130D01*
X1359654Y230213D01*
X1359904Y230130D01*
X1360112Y229922D01*
X1360237Y229547D01*
X1360195Y229172D01*
X1360029Y228797D01*
G01X1353737Y216147D02*
X1356237D01*
Y217188D01*
X1356112Y217522D01*
X1355945Y217730D01*
X1355612Y217813D01*
X1355279Y217730D01*
X1355070Y217480D01*
X1354945Y217188D01*
Y216147D01*
G01Y217188D02*
X1353737Y217813D01*
G01X1355820Y219288D02*
X1356070Y219538D01*
X1356195Y219830D01*
X1356237Y220163D01*
X1356154Y220580D01*
X1355945Y220872D01*
X1355695Y220955D01*
X1355445Y220913D01*
X1355237Y220747D01*
X1354820Y219913D01*
X1354529Y219538D01*
X1354112Y219288D01*
X1353737Y219205D01*
Y220955D01*
G01X1356237Y222263D02*
X1354445D01*
X1354070Y222430D01*
X1353820Y222763D01*
X1353737Y223180D01*
X1353820Y223597D01*
X1354070Y223930D01*
X1354445Y224097D01*
X1356237D01*
G01X1355820Y225488D02*
X1356070Y225738D01*
X1356195Y226030D01*
X1356237Y226363D01*
X1356154Y226780D01*
X1355945Y227072D01*
X1355695Y227155D01*
X1355445Y227113D01*
X1355237Y226947D01*
X1354820Y226113D01*
X1354529Y225738D01*
X1354112Y225488D01*
X1353737Y225405D01*
Y227155D01*
G01X1355820Y228588D02*
X1356070Y228838D01*
X1356195Y229130D01*
X1356237Y229463D01*
X1356154Y229880D01*
X1355945Y230172D01*
X1355695Y230255D01*
X1355445Y230213D01*
X1355237Y230047D01*
X1354820Y229213D01*
X1354529Y228838D01*
X1354112Y228588D01*
X1353737Y228505D01*
Y230255D01*
G01X1377737Y216147D02*
X1380237D01*
Y217188D01*
X1380112Y217522D01*
X1379945Y217730D01*
X1379612Y217813D01*
X1379279Y217730D01*
X1379070Y217480D01*
X1378945Y217188D01*
Y216147D01*
G01Y217188D02*
X1377737Y217813D01*
G01X1379820Y219288D02*
X1380070Y219538D01*
X1380195Y219830D01*
X1380237Y220163D01*
X1380154Y220580D01*
X1379945Y220872D01*
X1379695Y220955D01*
X1379445Y220913D01*
X1379237Y220747D01*
X1378820Y219913D01*
X1378529Y219538D01*
X1378112Y219288D01*
X1377737Y219205D01*
Y220955D01*
G01X1380237Y222263D02*
X1378445D01*
X1378070Y222430D01*
X1377820Y222763D01*
X1377737Y223180D01*
X1377820Y223597D01*
X1378070Y223930D01*
X1378445Y224097D01*
X1380237D01*
G01X1379820Y225488D02*
X1380070Y225738D01*
X1380195Y226030D01*
X1380237Y226363D01*
X1380154Y226780D01*
X1379945Y227072D01*
X1379695Y227155D01*
X1379445Y227113D01*
X1379237Y226947D01*
X1378820Y226113D01*
X1378529Y225738D01*
X1378112Y225488D01*
X1377737Y225405D01*
Y227155D01*
G01Y229380D02*
X1377779Y229672D01*
X1377904Y230005D01*
X1378112Y230213D01*
X1378404Y230297D01*
X1378695Y230213D01*
X1378945Y229963D01*
X1379070Y229588D01*
Y229172D01*
X1379154Y228922D01*
X1379362Y228713D01*
X1379654Y228630D01*
X1379945Y228755D01*
X1380154Y229047D01*
X1380237Y229380D01*
X1380154Y229713D01*
X1379945Y230005D01*
X1379654Y230130D01*
X1379362Y230047D01*
X1379154Y229838D01*
X1379070Y229588D01*
Y229172D01*
X1378945Y228797D01*
X1378695Y228547D01*
X1378404Y228463D01*
X1378112Y228547D01*
X1377904Y228755D01*
X1377779Y229088D01*
X1377737Y229380D01*
G01X1349737Y216147D02*
X1352237D01*
Y217188D01*
X1352112Y217522D01*
X1351945Y217730D01*
X1351612Y217813D01*
X1351279Y217730D01*
X1351070Y217480D01*
X1350945Y217188D01*
Y216147D01*
G01Y217188D02*
X1349737Y217813D01*
G01X1351820Y219288D02*
X1352070Y219538D01*
X1352195Y219830D01*
X1352237Y220163D01*
X1352154Y220580D01*
X1351945Y220872D01*
X1351695Y220955D01*
X1351445Y220913D01*
X1351237Y220747D01*
X1350820Y219913D01*
X1350529Y219538D01*
X1350112Y219288D01*
X1349737Y219205D01*
Y220955D01*
G01X1352237Y222263D02*
X1350445D01*
X1350070Y222430D01*
X1349820Y222763D01*
X1349737Y223180D01*
X1349820Y223597D01*
X1350070Y223930D01*
X1350445Y224097D01*
X1352237D01*
G01X1351820Y225488D02*
X1352070Y225738D01*
X1352195Y226030D01*
X1352237Y226363D01*
X1352154Y226780D01*
X1351945Y227072D01*
X1351695Y227155D01*
X1351445Y227113D01*
X1351237Y226947D01*
X1350820Y226113D01*
X1350529Y225738D01*
X1350112Y225488D01*
X1349737Y225405D01*
Y227155D01*
G01Y229380D02*
X1352237D01*
X1351737Y228880D01*
G01X1349737D02*
Y229880D01*
G01X1345737Y216147D02*
X1348237D01*
Y217188D01*
X1348112Y217522D01*
X1347945Y217730D01*
X1347612Y217813D01*
X1347279Y217730D01*
X1347070Y217480D01*
X1346945Y217188D01*
Y216147D01*
G01Y217188D02*
X1345737Y217813D01*
G01X1347820Y219288D02*
X1348070Y219538D01*
X1348195Y219830D01*
X1348237Y220163D01*
X1348154Y220580D01*
X1347945Y220872D01*
X1347695Y220955D01*
X1347445Y220913D01*
X1347237Y220747D01*
X1346820Y219913D01*
X1346529Y219538D01*
X1346112Y219288D01*
X1345737Y219205D01*
Y220955D01*
G01X1348237Y222263D02*
X1346445D01*
X1346070Y222430D01*
X1345820Y222763D01*
X1345737Y223180D01*
X1345820Y223597D01*
X1346070Y223930D01*
X1346445Y224097D01*
X1348237D01*
G01X1347820Y225488D02*
X1348070Y225738D01*
X1348195Y226030D01*
X1348237Y226363D01*
X1348154Y226780D01*
X1347945Y227072D01*
X1347695Y227155D01*
X1347445Y227113D01*
X1347237Y226947D01*
X1346820Y226113D01*
X1346529Y225738D01*
X1346112Y225488D01*
X1345737Y225405D01*
Y227155D01*
G01X1348237Y229380D02*
X1348154Y229047D01*
X1347945Y228797D01*
X1347695Y228630D01*
X1347362Y228505D01*
X1346987Y228463D01*
X1346612Y228505D01*
X1346279Y228630D01*
X1346029Y228797D01*
X1345820Y229047D01*
X1345737Y229380D01*
X1345820Y229713D01*
X1346029Y229963D01*
X1346279Y230130D01*
X1346612Y230255D01*
X1346987Y230297D01*
X1347362Y230255D01*
X1347695Y230130D01*
X1347945Y229963D01*
X1348154Y229713D01*
X1348237Y229380D01*
G01X1373737Y216147D02*
X1376237D01*
Y217188D01*
X1376112Y217522D01*
X1375945Y217730D01*
X1375612Y217813D01*
X1375279Y217730D01*
X1375070Y217480D01*
X1374945Y217188D01*
Y216147D01*
G01Y217188D02*
X1373737Y217813D01*
G01X1375820Y219288D02*
X1376070Y219538D01*
X1376195Y219830D01*
X1376237Y220163D01*
X1376154Y220580D01*
X1375945Y220872D01*
X1375695Y220955D01*
X1375445Y220913D01*
X1375237Y220747D01*
X1374820Y219913D01*
X1374529Y219538D01*
X1374112Y219288D01*
X1373737Y219205D01*
Y220955D01*
G01X1376237Y222263D02*
X1374445D01*
X1374070Y222430D01*
X1373820Y222763D01*
X1373737Y223180D01*
X1373820Y223597D01*
X1374070Y223930D01*
X1374445Y224097D01*
X1376237D01*
G01X1375820Y225488D02*
X1376070Y225738D01*
X1376195Y226030D01*
X1376237Y226363D01*
X1376154Y226780D01*
X1375945Y227072D01*
X1375695Y227155D01*
X1375445Y227113D01*
X1375237Y226947D01*
X1374820Y226113D01*
X1374529Y225738D01*
X1374112Y225488D01*
X1373737Y225405D01*
Y227155D01*
G01Y229297D02*
X1374279Y229380D01*
X1374737Y229505D01*
X1375154Y229672D01*
X1375612Y229880D01*
X1376237Y230213D01*
Y228547D01*
G01X1367033Y197158D02*
X1367283Y197283D01*
X1367575Y197366D01*
X1367908D01*
X1368283Y197241D01*
X1368575Y197033D01*
X1368783Y196783D01*
X1368950Y196366D01*
X1368992Y195991D01*
X1368908Y195616D01*
X1368783Y195366D01*
X1368533Y195116D01*
X1368242Y194949D01*
X1367950Y194866D01*
X1367658D01*
X1367367Y194949D01*
X1367117Y195074D01*
X1366908Y195241D01*
G01X1364350Y194866D02*
Y197366D01*
X1365892Y195574D01*
X1363808D01*
G01X1362583Y194866D02*
Y197366D01*
X1361542D01*
X1361208Y197241D01*
X1361000Y197074D01*
X1360917Y196741D01*
X1361000Y196408D01*
X1361250Y196199D01*
X1361542Y196074D01*
X1362583D01*
G01X1361542D02*
X1360917Y194866D01*
G01X1358650D02*
Y197366D01*
X1359150Y196866D01*
G01Y194866D02*
X1358150D01*
G01X1343336Y190000D02*
Y193791D01*
X1356132D01*
Y190000D01*
G01X1343336Y177400D02*
Y173838D01*
X1356132D01*
Y177400D01*
G01X1378700Y174700D02*
Y177398D01*
G01Y192700D02*
Y190005D01*
G01Y192700D02*
X1356128D01*
G01X1378700Y174700D02*
X1356125D01*
G01X1394500Y256000D02*
X1396000D01*
Y243500D01*
X1399000D01*
Y239000D01*
G01X1454700Y269000D02*
X1440300D01*
Y280000D01*
X1426000D01*
Y276000D01*
X1388000D01*
Y256300D01*
X1389100D01*
G01X1402000Y236007D02*
X1423644D01*
Y243431D01*
X1448796D01*
Y244797D01*
X1456750D01*
G01X1402200Y257246D02*
X1404700D01*
Y258287D01*
X1404575Y258621D01*
X1404408Y258829D01*
X1404075Y258912D01*
X1403742Y258829D01*
X1403533Y258579D01*
X1403408Y258287D01*
Y257246D01*
G01Y258287D02*
X1402200Y258912D01*
G01Y261679D02*
X1404700D01*
X1402908Y260137D01*
Y262221D01*
G01X1404700Y263029D02*
X1402200Y263612D01*
X1404700Y264279D01*
X1402200Y264946D01*
X1404700Y265529D01*
G01X1402200Y267379D02*
X1404700D01*
X1404200Y266879D01*
G01X1402200D02*
Y267879D01*
G01X1404550Y236967D02*
X1407050D01*
Y238008D01*
X1406925Y238342D01*
X1406758Y238550D01*
X1406425Y238633D01*
X1406092Y238550D01*
X1405883Y238300D01*
X1405758Y238008D01*
Y236967D01*
G01Y238008D02*
X1404550Y238633D01*
G01X1405050Y239983D02*
X1404758Y240233D01*
X1404592Y240567D01*
X1404550Y240942D01*
X1404592Y241275D01*
X1404800Y241608D01*
X1405050Y241817D01*
X1405300Y241858D01*
X1405592Y241775D01*
X1405800Y241483D01*
X1405883Y241192D01*
Y240817D01*
G01Y241192D02*
X1406008Y241442D01*
X1406217Y241650D01*
X1406467Y241733D01*
X1406717Y241650D01*
X1406925Y241442D01*
X1407050Y241067D01*
X1407008Y240692D01*
X1406842Y240317D01*
G01X1404550Y243167D02*
X1407050D01*
Y244208D01*
X1406925Y244542D01*
X1406758Y244750D01*
X1406425Y244833D01*
X1406092Y244750D01*
X1405883Y244500D01*
X1405758Y244208D01*
Y243167D01*
G01Y244208D02*
X1404550Y244833D01*
G01X1405050Y246183D02*
X1404758Y246433D01*
X1404592Y246767D01*
X1404550Y247142D01*
X1404592Y247475D01*
X1404800Y247808D01*
X1405050Y248017D01*
X1405300Y248058D01*
X1405592Y247975D01*
X1405800Y247683D01*
X1405883Y247392D01*
Y247017D01*
G01Y247392D02*
X1406008Y247642D01*
X1406217Y247850D01*
X1406467Y247933D01*
X1406717Y247850D01*
X1406925Y247642D01*
X1407050Y247267D01*
X1407008Y246892D01*
X1406842Y246517D01*
G01X1382533Y279500D02*
Y282000D01*
X1381492D01*
X1381158Y281875D01*
X1380950Y281708D01*
X1380867Y281375D01*
X1380950Y281042D01*
X1381200Y280833D01*
X1381492Y280708D01*
X1382533D01*
G01X1381492D02*
X1380867Y279500D01*
G01X1378683D02*
X1378600Y280042D01*
X1378475Y280500D01*
X1378308Y280917D01*
X1378100Y281375D01*
X1377767Y282000D01*
X1379433D01*
G01X1376417Y279500D02*
Y282000D01*
X1375583D01*
X1375250Y281875D01*
X1375000Y281708D01*
X1374792Y281458D01*
X1374625Y281167D01*
X1374583Y280750D01*
X1374625Y280333D01*
X1374792Y280042D01*
X1375000Y279792D01*
X1375250Y279625D01*
X1375583Y279500D01*
X1376417D01*
G01X1373317Y280000D02*
X1373067Y279708D01*
X1372733Y279542D01*
X1372358Y279500D01*
X1372025Y279542D01*
X1371692Y279750D01*
X1371483Y280000D01*
X1371442Y280250D01*
X1371525Y280542D01*
X1371817Y280750D01*
X1372108Y280833D01*
X1372483D01*
G01X1372108D02*
X1371858Y280958D01*
X1371650Y281167D01*
X1371567Y281417D01*
X1371650Y281667D01*
X1371858Y281875D01*
X1372233Y282000D01*
X1372608Y281958D01*
X1372983Y281792D01*
G01X1370008Y279792D02*
X1369717Y279583D01*
X1369383Y279500D01*
X1369050Y279583D01*
X1368758Y279833D01*
X1368550Y280208D01*
X1368467Y280583D01*
Y281042D01*
X1368550Y281417D01*
X1368758Y281750D01*
X1369008Y281917D01*
X1369300Y282000D01*
X1369633Y281917D01*
X1369883Y281750D01*
X1370050Y281500D01*
X1370133Y281167D01*
X1370050Y280875D01*
X1369842Y280583D01*
X1369592Y280417D01*
X1369300Y280375D01*
X1368967Y280458D01*
X1368717Y280667D01*
X1368467Y281042D01*
G01X1389700Y260767D02*
X1392200D01*
Y261808D01*
X1392075Y262142D01*
X1391908Y262350D01*
X1391575Y262433D01*
X1391242Y262350D01*
X1391033Y262100D01*
X1390908Y261808D01*
Y260767D01*
G01Y261808D02*
X1389700Y262433D01*
G01Y264700D02*
X1392200D01*
X1391700Y264200D01*
G01X1389700D02*
Y265200D01*
G01X1392200Y266550D02*
X1389700Y267133D01*
X1392200Y267800D01*
X1389700Y268467D01*
X1392200Y269050D01*
G01X1391783Y270108D02*
X1392033Y270358D01*
X1392158Y270650D01*
X1392200Y270983D01*
X1392117Y271400D01*
X1391908Y271692D01*
X1391658Y271775D01*
X1391408Y271733D01*
X1391200Y271567D01*
X1390783Y270733D01*
X1390492Y270358D01*
X1390075Y270108D01*
X1389700Y270025D01*
Y271775D01*
G01Y274000D02*
X1389742Y274292D01*
X1389867Y274625D01*
X1390075Y274833D01*
X1390367Y274917D01*
X1390658Y274833D01*
X1390908Y274583D01*
X1391033Y274208D01*
Y273792D01*
X1391117Y273542D01*
X1391325Y273333D01*
X1391617Y273250D01*
X1391908Y273375D01*
X1392117Y273667D01*
X1392200Y274000D01*
X1392117Y274333D01*
X1391908Y274625D01*
X1391617Y274750D01*
X1391325Y274667D01*
X1391117Y274458D01*
X1391033Y274208D01*
Y273792D01*
X1390908Y273417D01*
X1390658Y273167D01*
X1390367Y273083D01*
X1390075Y273167D01*
X1389867Y273375D01*
X1389742Y273708D01*
X1389700Y274000D01*
G01X1398200Y257146D02*
X1400700D01*
Y258187D01*
X1400575Y258521D01*
X1400408Y258729D01*
X1400075Y258812D01*
X1399742Y258729D01*
X1399533Y258479D01*
X1399408Y258187D01*
Y257146D01*
G01Y258187D02*
X1398200Y258812D01*
G01X1398700Y260162D02*
X1398408Y260412D01*
X1398242Y260746D01*
X1398200Y261121D01*
X1398242Y261454D01*
X1398450Y261787D01*
X1398700Y261996D01*
X1398950Y262037D01*
X1399242Y261954D01*
X1399450Y261662D01*
X1399533Y261371D01*
Y260996D01*
G01Y261371D02*
X1399658Y261621D01*
X1399867Y261829D01*
X1400117Y261912D01*
X1400367Y261829D01*
X1400575Y261621D01*
X1400700Y261246D01*
X1400658Y260871D01*
X1400492Y260496D01*
G01X1398200Y263346D02*
X1400700D01*
Y264387D01*
X1400575Y264721D01*
X1400408Y264929D01*
X1400075Y265012D01*
X1399742Y264929D01*
X1399533Y264679D01*
X1399408Y264387D01*
Y263346D01*
G01Y264387D02*
X1398200Y265012D01*
G01Y267279D02*
X1400700D01*
X1400200Y266779D01*
G01X1398200D02*
Y267779D01*
G01X1398575Y269462D02*
X1398367Y269712D01*
X1398242Y270004D01*
X1398200Y270379D01*
X1398283Y270754D01*
X1398450Y271046D01*
X1398742Y271254D01*
X1399075Y271296D01*
X1399408Y271212D01*
X1399617Y271004D01*
X1399783Y270712D01*
X1399825Y270421D01*
X1399783Y270129D01*
X1399617Y269754D01*
X1400700Y269879D01*
Y271004D01*
G01X1394150Y257217D02*
X1396650D01*
Y258258D01*
X1396525Y258592D01*
X1396358Y258800D01*
X1396025Y258883D01*
X1395692Y258800D01*
X1395483Y258550D01*
X1395358Y258258D01*
Y257217D01*
G01Y258258D02*
X1394150Y258883D01*
G01X1394650Y260233D02*
X1394358Y260483D01*
X1394192Y260817D01*
X1394150Y261192D01*
X1394192Y261525D01*
X1394400Y261858D01*
X1394650Y262067D01*
X1394900Y262108D01*
X1395192Y262025D01*
X1395400Y261733D01*
X1395483Y261442D01*
Y261067D01*
G01Y261442D02*
X1395608Y261692D01*
X1395817Y261900D01*
X1396067Y261983D01*
X1396317Y261900D01*
X1396525Y261692D01*
X1396650Y261317D01*
X1396608Y260942D01*
X1396442Y260567D01*
G01X1394150Y263417D02*
X1396650D01*
Y264458D01*
X1396525Y264792D01*
X1396358Y265000D01*
X1396025Y265083D01*
X1395692Y265000D01*
X1395483Y264750D01*
X1395358Y264458D01*
Y263417D01*
G01Y264458D02*
X1394150Y265083D01*
G01Y267350D02*
X1396650D01*
X1396150Y266850D01*
G01X1394150D02*
Y267850D01*
G01Y270450D02*
X1396650D01*
X1396150Y269950D01*
G01X1394150D02*
Y270950D01*
G01X1392859Y243917D02*
X1392984Y243667D01*
X1393067Y243375D01*
Y243042D01*
X1392942Y242667D01*
X1392734Y242375D01*
X1392484Y242167D01*
X1392067Y242000D01*
X1391692Y241958D01*
X1391317Y242042D01*
X1391067Y242167D01*
X1390817Y242417D01*
X1390650Y242708D01*
X1390567Y243000D01*
Y243292D01*
X1390650Y243583D01*
X1390775Y243833D01*
X1390942Y244042D01*
G01X1392650Y245308D02*
X1392900Y245558D01*
X1393025Y245850D01*
X1393067Y246183D01*
X1392984Y246600D01*
X1392775Y246892D01*
X1392525Y246975D01*
X1392275Y246933D01*
X1392067Y246767D01*
X1391650Y245933D01*
X1391359Y245558D01*
X1390942Y245308D01*
X1390567Y245225D01*
Y246975D01*
G01X1393067Y248283D02*
X1391275D01*
X1390900Y248450D01*
X1390650Y248783D01*
X1390567Y249200D01*
X1390650Y249617D01*
X1390900Y249950D01*
X1391275Y250117D01*
X1393067D01*
G01X1390567Y252300D02*
X1393067D01*
X1392567Y251800D01*
G01X1390567D02*
Y252800D01*
G01Y255400D02*
X1390609Y255692D01*
X1390734Y256025D01*
X1390942Y256233D01*
X1391234Y256317D01*
X1391525Y256233D01*
X1391775Y255983D01*
X1391900Y255608D01*
Y255192D01*
X1391984Y254942D01*
X1392192Y254733D01*
X1392484Y254650D01*
X1392775Y254775D01*
X1392984Y255067D01*
X1393067Y255400D01*
X1392984Y255733D01*
X1392775Y256025D01*
X1392484Y256150D01*
X1392192Y256067D01*
X1391984Y255858D01*
X1391900Y255608D01*
Y255192D01*
X1391775Y254817D01*
X1391525Y254567D01*
X1391234Y254483D01*
X1390942Y254567D01*
X1390734Y254775D01*
X1390609Y255108D01*
X1390567Y255400D01*
G01X1403292Y240717D02*
X1403417Y240467D01*
X1403500Y240175D01*
Y239842D01*
X1403375Y239467D01*
X1403167Y239175D01*
X1402917Y238967D01*
X1402500Y238800D01*
X1402125Y238758D01*
X1401750Y238842D01*
X1401500Y238967D01*
X1401250Y239217D01*
X1401083Y239508D01*
X1401000Y239800D01*
Y240092D01*
X1401083Y240383D01*
X1401208Y240633D01*
X1401375Y240842D01*
G01X1401500Y241983D02*
X1401208Y242233D01*
X1401042Y242567D01*
X1401000Y242942D01*
X1401042Y243275D01*
X1401250Y243608D01*
X1401500Y243817D01*
X1401750Y243858D01*
X1402042Y243775D01*
X1402250Y243483D01*
X1402333Y243192D01*
Y242817D01*
G01Y243192D02*
X1402458Y243442D01*
X1402667Y243650D01*
X1402917Y243733D01*
X1403167Y243650D01*
X1403375Y243442D01*
X1403500Y243067D01*
X1403458Y242692D01*
X1403292Y242317D01*
G01X1401000Y245167D02*
X1403500D01*
Y246167D01*
X1403375Y246500D01*
X1403083Y246750D01*
X1402750Y246833D01*
X1402417Y246750D01*
X1402167Y246542D01*
X1402042Y246167D01*
Y245167D01*
G01X1401375Y248183D02*
X1401167Y248433D01*
X1401042Y248725D01*
X1401000Y249100D01*
X1401083Y249475D01*
X1401250Y249767D01*
X1401542Y249975D01*
X1401875Y250017D01*
X1402208Y249933D01*
X1402417Y249725D01*
X1402583Y249433D01*
X1402625Y249142D01*
X1402583Y248850D01*
X1402417Y248475D01*
X1403500Y248600D01*
Y249725D01*
G01Y252200D02*
X1403417Y251867D01*
X1403208Y251617D01*
X1402958Y251450D01*
X1402625Y251325D01*
X1402250Y251283D01*
X1401875Y251325D01*
X1401542Y251450D01*
X1401292Y251617D01*
X1401083Y251867D01*
X1401000Y252200D01*
X1401083Y252533D01*
X1401292Y252783D01*
X1401542Y252950D01*
X1401875Y253075D01*
X1402250Y253117D01*
X1402625Y253075D01*
X1402958Y252950D01*
X1403208Y252783D01*
X1403417Y252533D01*
X1403500Y252200D01*
G01X1351889Y245764D02*
X1352014Y245514D01*
X1352097Y245222D01*
Y244889D01*
X1351972Y244514D01*
X1351764Y244222D01*
X1351514Y244014D01*
X1351097Y243847D01*
X1350722Y243805D01*
X1350347Y243889D01*
X1350097Y244014D01*
X1349847Y244264D01*
X1349680Y244555D01*
X1349597Y244847D01*
Y245139D01*
X1349680Y245430D01*
X1349805Y245680D01*
X1349972Y245889D01*
G01X1351680Y247155D02*
X1351930Y247405D01*
X1352055Y247697D01*
X1352097Y248030D01*
X1352014Y248447D01*
X1351805Y248739D01*
X1351555Y248822D01*
X1351305Y248780D01*
X1351097Y248614D01*
X1350680Y247780D01*
X1350389Y247405D01*
X1349972Y247155D01*
X1349597Y247072D01*
Y248822D01*
G01X1352097Y250130D02*
X1350305D01*
X1349930Y250297D01*
X1349680Y250630D01*
X1349597Y251047D01*
X1349680Y251464D01*
X1349930Y251797D01*
X1350305Y251964D01*
X1352097D01*
G01X1349597Y254147D02*
X1352097D01*
X1351597Y253647D01*
G01X1349597D02*
Y254647D01*
G01X1352097Y257247D02*
X1352014Y256914D01*
X1351805Y256664D01*
X1351555Y256497D01*
X1351222Y256372D01*
X1350847Y256330D01*
X1350472Y256372D01*
X1350139Y256497D01*
X1349889Y256664D01*
X1349680Y256914D01*
X1349597Y257247D01*
X1349680Y257580D01*
X1349889Y257830D01*
X1350139Y257997D01*
X1350472Y258122D01*
X1350847Y258164D01*
X1351222Y258122D01*
X1351555Y257997D01*
X1351805Y257830D01*
X1352014Y257580D01*
X1352097Y257247D01*
G01X1384888Y246000D02*
X1385013Y245750D01*
X1385096Y245458D01*
Y245125D01*
X1384971Y244750D01*
X1384763Y244458D01*
X1384513Y244250D01*
X1384096Y244083D01*
X1383721Y244041D01*
X1383346Y244125D01*
X1383096Y244250D01*
X1382846Y244500D01*
X1382679Y244791D01*
X1382596Y245083D01*
Y245375D01*
X1382679Y245666D01*
X1382804Y245916D01*
X1382971Y246125D01*
G01X1384679Y247391D02*
X1384929Y247641D01*
X1385054Y247933D01*
X1385096Y248266D01*
X1385013Y248683D01*
X1384804Y248975D01*
X1384554Y249058D01*
X1384304Y249016D01*
X1384096Y248850D01*
X1383679Y248016D01*
X1383388Y247641D01*
X1382971Y247391D01*
X1382596Y247308D01*
Y249058D01*
G01X1385096Y250366D02*
X1383304D01*
X1382929Y250533D01*
X1382679Y250866D01*
X1382596Y251283D01*
X1382679Y251700D01*
X1382929Y252033D01*
X1383304Y252200D01*
X1385096D01*
G01X1382596Y254383D02*
X1385096D01*
X1384596Y253883D01*
G01X1382596D02*
Y254883D01*
G01Y257400D02*
X1383138Y257483D01*
X1383596Y257608D01*
X1384013Y257775D01*
X1384471Y257983D01*
X1385096Y258316D01*
Y256650D01*
G01X1380759Y246917D02*
X1380884Y246667D01*
X1380967Y246375D01*
Y246042D01*
X1380842Y245667D01*
X1380634Y245375D01*
X1380384Y245167D01*
X1379967Y245000D01*
X1379592Y244958D01*
X1379217Y245042D01*
X1378967Y245167D01*
X1378717Y245417D01*
X1378550Y245708D01*
X1378467Y246000D01*
Y246292D01*
X1378550Y246583D01*
X1378675Y246833D01*
X1378842Y247042D01*
G01X1380550Y248308D02*
X1380800Y248558D01*
X1380925Y248850D01*
X1380967Y249183D01*
X1380884Y249600D01*
X1380675Y249892D01*
X1380425Y249975D01*
X1380175Y249933D01*
X1379967Y249767D01*
X1379550Y248933D01*
X1379259Y248558D01*
X1378842Y248308D01*
X1378467Y248225D01*
Y249975D01*
G01X1380967Y251283D02*
X1379175D01*
X1378800Y251450D01*
X1378550Y251783D01*
X1378467Y252200D01*
X1378550Y252617D01*
X1378800Y252950D01*
X1379175Y253117D01*
X1380967D01*
G01X1378467Y255300D02*
X1380967D01*
X1380467Y254800D01*
G01X1378467D02*
Y255800D01*
G01X1379509Y257608D02*
X1379800Y257900D01*
X1379967Y258150D01*
X1380050Y258483D01*
X1379967Y258775D01*
X1379800Y258983D01*
X1379550Y259150D01*
X1379259Y259192D01*
X1379009Y259150D01*
X1378759Y258983D01*
X1378550Y258733D01*
X1378467Y258442D01*
X1378550Y258108D01*
X1378800Y257817D01*
X1379175Y257650D01*
X1379592Y257608D01*
X1380134Y257692D01*
X1380425Y257817D01*
X1380717Y258025D01*
X1380925Y258317D01*
X1380967Y258608D01*
X1380884Y258900D01*
X1380675Y259108D01*
G01X1376959Y247017D02*
X1377084Y246767D01*
X1377167Y246475D01*
Y246142D01*
X1377042Y245767D01*
X1376834Y245475D01*
X1376584Y245267D01*
X1376167Y245100D01*
X1375792Y245058D01*
X1375417Y245142D01*
X1375167Y245267D01*
X1374917Y245517D01*
X1374750Y245808D01*
X1374667Y246100D01*
Y246392D01*
X1374750Y246683D01*
X1374875Y246933D01*
X1375042Y247142D01*
G01X1376750Y248408D02*
X1377000Y248658D01*
X1377125Y248950D01*
X1377167Y249283D01*
X1377084Y249700D01*
X1376875Y249992D01*
X1376625Y250075D01*
X1376375Y250033D01*
X1376167Y249867D01*
X1375750Y249033D01*
X1375459Y248658D01*
X1375042Y248408D01*
X1374667Y248325D01*
Y250075D01*
G01X1377167Y251383D02*
X1375375D01*
X1375000Y251550D01*
X1374750Y251883D01*
X1374667Y252300D01*
X1374750Y252717D01*
X1375000Y253050D01*
X1375375Y253217D01*
X1377167D01*
G01X1374667Y255400D02*
X1377167D01*
X1376667Y254900D01*
G01X1374667D02*
Y255900D01*
G01X1375042Y257583D02*
X1374834Y257833D01*
X1374709Y258125D01*
X1374667Y258500D01*
X1374750Y258875D01*
X1374917Y259167D01*
X1375209Y259375D01*
X1375542Y259417D01*
X1375875Y259333D01*
X1376084Y259125D01*
X1376250Y258833D01*
X1376292Y258542D01*
X1376250Y258250D01*
X1376084Y257875D01*
X1377167Y258000D01*
Y259125D01*
G01X1366642Y244934D02*
X1366767Y244684D01*
X1366850Y244392D01*
Y244059D01*
X1366725Y243684D01*
X1366517Y243392D01*
X1366267Y243184D01*
X1365850Y243017D01*
X1365475Y242975D01*
X1365100Y243059D01*
X1364850Y243184D01*
X1364600Y243434D01*
X1364433Y243725D01*
X1364350Y244017D01*
Y244309D01*
X1364433Y244600D01*
X1364558Y244850D01*
X1364725Y245059D01*
G01X1366433Y246325D02*
X1366683Y246575D01*
X1366808Y246867D01*
X1366850Y247200D01*
X1366767Y247617D01*
X1366558Y247909D01*
X1366308Y247992D01*
X1366058Y247950D01*
X1365850Y247784D01*
X1365433Y246950D01*
X1365142Y246575D01*
X1364725Y246325D01*
X1364350Y246242D01*
Y247992D01*
G01X1366850Y249300D02*
X1365058D01*
X1364683Y249467D01*
X1364433Y249800D01*
X1364350Y250217D01*
X1364433Y250634D01*
X1364683Y250967D01*
X1365058Y251134D01*
X1366850D01*
G01X1364350Y253317D02*
X1366850D01*
X1366350Y252817D01*
G01X1364350D02*
Y253817D01*
G01X1364850Y255500D02*
X1364558Y255750D01*
X1364392Y256084D01*
X1364350Y256459D01*
X1364392Y256792D01*
X1364600Y257125D01*
X1364850Y257334D01*
X1365100Y257375D01*
X1365392Y257292D01*
X1365600Y257000D01*
X1365683Y256709D01*
Y256334D01*
G01Y256709D02*
X1365808Y256959D01*
X1366017Y257167D01*
X1366267Y257250D01*
X1366517Y257167D01*
X1366725Y256959D01*
X1366850Y256584D01*
X1366808Y256209D01*
X1366642Y255834D01*
G01X1372659Y247317D02*
X1372784Y247067D01*
X1372867Y246775D01*
Y246442D01*
X1372742Y246067D01*
X1372534Y245775D01*
X1372284Y245567D01*
X1371867Y245400D01*
X1371492Y245358D01*
X1371117Y245442D01*
X1370867Y245567D01*
X1370617Y245817D01*
X1370450Y246108D01*
X1370367Y246400D01*
Y246692D01*
X1370450Y246983D01*
X1370575Y247233D01*
X1370742Y247442D01*
G01X1372450Y248708D02*
X1372700Y248958D01*
X1372825Y249250D01*
X1372867Y249583D01*
X1372784Y250000D01*
X1372575Y250292D01*
X1372325Y250375D01*
X1372075Y250333D01*
X1371867Y250167D01*
X1371450Y249333D01*
X1371159Y248958D01*
X1370742Y248708D01*
X1370367Y248625D01*
Y250375D01*
G01X1372867Y251683D02*
X1371075D01*
X1370700Y251850D01*
X1370450Y252183D01*
X1370367Y252600D01*
X1370450Y253017D01*
X1370700Y253350D01*
X1371075Y253517D01*
X1372867D01*
G01X1370367Y255700D02*
X1372867D01*
X1372367Y255200D01*
G01X1370367D02*
Y256200D01*
G01Y259300D02*
X1372867D01*
X1371075Y257758D01*
Y259842D01*
G01X1361427Y245408D02*
X1361552Y245158D01*
X1361635Y244866D01*
Y244533D01*
X1361510Y244158D01*
X1361302Y243866D01*
X1361052Y243658D01*
X1360635Y243491D01*
X1360260Y243449D01*
X1359885Y243533D01*
X1359635Y243658D01*
X1359385Y243908D01*
X1359218Y244199D01*
X1359135Y244491D01*
Y244783D01*
X1359218Y245074D01*
X1359343Y245324D01*
X1359510Y245533D01*
G01X1361218Y246799D02*
X1361468Y247049D01*
X1361593Y247341D01*
X1361635Y247674D01*
X1361552Y248091D01*
X1361343Y248383D01*
X1361093Y248466D01*
X1360843Y248424D01*
X1360635Y248258D01*
X1360218Y247424D01*
X1359927Y247049D01*
X1359510Y246799D01*
X1359135Y246716D01*
Y248466D01*
G01X1361635Y249774D02*
X1359843D01*
X1359468Y249941D01*
X1359218Y250274D01*
X1359135Y250691D01*
X1359218Y251108D01*
X1359468Y251441D01*
X1359843Y251608D01*
X1361635D01*
G01X1359135Y253791D02*
X1361635D01*
X1361135Y253291D01*
G01X1359135D02*
Y254291D01*
G01X1361218Y256099D02*
X1361468Y256349D01*
X1361593Y256641D01*
X1361635Y256974D01*
X1361552Y257391D01*
X1361343Y257683D01*
X1361093Y257766D01*
X1360843Y257724D01*
X1360635Y257558D01*
X1360218Y256724D01*
X1359927Y256349D01*
X1359510Y256099D01*
X1359135Y256016D01*
Y257766D01*
G01X1357559Y246017D02*
X1357684Y245767D01*
X1357767Y245475D01*
Y245142D01*
X1357642Y244767D01*
X1357434Y244475D01*
X1357184Y244267D01*
X1356767Y244100D01*
X1356392Y244058D01*
X1356017Y244142D01*
X1355767Y244267D01*
X1355517Y244517D01*
X1355350Y244808D01*
X1355267Y245100D01*
Y245392D01*
X1355350Y245683D01*
X1355475Y245933D01*
X1355642Y246142D01*
G01X1357350Y247408D02*
X1357600Y247658D01*
X1357725Y247950D01*
X1357767Y248283D01*
X1357684Y248700D01*
X1357475Y248992D01*
X1357225Y249075D01*
X1356975Y249033D01*
X1356767Y248867D01*
X1356350Y248033D01*
X1356059Y247658D01*
X1355642Y247408D01*
X1355267Y247325D01*
Y249075D01*
G01X1357767Y250383D02*
X1355975D01*
X1355600Y250550D01*
X1355350Y250883D01*
X1355267Y251300D01*
X1355350Y251717D01*
X1355600Y252050D01*
X1355975Y252217D01*
X1357767D01*
G01X1355267Y254400D02*
X1357767D01*
X1357267Y253900D01*
G01X1355267D02*
Y254900D01*
G01Y257500D02*
X1357767D01*
X1357267Y257000D01*
G01X1355267D02*
Y258000D01*
G01X1371600Y312400D02*
X1344700D01*
G01X1400076Y322155D02*
Y324655D01*
X1399035D01*
X1398701Y324530D01*
X1398493Y324363D01*
X1398410Y324030D01*
X1398493Y323697D01*
X1398743Y323488D01*
X1399035Y323363D01*
X1400076D01*
G01X1399035D02*
X1398410Y322155D01*
G01X1397060Y322655D02*
X1396810Y322363D01*
X1396476Y322197D01*
X1396101Y322155D01*
X1395768Y322197D01*
X1395435Y322405D01*
X1395226Y322655D01*
X1395185Y322905D01*
X1395268Y323197D01*
X1395560Y323405D01*
X1395851Y323488D01*
X1396226D01*
G01X1395851D02*
X1395601Y323613D01*
X1395393Y323822D01*
X1395310Y324072D01*
X1395393Y324322D01*
X1395601Y324530D01*
X1395976Y324655D01*
X1396351Y324613D01*
X1396726Y324447D01*
G01X1393876Y322155D02*
Y324655D01*
X1392876D01*
X1392543Y324530D01*
X1392293Y324238D01*
X1392210Y323905D01*
X1392293Y323572D01*
X1392501Y323322D01*
X1392876Y323197D01*
X1393876D01*
G01X1390735Y324238D02*
X1390485Y324488D01*
X1390193Y324613D01*
X1389860Y324655D01*
X1389443Y324572D01*
X1389151Y324363D01*
X1389068Y324113D01*
X1389110Y323863D01*
X1389276Y323655D01*
X1390110Y323238D01*
X1390485Y322947D01*
X1390735Y322530D01*
X1390818Y322155D01*
X1389068D01*
G01X1387635Y324238D02*
X1387385Y324488D01*
X1387093Y324613D01*
X1386760Y324655D01*
X1386343Y324572D01*
X1386051Y324363D01*
X1385968Y324113D01*
X1386010Y323863D01*
X1386176Y323655D01*
X1387010Y323238D01*
X1387385Y322947D01*
X1387635Y322530D01*
X1387718Y322155D01*
X1385968D01*
G01X1382825Y286289D02*
Y288789D01*
X1381784D01*
X1381450Y288664D01*
X1381242Y288497D01*
X1381159Y288164D01*
X1381242Y287831D01*
X1381492Y287622D01*
X1381784Y287497D01*
X1382825D01*
G01X1381784D02*
X1381159Y286289D01*
G01X1378975D02*
X1378892Y286831D01*
X1378767Y287289D01*
X1378600Y287706D01*
X1378392Y288164D01*
X1378059Y288789D01*
X1379725D01*
G01X1376709Y286289D02*
Y288789D01*
X1375875D01*
X1375542Y288664D01*
X1375292Y288497D01*
X1375084Y288247D01*
X1374917Y287956D01*
X1374875Y287539D01*
X1374917Y287122D01*
X1375084Y286831D01*
X1375292Y286581D01*
X1375542Y286414D01*
X1375875Y286289D01*
X1376709D01*
G01X1372192D02*
Y288789D01*
X1373734Y286997D01*
X1371650D01*
G01X1369592Y288789D02*
X1369925Y288706D01*
X1370175Y288497D01*
X1370342Y288247D01*
X1370467Y287914D01*
X1370509Y287539D01*
X1370467Y287164D01*
X1370342Y286831D01*
X1370175Y286581D01*
X1369925Y286372D01*
X1369592Y286289D01*
X1369259Y286372D01*
X1369009Y286581D01*
X1368842Y286831D01*
X1368717Y287164D01*
X1368675Y287539D01*
X1368717Y287914D01*
X1368842Y288247D01*
X1369009Y288497D01*
X1369259Y288706D01*
X1369592Y288789D01*
G01X1383325Y293289D02*
Y295789D01*
X1382284D01*
X1381950Y295664D01*
X1381742Y295497D01*
X1381659Y295164D01*
X1381742Y294831D01*
X1381992Y294622D01*
X1382284Y294497D01*
X1383325D01*
G01X1382284D02*
X1381659Y293289D01*
G01X1380309Y293789D02*
X1380059Y293497D01*
X1379725Y293331D01*
X1379350Y293289D01*
X1379017Y293331D01*
X1378684Y293539D01*
X1378475Y293789D01*
X1378434Y294039D01*
X1378517Y294331D01*
X1378809Y294539D01*
X1379100Y294622D01*
X1379475D01*
G01X1379100D02*
X1378850Y294747D01*
X1378642Y294956D01*
X1378559Y295206D01*
X1378642Y295456D01*
X1378850Y295664D01*
X1379225Y295789D01*
X1379600Y295747D01*
X1379975Y295581D01*
G01X1377125Y293289D02*
Y295789D01*
X1376125D01*
X1375792Y295664D01*
X1375542Y295372D01*
X1375459Y295039D01*
X1375542Y294706D01*
X1375750Y294456D01*
X1376125Y294331D01*
X1377125D01*
G01X1374109Y293789D02*
X1373859Y293497D01*
X1373525Y293331D01*
X1373150Y293289D01*
X1372817Y293331D01*
X1372484Y293539D01*
X1372275Y293789D01*
X1372234Y294039D01*
X1372317Y294331D01*
X1372609Y294539D01*
X1372900Y294622D01*
X1373275D01*
G01X1372900D02*
X1372650Y294747D01*
X1372442Y294956D01*
X1372359Y295206D01*
X1372442Y295456D01*
X1372650Y295664D01*
X1373025Y295789D01*
X1373400Y295747D01*
X1373775Y295581D01*
G01X1371009Y293664D02*
X1370759Y293456D01*
X1370467Y293331D01*
X1370092Y293289D01*
X1369717Y293372D01*
X1369425Y293539D01*
X1369217Y293831D01*
X1369175Y294164D01*
X1369259Y294497D01*
X1369467Y294706D01*
X1369759Y294872D01*
X1370050Y294914D01*
X1370342Y294872D01*
X1370717Y294706D01*
X1370592Y295789D01*
X1369467D01*
G01X1383125Y289889D02*
Y292389D01*
X1382084D01*
X1381750Y292264D01*
X1381542Y292097D01*
X1381459Y291764D01*
X1381542Y291431D01*
X1381792Y291222D01*
X1382084Y291097D01*
X1383125D01*
G01X1382084D02*
X1381459Y289889D01*
G01X1379192D02*
X1378900Y289931D01*
X1378567Y290056D01*
X1378359Y290264D01*
X1378275Y290556D01*
X1378359Y290847D01*
X1378609Y291097D01*
X1378984Y291222D01*
X1379400D01*
X1379650Y291306D01*
X1379859Y291514D01*
X1379942Y291806D01*
X1379817Y292097D01*
X1379525Y292306D01*
X1379192Y292389D01*
X1378859Y292306D01*
X1378567Y292097D01*
X1378442Y291806D01*
X1378525Y291514D01*
X1378734Y291306D01*
X1378984Y291222D01*
X1379400D01*
X1379775Y291097D01*
X1380025Y290847D01*
X1380109Y290556D01*
X1380025Y290264D01*
X1379817Y290056D01*
X1379484Y289931D01*
X1379192Y289889D01*
G01X1377009D02*
Y292389D01*
X1376175D01*
X1375842Y292264D01*
X1375592Y292097D01*
X1375384Y291847D01*
X1375217Y291556D01*
X1375175Y291139D01*
X1375217Y290722D01*
X1375384Y290431D01*
X1375592Y290181D01*
X1375842Y290014D01*
X1376175Y289889D01*
X1377009D01*
G01X1372492D02*
Y292389D01*
X1374034Y290597D01*
X1371950D01*
G01X1370809Y290389D02*
X1370559Y290097D01*
X1370225Y289931D01*
X1369850Y289889D01*
X1369517Y289931D01*
X1369184Y290139D01*
X1368975Y290389D01*
X1368934Y290639D01*
X1369017Y290931D01*
X1369309Y291139D01*
X1369600Y291222D01*
X1369975D01*
G01X1369600D02*
X1369350Y291347D01*
X1369142Y291556D01*
X1369059Y291806D01*
X1369142Y292056D01*
X1369350Y292264D01*
X1369725Y292389D01*
X1370100Y292347D01*
X1370475Y292181D01*
G01X1409933Y327892D02*
X1410183Y328017D01*
X1410475Y328100D01*
X1410808D01*
X1411183Y327975D01*
X1411475Y327767D01*
X1411683Y327517D01*
X1411850Y327100D01*
X1411892Y326725D01*
X1411808Y326350D01*
X1411683Y326100D01*
X1411433Y325850D01*
X1411142Y325683D01*
X1410850Y325600D01*
X1410558D01*
X1410267Y325683D01*
X1410017Y325808D01*
X1409808Y325975D01*
G01X1408667Y326100D02*
X1408417Y325808D01*
X1408083Y325642D01*
X1407708Y325600D01*
X1407375Y325642D01*
X1407042Y325850D01*
X1406833Y326100D01*
X1406792Y326350D01*
X1406875Y326642D01*
X1407167Y326850D01*
X1407458Y326933D01*
X1407833D01*
G01X1407458D02*
X1407208Y327058D01*
X1407000Y327267D01*
X1406917Y327517D01*
X1407000Y327767D01*
X1407208Y327975D01*
X1407583Y328100D01*
X1407958Y328058D01*
X1408333Y327892D01*
G01X1405483Y325600D02*
Y328100D01*
X1404483D01*
X1404150Y327975D01*
X1403900Y327683D01*
X1403817Y327350D01*
X1403900Y327017D01*
X1404108Y326767D01*
X1404483Y326642D01*
X1405483D01*
G01X1401550Y325600D02*
Y328100D01*
X1402050Y327600D01*
G01Y325600D02*
X1401050D01*
G01X1375192Y314167D02*
X1375317Y313917D01*
X1375400Y313625D01*
Y313292D01*
X1375275Y312917D01*
X1375067Y312625D01*
X1374817Y312417D01*
X1374400Y312250D01*
X1374025Y312208D01*
X1373650Y312292D01*
X1373400Y312417D01*
X1373150Y312667D01*
X1372983Y312958D01*
X1372900Y313250D01*
Y313542D01*
X1372983Y313833D01*
X1373108Y314083D01*
X1373275Y314292D01*
G01X1373400Y315433D02*
X1373108Y315683D01*
X1372942Y316017D01*
X1372900Y316392D01*
X1372942Y316725D01*
X1373150Y317058D01*
X1373400Y317267D01*
X1373650Y317308D01*
X1373942Y317225D01*
X1374150Y316933D01*
X1374233Y316642D01*
Y316267D01*
G01Y316642D02*
X1374358Y316892D01*
X1374567Y317100D01*
X1374817Y317183D01*
X1375067Y317100D01*
X1375275Y316892D01*
X1375400Y316517D01*
X1375358Y316142D01*
X1375192Y315767D01*
G01X1372900Y318617D02*
X1375400D01*
Y319617D01*
X1375275Y319950D01*
X1374983Y320200D01*
X1374650Y320283D01*
X1374317Y320200D01*
X1374067Y319992D01*
X1373942Y319617D01*
Y318617D01*
G01X1372900Y323050D02*
X1375400D01*
X1373608Y321508D01*
Y323592D01*
G01X1378692Y314267D02*
X1378817Y314017D01*
X1378900Y313725D01*
Y313392D01*
X1378775Y313017D01*
X1378567Y312725D01*
X1378317Y312517D01*
X1377900Y312350D01*
X1377525Y312308D01*
X1377150Y312392D01*
X1376900Y312517D01*
X1376650Y312767D01*
X1376483Y313058D01*
X1376400Y313350D01*
Y313642D01*
X1376483Y313933D01*
X1376608Y314183D01*
X1376775Y314392D01*
G01X1376900Y315533D02*
X1376608Y315783D01*
X1376442Y316117D01*
X1376400Y316492D01*
X1376442Y316825D01*
X1376650Y317158D01*
X1376900Y317367D01*
X1377150Y317408D01*
X1377442Y317325D01*
X1377650Y317033D01*
X1377733Y316742D01*
Y316367D01*
G01Y316742D02*
X1377858Y316992D01*
X1378067Y317200D01*
X1378317Y317283D01*
X1378567Y317200D01*
X1378775Y316992D01*
X1378900Y316617D01*
X1378858Y316242D01*
X1378692Y315867D01*
G01X1376400Y318717D02*
X1378900D01*
Y319717D01*
X1378775Y320050D01*
X1378483Y320300D01*
X1378150Y320383D01*
X1377817Y320300D01*
X1377567Y320092D01*
X1377442Y319717D01*
Y318717D01*
G01X1376775Y321733D02*
X1376567Y321983D01*
X1376442Y322275D01*
X1376400Y322650D01*
X1376483Y323025D01*
X1376650Y323317D01*
X1376942Y323525D01*
X1377275Y323567D01*
X1377608Y323483D01*
X1377817Y323275D01*
X1377983Y322983D01*
X1378025Y322692D01*
X1377983Y322400D01*
X1377817Y322025D01*
X1378900Y322150D01*
Y323275D01*
G01X1397076Y327647D02*
X1397326Y327772D01*
X1397618Y327855D01*
X1397951D01*
X1398326Y327730D01*
X1398618Y327522D01*
X1398826Y327272D01*
X1398993Y326855D01*
X1399035Y326480D01*
X1398951Y326105D01*
X1398826Y325855D01*
X1398576Y325605D01*
X1398285Y325438D01*
X1397993Y325355D01*
X1397701D01*
X1397410Y325438D01*
X1397160Y325563D01*
X1396951Y325730D01*
G01X1395810Y325855D02*
X1395560Y325563D01*
X1395226Y325397D01*
X1394851Y325355D01*
X1394518Y325397D01*
X1394185Y325605D01*
X1393976Y325855D01*
X1393935Y326105D01*
X1394018Y326397D01*
X1394310Y326605D01*
X1394601Y326688D01*
X1394976D01*
G01X1394601D02*
X1394351Y326813D01*
X1394143Y327022D01*
X1394060Y327272D01*
X1394143Y327522D01*
X1394351Y327730D01*
X1394726Y327855D01*
X1395101Y327813D01*
X1395476Y327647D01*
G01X1392626Y325355D02*
Y327855D01*
X1391626D01*
X1391293Y327730D01*
X1391043Y327438D01*
X1390960Y327105D01*
X1391043Y326772D01*
X1391251Y326522D01*
X1391626Y326397D01*
X1392626D01*
G01X1389610Y325855D02*
X1389360Y325563D01*
X1389026Y325397D01*
X1388651Y325355D01*
X1388318Y325397D01*
X1387985Y325605D01*
X1387776Y325855D01*
X1387735Y326105D01*
X1387818Y326397D01*
X1388110Y326605D01*
X1388401Y326688D01*
X1388776D01*
G01X1388401D02*
X1388151Y326813D01*
X1387943Y327022D01*
X1387860Y327272D01*
X1387943Y327522D01*
X1388151Y327730D01*
X1388526Y327855D01*
X1388901Y327813D01*
X1389276Y327647D01*
G01X1398015Y337728D02*
X1398265Y337853D01*
X1398557Y337936D01*
X1398890D01*
X1399265Y337811D01*
X1399557Y337603D01*
X1399765Y337353D01*
X1399932Y336936D01*
X1399974Y336561D01*
X1399890Y336186D01*
X1399765Y335936D01*
X1399515Y335686D01*
X1399224Y335519D01*
X1398932Y335436D01*
X1398640D01*
X1398349Y335519D01*
X1398099Y335644D01*
X1397890Y335811D01*
G01X1396749Y335936D02*
X1396499Y335644D01*
X1396165Y335478D01*
X1395790Y335436D01*
X1395457Y335478D01*
X1395124Y335686D01*
X1394915Y335936D01*
X1394874Y336186D01*
X1394957Y336478D01*
X1395249Y336686D01*
X1395540Y336769D01*
X1395915D01*
G01X1395540D02*
X1395290Y336894D01*
X1395082Y337103D01*
X1394999Y337353D01*
X1395082Y337603D01*
X1395290Y337811D01*
X1395665Y337936D01*
X1396040Y337894D01*
X1396415Y337728D01*
G01X1393565Y335436D02*
Y337936D01*
X1392565D01*
X1392232Y337811D01*
X1391982Y337519D01*
X1391899Y337186D01*
X1391982Y336853D01*
X1392190Y336603D01*
X1392565Y336478D01*
X1393565D01*
G01X1390424Y337519D02*
X1390174Y337769D01*
X1389882Y337894D01*
X1389549Y337936D01*
X1389132Y337853D01*
X1388840Y337644D01*
X1388757Y337394D01*
X1388799Y337144D01*
X1388965Y336936D01*
X1389799Y336519D01*
X1390174Y336228D01*
X1390424Y335811D01*
X1390507Y335436D01*
X1388757D01*
G01X1399233Y333892D02*
X1399483Y334017D01*
X1399775Y334100D01*
X1400108D01*
X1400483Y333975D01*
X1400775Y333767D01*
X1400983Y333517D01*
X1401150Y333100D01*
X1401192Y332725D01*
X1401108Y332350D01*
X1400983Y332100D01*
X1400733Y331850D01*
X1400442Y331683D01*
X1400150Y331600D01*
X1399858D01*
X1399567Y331683D01*
X1399317Y331808D01*
X1399108Y331975D01*
G01X1397967Y332100D02*
X1397717Y331808D01*
X1397383Y331642D01*
X1397008Y331600D01*
X1396675Y331642D01*
X1396342Y331850D01*
X1396133Y332100D01*
X1396092Y332350D01*
X1396175Y332642D01*
X1396467Y332850D01*
X1396758Y332933D01*
X1397133D01*
G01X1396758D02*
X1396508Y333058D01*
X1396300Y333267D01*
X1396217Y333517D01*
X1396300Y333767D01*
X1396508Y333975D01*
X1396883Y334100D01*
X1397258Y334058D01*
X1397633Y333892D01*
G01X1394783Y331600D02*
Y334100D01*
X1393783D01*
X1393450Y333975D01*
X1393200Y333683D01*
X1393117Y333350D01*
X1393200Y333017D01*
X1393408Y332767D01*
X1393783Y332642D01*
X1394783D01*
G01X1390933Y331600D02*
X1390850Y332142D01*
X1390725Y332600D01*
X1390558Y333017D01*
X1390350Y333475D01*
X1390017Y334100D01*
X1391683D01*
G01X1404533Y329525D02*
X1404325Y329858D01*
X1404200Y330233D01*
Y330567D01*
X1404325Y330900D01*
X1404533Y331150D01*
X1404825Y331275D01*
X1405117Y331192D01*
X1405367Y330983D01*
X1405533Y330608D01*
X1405617Y330108D01*
X1405783Y329817D01*
X1406075Y329692D01*
X1406367Y329775D01*
X1406575Y329983D01*
X1406700Y330275D01*
Y330567D01*
X1406617Y330858D01*
X1406408Y331108D01*
G01X1404200Y332625D02*
X1406700D01*
G01Y334375D02*
X1404200D01*
G01X1405450D02*
Y332625D01*
G01X1404700Y335683D02*
X1404408Y335933D01*
X1404242Y336267D01*
X1404200Y336642D01*
X1404242Y336975D01*
X1404450Y337308D01*
X1404700Y337517D01*
X1404950Y337558D01*
X1405242Y337475D01*
X1405450Y337183D01*
X1405533Y336892D01*
Y336517D01*
G01Y336892D02*
X1405658Y337142D01*
X1405867Y337350D01*
X1406117Y337433D01*
X1406367Y337350D01*
X1406575Y337142D01*
X1406700Y336767D01*
X1406658Y336392D01*
X1406492Y336017D01*
G01X1404200Y338867D02*
X1406700D01*
Y339867D01*
X1406575Y340200D01*
X1406283Y340450D01*
X1405950Y340533D01*
X1405617Y340450D01*
X1405367Y340242D01*
X1405242Y339867D01*
Y338867D01*
G01X1406283Y342008D02*
X1406533Y342258D01*
X1406658Y342550D01*
X1406700Y342883D01*
X1406617Y343300D01*
X1406408Y343592D01*
X1406158Y343675D01*
X1405908Y343633D01*
X1405700Y343467D01*
X1405283Y342633D01*
X1404992Y342258D01*
X1404575Y342008D01*
X1404200Y341925D01*
Y343675D01*
G01X1376350Y332250D02*
Y356350D01*
X1352250D01*
Y332250D01*
X1376350D01*
G01X1373330Y334261D02*
X1374339D01*
Y335443D01*
G01X1354261Y335333D02*
Y334261D01*
G01D02*
X1355374D01*
G01X1379871Y366175D02*
X1380121Y366300D01*
X1380413Y366383D01*
X1380746D01*
X1381121Y366258D01*
X1381413Y366050D01*
X1381621Y365800D01*
X1381788Y365383D01*
X1381830Y365008D01*
X1381746Y364633D01*
X1381621Y364383D01*
X1381371Y364133D01*
X1381080Y363966D01*
X1380788Y363883D01*
X1380496D01*
X1380205Y363966D01*
X1379955Y364091D01*
X1379746Y364258D01*
G01X1378605Y364383D02*
X1378355Y364091D01*
X1378021Y363925D01*
X1377646Y363883D01*
X1377313Y363925D01*
X1376980Y364133D01*
X1376771Y364383D01*
X1376730Y364633D01*
X1376813Y364925D01*
X1377105Y365133D01*
X1377396Y365216D01*
X1377771D01*
G01X1377396D02*
X1377146Y365341D01*
X1376938Y365550D01*
X1376855Y365800D01*
X1376938Y366050D01*
X1377146Y366258D01*
X1377521Y366383D01*
X1377896Y366341D01*
X1378271Y366175D01*
G01X1375546Y363883D02*
Y366383D01*
X1373630Y363883D01*
Y366383D01*
G01X1372405Y364383D02*
X1372155Y364091D01*
X1371821Y363925D01*
X1371446Y363883D01*
X1371113Y363925D01*
X1370780Y364133D01*
X1370571Y364383D01*
X1370530Y364633D01*
X1370613Y364925D01*
X1370905Y365133D01*
X1371196Y365216D01*
X1371571D01*
G01X1371196D02*
X1370946Y365341D01*
X1370738Y365550D01*
X1370655Y365800D01*
X1370738Y366050D01*
X1370946Y366258D01*
X1371321Y366383D01*
X1371696Y366341D01*
X1372071Y366175D01*
G01X1369180Y364925D02*
X1368888Y365216D01*
X1368638Y365383D01*
X1368305Y365466D01*
X1368013Y365383D01*
X1367805Y365216D01*
X1367638Y364966D01*
X1367596Y364675D01*
X1367638Y364425D01*
X1367805Y364175D01*
X1368055Y363966D01*
X1368346Y363883D01*
X1368680Y363966D01*
X1368971Y364216D01*
X1369138Y364591D01*
X1369180Y365008D01*
X1369096Y365550D01*
X1368971Y365841D01*
X1368763Y366133D01*
X1368471Y366341D01*
X1368180Y366383D01*
X1367888Y366300D01*
X1367680Y366091D01*
G01X1379780Y369761D02*
X1380030Y369886D01*
X1380322Y369969D01*
X1380655D01*
X1381030Y369844D01*
X1381322Y369636D01*
X1381530Y369386D01*
X1381697Y368969D01*
X1381739Y368594D01*
X1381655Y368219D01*
X1381530Y367969D01*
X1381280Y367719D01*
X1380989Y367552D01*
X1380697Y367469D01*
X1380405D01*
X1380114Y367552D01*
X1379864Y367677D01*
X1379655Y367844D01*
G01X1378514Y367969D02*
X1378264Y367677D01*
X1377930Y367511D01*
X1377555Y367469D01*
X1377222Y367511D01*
X1376889Y367719D01*
X1376680Y367969D01*
X1376639Y368219D01*
X1376722Y368511D01*
X1377014Y368719D01*
X1377305Y368802D01*
X1377680D01*
G01X1377305D02*
X1377055Y368927D01*
X1376847Y369136D01*
X1376764Y369386D01*
X1376847Y369636D01*
X1377055Y369844D01*
X1377430Y369969D01*
X1377805Y369927D01*
X1378180Y369761D01*
G01X1375455Y367469D02*
Y369969D01*
X1373539Y367469D01*
Y369969D01*
G01X1372314Y367969D02*
X1372064Y367677D01*
X1371730Y367511D01*
X1371355Y367469D01*
X1371022Y367511D01*
X1370689Y367719D01*
X1370480Y367969D01*
X1370439Y368219D01*
X1370522Y368511D01*
X1370814Y368719D01*
X1371105Y368802D01*
X1371480D01*
G01X1371105D02*
X1370855Y368927D01*
X1370647Y369136D01*
X1370564Y369386D01*
X1370647Y369636D01*
X1370855Y369844D01*
X1371230Y369969D01*
X1371605Y369927D01*
X1371980Y369761D01*
G01X1369214Y367969D02*
X1368964Y367677D01*
X1368630Y367511D01*
X1368255Y367469D01*
X1367922Y367511D01*
X1367589Y367719D01*
X1367380Y367969D01*
X1367339Y368219D01*
X1367422Y368511D01*
X1367714Y368719D01*
X1368005Y368802D01*
X1368380D01*
G01X1368005D02*
X1367755Y368927D01*
X1367547Y369136D01*
X1367464Y369386D01*
X1367547Y369636D01*
X1367755Y369844D01*
X1368130Y369969D01*
X1368505Y369927D01*
X1368880Y369761D01*
G01X1388183Y383818D02*
X1388433Y383943D01*
X1388725Y384026D01*
X1389058D01*
X1389433Y383901D01*
X1389725Y383693D01*
X1389933Y383443D01*
X1390100Y383026D01*
X1390142Y382651D01*
X1390058Y382276D01*
X1389933Y382026D01*
X1389683Y381776D01*
X1389392Y381609D01*
X1389100Y381526D01*
X1388808D01*
X1388517Y381609D01*
X1388267Y381734D01*
X1388058Y381901D01*
G01X1386917Y382026D02*
X1386667Y381734D01*
X1386333Y381568D01*
X1385958Y381526D01*
X1385625Y381568D01*
X1385292Y381776D01*
X1385083Y382026D01*
X1385042Y382276D01*
X1385125Y382568D01*
X1385417Y382776D01*
X1385708Y382859D01*
X1386083D01*
G01X1385708D02*
X1385458Y382984D01*
X1385250Y383193D01*
X1385167Y383443D01*
X1385250Y383693D01*
X1385458Y383901D01*
X1385833Y384026D01*
X1386208Y383984D01*
X1386583Y383818D01*
G01X1383858Y381526D02*
Y384026D01*
X1381942Y381526D01*
Y384026D01*
G01X1380717Y382026D02*
X1380467Y381734D01*
X1380133Y381568D01*
X1379758Y381526D01*
X1379425Y381568D01*
X1379092Y381776D01*
X1378883Y382026D01*
X1378842Y382276D01*
X1378925Y382568D01*
X1379217Y382776D01*
X1379508Y382859D01*
X1379883D01*
G01X1379508D02*
X1379258Y382984D01*
X1379050Y383193D01*
X1378967Y383443D01*
X1379050Y383693D01*
X1379258Y383901D01*
X1379633Y384026D01*
X1380008Y383984D01*
X1380383Y383818D01*
G01X1376200Y381526D02*
Y384026D01*
X1377742Y382234D01*
X1375658D01*
G01X1409933Y345549D02*
Y348049D01*
X1408892D01*
X1408558Y347924D01*
X1408350Y347757D01*
X1408267Y347424D01*
X1408350Y347091D01*
X1408600Y346882D01*
X1408892Y346757D01*
X1409933D01*
G01X1408892D02*
X1408267Y345549D01*
G01X1406917Y346049D02*
X1406667Y345757D01*
X1406333Y345591D01*
X1405958Y345549D01*
X1405625Y345591D01*
X1405292Y345799D01*
X1405083Y346049D01*
X1405042Y346299D01*
X1405125Y346591D01*
X1405417Y346799D01*
X1405708Y346882D01*
X1406083D01*
G01X1405708D02*
X1405458Y347007D01*
X1405250Y347216D01*
X1405167Y347466D01*
X1405250Y347716D01*
X1405458Y347924D01*
X1405833Y348049D01*
X1406208Y348007D01*
X1406583Y347841D01*
G01X1403733Y345549D02*
Y348049D01*
X1402733D01*
X1402400Y347924D01*
X1402150Y347632D01*
X1402067Y347299D01*
X1402150Y346966D01*
X1402358Y346716D01*
X1402733Y346591D01*
X1403733D01*
G01X1399800Y345549D02*
Y348049D01*
X1400300Y347549D01*
G01Y345549D02*
X1399300D01*
G01X1397492Y346591D02*
X1397200Y346882D01*
X1396950Y347049D01*
X1396617Y347132D01*
X1396325Y347049D01*
X1396117Y346882D01*
X1395950Y346632D01*
X1395908Y346341D01*
X1395950Y346091D01*
X1396117Y345841D01*
X1396367Y345632D01*
X1396658Y345549D01*
X1396992Y345632D01*
X1397283Y345882D01*
X1397450Y346257D01*
X1397492Y346674D01*
X1397408Y347216D01*
X1397283Y347507D01*
X1397075Y347799D01*
X1396783Y348007D01*
X1396492Y348049D01*
X1396200Y347966D01*
X1395992Y347757D01*
G01X1409733Y348899D02*
Y351399D01*
X1408692D01*
X1408358Y351274D01*
X1408150Y351107D01*
X1408067Y350774D01*
X1408150Y350441D01*
X1408400Y350232D01*
X1408692Y350107D01*
X1409733D01*
G01X1408692D02*
X1408067Y348899D01*
G01X1406717Y349399D02*
X1406467Y349107D01*
X1406133Y348941D01*
X1405758Y348899D01*
X1405425Y348941D01*
X1405092Y349149D01*
X1404883Y349399D01*
X1404842Y349649D01*
X1404925Y349941D01*
X1405217Y350149D01*
X1405508Y350232D01*
X1405883D01*
G01X1405508D02*
X1405258Y350357D01*
X1405050Y350566D01*
X1404967Y350816D01*
X1405050Y351066D01*
X1405258Y351274D01*
X1405633Y351399D01*
X1406008Y351357D01*
X1406383Y351191D01*
G01X1403533Y348899D02*
Y351399D01*
X1402533D01*
X1402200Y351274D01*
X1401950Y350982D01*
X1401867Y350649D01*
X1401950Y350316D01*
X1402158Y350066D01*
X1402533Y349941D01*
X1403533D01*
G01X1399600Y348899D02*
Y351399D01*
X1400100Y350899D01*
G01Y348899D02*
X1399100D01*
G01X1397292Y350982D02*
X1397042Y351232D01*
X1396750Y351357D01*
X1396417Y351399D01*
X1396000Y351316D01*
X1395708Y351107D01*
X1395625Y350857D01*
X1395667Y350607D01*
X1395833Y350399D01*
X1396667Y349982D01*
X1397042Y349691D01*
X1397292Y349274D01*
X1397375Y348899D01*
X1395625D01*
G01X1410733Y360136D02*
Y362636D01*
X1409692D01*
X1409358Y362511D01*
X1409150Y362344D01*
X1409067Y362011D01*
X1409150Y361678D01*
X1409400Y361469D01*
X1409692Y361344D01*
X1410733D01*
G01X1409692D02*
X1409067Y360136D01*
G01X1407717Y360636D02*
X1407467Y360344D01*
X1407133Y360178D01*
X1406758Y360136D01*
X1406425Y360178D01*
X1406092Y360386D01*
X1405883Y360636D01*
X1405842Y360886D01*
X1405925Y361178D01*
X1406217Y361386D01*
X1406508Y361469D01*
X1406883D01*
G01X1406508D02*
X1406258Y361594D01*
X1406050Y361803D01*
X1405967Y362053D01*
X1406050Y362303D01*
X1406258Y362511D01*
X1406633Y362636D01*
X1407008Y362594D01*
X1407383Y362428D01*
G01X1404658Y360136D02*
Y362636D01*
X1402742Y360136D01*
Y362636D01*
G01X1401392Y362219D02*
X1401142Y362469D01*
X1400850Y362594D01*
X1400517Y362636D01*
X1400100Y362553D01*
X1399808Y362344D01*
X1399725Y362094D01*
X1399767Y361844D01*
X1399933Y361636D01*
X1400767Y361219D01*
X1401142Y360928D01*
X1401392Y360511D01*
X1401475Y360136D01*
X1399725D01*
G01X1398292Y362219D02*
X1398042Y362469D01*
X1397750Y362594D01*
X1397417Y362636D01*
X1397000Y362553D01*
X1396708Y362344D01*
X1396625Y362094D01*
X1396667Y361844D01*
X1396833Y361636D01*
X1397667Y361219D01*
X1398042Y360928D01*
X1398292Y360511D01*
X1398375Y360136D01*
X1396625D01*
G01X1410833Y363731D02*
Y366231D01*
X1409792D01*
X1409458Y366106D01*
X1409250Y365939D01*
X1409167Y365606D01*
X1409250Y365273D01*
X1409500Y365064D01*
X1409792Y364939D01*
X1410833D01*
G01X1409792D02*
X1409167Y363731D01*
G01X1407817Y364231D02*
X1407567Y363939D01*
X1407233Y363773D01*
X1406858Y363731D01*
X1406525Y363773D01*
X1406192Y363981D01*
X1405983Y364231D01*
X1405942Y364481D01*
X1406025Y364773D01*
X1406317Y364981D01*
X1406608Y365064D01*
X1406983D01*
G01X1406608D02*
X1406358Y365189D01*
X1406150Y365398D01*
X1406067Y365648D01*
X1406150Y365898D01*
X1406358Y366106D01*
X1406733Y366231D01*
X1407108Y366189D01*
X1407483Y366023D01*
G01X1404758Y363731D02*
Y366231D01*
X1402842Y363731D01*
Y366231D01*
G01X1401492Y365814D02*
X1401242Y366064D01*
X1400950Y366189D01*
X1400617Y366231D01*
X1400200Y366148D01*
X1399908Y365939D01*
X1399825Y365689D01*
X1399867Y365439D01*
X1400033Y365231D01*
X1400867Y364814D01*
X1401242Y364523D01*
X1401492Y364106D01*
X1401575Y363731D01*
X1399825D01*
G01X1398517Y364231D02*
X1398267Y363939D01*
X1397933Y363773D01*
X1397558Y363731D01*
X1397225Y363773D01*
X1396892Y363981D01*
X1396683Y364231D01*
X1396642Y364481D01*
X1396725Y364773D01*
X1397017Y364981D01*
X1397308Y365064D01*
X1397683D01*
G01X1397308D02*
X1397058Y365189D01*
X1396850Y365398D01*
X1396767Y365648D01*
X1396850Y365898D01*
X1397058Y366106D01*
X1397433Y366231D01*
X1397808Y366189D01*
X1398183Y366023D01*
G01X1411433Y352947D02*
Y355447D01*
X1410392D01*
X1410058Y355322D01*
X1409850Y355155D01*
X1409767Y354822D01*
X1409850Y354489D01*
X1410100Y354280D01*
X1410392Y354155D01*
X1411433D01*
G01X1410392D02*
X1409767Y352947D01*
G01X1408417Y353447D02*
X1408167Y353155D01*
X1407833Y352989D01*
X1407458Y352947D01*
X1407125Y352989D01*
X1406792Y353197D01*
X1406583Y353447D01*
X1406542Y353697D01*
X1406625Y353989D01*
X1406917Y354197D01*
X1407208Y354280D01*
X1407583D01*
G01X1407208D02*
X1406958Y354405D01*
X1406750Y354614D01*
X1406667Y354864D01*
X1406750Y355114D01*
X1406958Y355322D01*
X1407333Y355447D01*
X1407708Y355405D01*
X1408083Y355239D01*
G01X1405358Y352947D02*
Y355447D01*
X1403442Y352947D01*
Y355447D01*
G01X1402217Y353447D02*
X1401967Y353155D01*
X1401633Y352989D01*
X1401258Y352947D01*
X1400925Y352989D01*
X1400592Y353197D01*
X1400383Y353447D01*
X1400342Y353697D01*
X1400425Y353989D01*
X1400717Y354197D01*
X1401008Y354280D01*
X1401383D01*
G01X1401008D02*
X1400758Y354405D01*
X1400550Y354614D01*
X1400467Y354864D01*
X1400550Y355114D01*
X1400758Y355322D01*
X1401133Y355447D01*
X1401508Y355405D01*
X1401883Y355239D01*
G01X1398200Y352947D02*
Y355447D01*
X1398700Y354947D01*
G01Y352947D02*
X1397700D01*
G01X1390983Y394600D02*
Y397100D01*
X1389942D01*
X1389608Y396975D01*
X1389400Y396808D01*
X1389317Y396475D01*
X1389400Y396142D01*
X1389650Y395933D01*
X1389942Y395808D01*
X1390983D01*
G01X1389942D02*
X1389317Y394600D01*
G01X1387967Y395100D02*
X1387717Y394808D01*
X1387383Y394642D01*
X1387008Y394600D01*
X1386675Y394642D01*
X1386342Y394850D01*
X1386133Y395100D01*
X1386092Y395350D01*
X1386175Y395642D01*
X1386467Y395850D01*
X1386758Y395933D01*
X1387133D01*
G01X1386758D02*
X1386508Y396058D01*
X1386300Y396267D01*
X1386217Y396517D01*
X1386300Y396767D01*
X1386508Y396975D01*
X1386883Y397100D01*
X1387258Y397058D01*
X1387633Y396892D01*
G01X1384908Y394600D02*
Y397100D01*
X1382992Y394600D01*
Y397100D01*
G01X1380933Y394600D02*
X1380850Y395142D01*
X1380725Y395600D01*
X1380558Y396017D01*
X1380350Y396475D01*
X1380017Y397100D01*
X1381683D01*
G01X1410183Y358789D02*
X1410433Y358914D01*
X1410725Y358997D01*
X1411058D01*
X1411433Y358872D01*
X1411725Y358664D01*
X1411933Y358414D01*
X1412100Y357997D01*
X1412142Y357622D01*
X1412058Y357247D01*
X1411933Y356997D01*
X1411683Y356747D01*
X1411392Y356580D01*
X1411100Y356497D01*
X1410808D01*
X1410517Y356580D01*
X1410267Y356705D01*
X1410058Y356872D01*
G01X1407500Y356497D02*
Y358997D01*
X1409042Y357205D01*
X1406958D01*
G01X1406150Y358997D02*
X1405567Y356497D01*
X1404900Y358997D01*
X1404233Y356497D01*
X1403650Y358997D01*
G01X1401800Y356497D02*
Y358997D01*
X1402300Y358497D01*
G01Y356497D02*
X1401300D01*
G01X1352000Y380000D02*
Y377305D01*
G01Y362000D02*
Y364698D01*
G01Y400000D02*
Y397305D01*
G01Y382000D02*
Y384698D01*
G01Y402000D02*
Y404698D01*
G01X1400583Y400892D02*
X1400833Y401017D01*
X1401125Y401100D01*
X1401458D01*
X1401833Y400975D01*
X1402125Y400767D01*
X1402333Y400517D01*
X1402500Y400100D01*
X1402542Y399725D01*
X1402458Y399350D01*
X1402333Y399100D01*
X1402083Y398850D01*
X1401792Y398683D01*
X1401500Y398600D01*
X1401208D01*
X1400917Y398683D01*
X1400667Y398808D01*
X1400458Y398975D01*
G01X1398483Y398600D02*
X1398400Y399142D01*
X1398275Y399600D01*
X1398108Y400017D01*
X1397900Y400475D01*
X1397567Y401100D01*
X1399233D01*
G01X1394383Y400892D02*
X1394633Y401017D01*
X1394925Y401100D01*
X1395258D01*
X1395633Y400975D01*
X1395925Y400767D01*
X1396133Y400517D01*
X1396300Y400100D01*
X1396342Y399725D01*
X1396258Y399350D01*
X1396133Y399100D01*
X1395883Y398850D01*
X1395592Y398683D01*
X1395300Y398600D01*
X1395008D01*
X1394717Y398683D01*
X1394467Y398808D01*
X1394258Y398975D01*
G01X1392992Y400683D02*
X1392742Y400933D01*
X1392450Y401058D01*
X1392117Y401100D01*
X1391700Y401017D01*
X1391408Y400808D01*
X1391325Y400558D01*
X1391367Y400308D01*
X1391533Y400100D01*
X1392367Y399683D01*
X1392742Y399392D01*
X1392992Y398975D01*
X1393075Y398600D01*
X1391325D01*
G01X1389100Y401100D02*
X1389433Y401017D01*
X1389683Y400808D01*
X1389850Y400558D01*
X1389975Y400225D01*
X1390017Y399850D01*
X1389975Y399475D01*
X1389850Y399142D01*
X1389683Y398892D01*
X1389433Y398683D01*
X1389100Y398600D01*
X1388767Y398683D01*
X1388517Y398892D01*
X1388350Y399142D01*
X1388225Y399475D01*
X1388183Y399850D01*
X1388225Y400225D01*
X1388350Y400558D01*
X1388517Y400808D01*
X1388767Y401017D01*
X1389100Y401100D01*
G01X1407033Y386292D02*
X1407283Y386417D01*
X1407575Y386500D01*
X1407908D01*
X1408283Y386375D01*
X1408575Y386167D01*
X1408783Y385917D01*
X1408950Y385500D01*
X1408992Y385125D01*
X1408908Y384750D01*
X1408783Y384500D01*
X1408533Y384250D01*
X1408242Y384083D01*
X1407950Y384000D01*
X1407658D01*
X1407367Y384083D01*
X1407117Y384208D01*
X1406908Y384375D01*
G01X1404933Y384000D02*
X1404850Y384542D01*
X1404725Y385000D01*
X1404558Y385417D01*
X1404350Y385875D01*
X1404017Y386500D01*
X1405683D01*
G01X1400833Y386292D02*
X1401083Y386417D01*
X1401375Y386500D01*
X1401708D01*
X1402083Y386375D01*
X1402375Y386167D01*
X1402583Y385917D01*
X1402750Y385500D01*
X1402792Y385125D01*
X1402708Y384750D01*
X1402583Y384500D01*
X1402333Y384250D01*
X1402042Y384083D01*
X1401750Y384000D01*
X1401458D01*
X1401167Y384083D01*
X1400917Y384208D01*
X1400708Y384375D01*
G01X1398650Y384000D02*
X1398358Y384042D01*
X1398025Y384167D01*
X1397817Y384375D01*
X1397733Y384667D01*
X1397817Y384958D01*
X1398067Y385208D01*
X1398442Y385333D01*
X1398858D01*
X1399108Y385417D01*
X1399317Y385625D01*
X1399400Y385917D01*
X1399275Y386208D01*
X1398983Y386417D01*
X1398650Y386500D01*
X1398317Y386417D01*
X1398025Y386208D01*
X1397900Y385917D01*
X1397983Y385625D01*
X1398192Y385417D01*
X1398442Y385333D01*
X1398858D01*
X1399233Y385208D01*
X1399483Y384958D01*
X1399567Y384667D01*
X1399483Y384375D01*
X1399275Y384167D01*
X1398942Y384042D01*
X1398650Y384000D01*
G01X1375313Y357577D02*
X1376979D01*
Y360077D01*
X1375313D01*
G01X1375979Y358869D02*
X1376979D01*
G01X1373963Y360077D02*
Y358285D01*
X1373796Y357910D01*
X1373463Y357660D01*
X1373046Y357577D01*
X1372629Y357660D01*
X1372296Y357910D01*
X1372129Y358285D01*
Y360077D01*
G01X1370863Y358077D02*
X1370613Y357785D01*
X1370279Y357619D01*
X1369904Y357577D01*
X1369571Y357619D01*
X1369238Y357827D01*
X1369029Y358077D01*
X1368988Y358327D01*
X1369071Y358619D01*
X1369363Y358827D01*
X1369654Y358910D01*
X1370029D01*
G01X1369654D02*
X1369404Y359035D01*
X1369196Y359244D01*
X1369113Y359494D01*
X1369196Y359744D01*
X1369404Y359952D01*
X1369779Y360077D01*
X1370154Y360035D01*
X1370529Y359869D01*
G01X1367679Y357577D02*
Y360077D01*
X1366679D01*
X1366346Y359952D01*
X1366096Y359660D01*
X1366013Y359327D01*
X1366096Y358994D01*
X1366304Y358744D01*
X1366679Y358619D01*
X1367679D01*
G01X1363746Y357577D02*
Y360077D01*
X1364246Y359577D01*
G01Y357577D02*
X1363246D01*
G01X1355507Y354339D02*
X1354261D01*
Y353157D01*
G01X1374339Y353141D02*
Y354339D01*
X1373191D01*
G01X1389124Y464923D02*
Y467423D01*
X1388083D01*
X1387749Y467298D01*
X1387541Y467131D01*
X1387458Y466798D01*
X1387541Y466465D01*
X1387791Y466256D01*
X1388083Y466131D01*
X1389124D01*
G01X1388083D02*
X1387458Y464923D01*
G01X1385274D02*
X1385191Y465465D01*
X1385066Y465923D01*
X1384899Y466340D01*
X1384691Y466798D01*
X1384358Y467423D01*
X1386024D01*
G01X1382174Y464923D02*
X1382091Y465465D01*
X1381966Y465923D01*
X1381799Y466340D01*
X1381591Y466798D01*
X1381258Y467423D01*
X1382924D01*
G01X1379074Y464923D02*
X1378991Y465465D01*
X1378866Y465923D01*
X1378699Y466340D01*
X1378491Y466798D01*
X1378158Y467423D01*
X1379824D01*
G01X1388199Y430865D02*
X1388324Y430615D01*
X1388407Y430323D01*
Y429990D01*
X1388282Y429615D01*
X1388074Y429323D01*
X1387824Y429115D01*
X1387407Y428948D01*
X1387032Y428906D01*
X1386657Y428990D01*
X1386407Y429115D01*
X1386157Y429365D01*
X1385990Y429656D01*
X1385907Y429948D01*
Y430240D01*
X1385990Y430531D01*
X1386115Y430781D01*
X1386282Y430990D01*
G01X1386407Y432131D02*
X1386115Y432381D01*
X1385949Y432715D01*
X1385907Y433090D01*
X1385949Y433423D01*
X1386157Y433756D01*
X1386407Y433965D01*
X1386657Y434006D01*
X1386949Y433923D01*
X1387157Y433631D01*
X1387240Y433340D01*
Y432965D01*
G01Y433340D02*
X1387365Y433590D01*
X1387574Y433798D01*
X1387824Y433881D01*
X1388074Y433798D01*
X1388282Y433590D01*
X1388407Y433215D01*
X1388365Y432840D01*
X1388199Y432465D01*
G01X1385907Y435190D02*
X1388407D01*
X1385907Y437106D01*
X1388407D01*
G01X1385907Y439748D02*
X1388407D01*
X1386615Y438206D01*
Y440290D01*
G01X1388407Y442348D02*
X1388324Y442015D01*
X1388115Y441765D01*
X1387865Y441598D01*
X1387532Y441473D01*
X1387157Y441431D01*
X1386782Y441473D01*
X1386449Y441598D01*
X1386199Y441765D01*
X1385990Y442015D01*
X1385907Y442348D01*
X1385990Y442681D01*
X1386199Y442931D01*
X1386449Y443098D01*
X1386782Y443223D01*
X1387157Y443265D01*
X1387532Y443223D01*
X1387865Y443098D01*
X1388115Y442931D01*
X1388324Y442681D01*
X1388407Y442348D01*
G01X1365583Y420992D02*
X1365833Y421117D01*
X1366125Y421200D01*
X1366458D01*
X1366833Y421075D01*
X1367125Y420867D01*
X1367333Y420617D01*
X1367500Y420200D01*
X1367542Y419825D01*
X1367458Y419450D01*
X1367333Y419200D01*
X1367083Y418950D01*
X1366792Y418783D01*
X1366500Y418700D01*
X1366208D01*
X1365917Y418783D01*
X1365667Y418908D01*
X1365458Y419075D01*
G01X1364317Y419200D02*
X1364067Y418908D01*
X1363733Y418742D01*
X1363358Y418700D01*
X1363025Y418742D01*
X1362692Y418950D01*
X1362483Y419200D01*
X1362442Y419450D01*
X1362525Y419742D01*
X1362817Y419950D01*
X1363108Y420033D01*
X1363483D01*
G01X1363108D02*
X1362858Y420158D01*
X1362650Y420367D01*
X1362567Y420617D01*
X1362650Y420867D01*
X1362858Y421075D01*
X1363233Y421200D01*
X1363608Y421158D01*
X1363983Y420992D01*
G01X1361258Y418700D02*
Y421200D01*
X1359342Y418700D01*
Y421200D01*
G01X1357200Y418700D02*
Y421200D01*
X1357700Y420700D01*
G01Y418700D02*
X1356700D01*
G01X1353600D02*
Y421200D01*
X1355142Y419408D01*
X1353058D01*
G01X1381964Y424700D02*
Y420909D01*
X1369168D01*
Y424700D01*
G01X1381964Y437300D02*
Y440862D01*
X1369168D01*
Y437300D01*
G01X1346600Y440000D02*
Y437302D01*
G01Y422000D02*
Y424695D01*
G01Y422000D02*
X1369172D01*
G01X1346600Y440000D02*
X1369175D01*
G01X1352000Y420000D02*
Y417305D01*
G01X1403627Y406846D02*
X1403752Y406596D01*
X1403835Y406304D01*
Y405971D01*
X1403710Y405596D01*
X1403502Y405304D01*
X1403252Y405096D01*
X1402835Y404929D01*
X1402460Y404887D01*
X1402085Y404971D01*
X1401835Y405096D01*
X1401585Y405346D01*
X1401418Y405637D01*
X1401335Y405929D01*
Y406221D01*
X1401418Y406512D01*
X1401543Y406762D01*
X1401710Y406971D01*
G01X1403418Y408237D02*
X1403668Y408487D01*
X1403793Y408779D01*
X1403835Y409112D01*
X1403752Y409529D01*
X1403543Y409821D01*
X1403293Y409904D01*
X1403043Y409862D01*
X1402835Y409696D01*
X1402418Y408862D01*
X1402127Y408487D01*
X1401710Y408237D01*
X1401335Y408154D01*
Y409904D01*
G01X1403418Y411337D02*
X1403668Y411587D01*
X1403793Y411879D01*
X1403835Y412212D01*
X1403752Y412629D01*
X1403543Y412921D01*
X1403293Y413004D01*
X1403043Y412962D01*
X1402835Y412796D01*
X1402418Y411962D01*
X1402127Y411587D01*
X1401710Y411337D01*
X1401335Y411254D01*
Y413004D01*
G01X1403835Y413979D02*
X1401335Y414562D01*
X1403835Y415229D01*
X1401335Y415896D01*
X1403835Y416479D01*
G01X1401835Y417412D02*
X1401543Y417662D01*
X1401377Y417996D01*
X1401335Y418371D01*
X1401377Y418704D01*
X1401585Y419037D01*
X1401835Y419246D01*
X1402085Y419287D01*
X1402377Y419204D01*
X1402585Y418912D01*
X1402668Y418621D01*
Y418246D01*
G01Y418621D02*
X1402793Y418871D01*
X1403002Y419079D01*
X1403252Y419162D01*
X1403502Y419079D01*
X1403710Y418871D01*
X1403835Y418496D01*
X1403793Y418121D01*
X1403627Y417746D01*
G01X1403418Y420637D02*
X1403668Y420887D01*
X1403793Y421179D01*
X1403835Y421512D01*
X1403752Y421929D01*
X1403543Y422221D01*
X1403293Y422304D01*
X1403043Y422262D01*
X1402835Y422096D01*
X1402418Y421262D01*
X1402127Y420887D01*
X1401710Y420637D01*
X1401335Y420554D01*
Y422304D01*
G01X1399403Y418259D02*
X1399528Y418009D01*
X1399611Y417717D01*
Y417384D01*
X1399486Y417009D01*
X1399278Y416717D01*
X1399028Y416509D01*
X1398611Y416342D01*
X1398236Y416300D01*
X1397861Y416384D01*
X1397611Y416509D01*
X1397361Y416759D01*
X1397194Y417050D01*
X1397111Y417342D01*
Y417634D01*
X1397194Y417925D01*
X1397319Y418175D01*
X1397486Y418384D01*
G01X1399194Y419650D02*
X1399444Y419900D01*
X1399569Y420192D01*
X1399611Y420525D01*
X1399528Y420942D01*
X1399319Y421234D01*
X1399069Y421317D01*
X1398819Y421275D01*
X1398611Y421109D01*
X1398194Y420275D01*
X1397903Y419900D01*
X1397486Y419650D01*
X1397111Y419567D01*
Y421317D01*
G01X1399194Y422750D02*
X1399444Y423000D01*
X1399569Y423292D01*
X1399611Y423625D01*
X1399528Y424042D01*
X1399319Y424334D01*
X1399069Y424417D01*
X1398819Y424375D01*
X1398611Y424209D01*
X1398194Y423375D01*
X1397903Y423000D01*
X1397486Y422750D01*
X1397111Y422667D01*
Y424417D01*
G01X1399611Y425392D02*
X1397111Y425975D01*
X1399611Y426642D01*
X1397111Y427309D01*
X1399611Y427892D01*
G01X1397611Y428825D02*
X1397319Y429075D01*
X1397153Y429409D01*
X1397111Y429784D01*
X1397153Y430117D01*
X1397361Y430450D01*
X1397611Y430659D01*
X1397861Y430700D01*
X1398153Y430617D01*
X1398361Y430325D01*
X1398444Y430034D01*
Y429659D01*
G01Y430034D02*
X1398569Y430284D01*
X1398778Y430492D01*
X1399028Y430575D01*
X1399278Y430492D01*
X1399486Y430284D01*
X1399611Y429909D01*
X1399569Y429534D01*
X1399403Y429159D01*
G01X1399611Y432842D02*
X1399528Y432509D01*
X1399319Y432259D01*
X1399069Y432092D01*
X1398736Y431967D01*
X1398361Y431925D01*
X1397986Y431967D01*
X1397653Y432092D01*
X1397403Y432259D01*
X1397194Y432509D01*
X1397111Y432842D01*
X1397194Y433175D01*
X1397403Y433425D01*
X1397653Y433592D01*
X1397986Y433717D01*
X1398361Y433759D01*
X1398736Y433717D01*
X1399069Y433592D01*
X1399319Y433425D01*
X1399528Y433175D01*
X1399611Y432842D01*
G01X1394216Y419636D02*
X1394341Y419386D01*
X1394424Y419094D01*
Y418761D01*
X1394299Y418386D01*
X1394091Y418094D01*
X1393841Y417886D01*
X1393424Y417719D01*
X1393049Y417677D01*
X1392674Y417761D01*
X1392424Y417886D01*
X1392174Y418136D01*
X1392007Y418427D01*
X1391924Y418719D01*
Y419011D01*
X1392007Y419302D01*
X1392132Y419552D01*
X1392299Y419761D01*
G01X1394007Y421027D02*
X1394257Y421277D01*
X1394382Y421569D01*
X1394424Y421902D01*
X1394341Y422319D01*
X1394132Y422611D01*
X1393882Y422694D01*
X1393632Y422652D01*
X1393424Y422486D01*
X1393007Y421652D01*
X1392716Y421277D01*
X1392299Y421027D01*
X1391924Y420944D01*
Y422694D01*
G01X1394007Y424127D02*
X1394257Y424377D01*
X1394382Y424669D01*
X1394424Y425002D01*
X1394341Y425419D01*
X1394132Y425711D01*
X1393882Y425794D01*
X1393632Y425752D01*
X1393424Y425586D01*
X1393007Y424752D01*
X1392716Y424377D01*
X1392299Y424127D01*
X1391924Y424044D01*
Y425794D01*
G01X1394424Y426769D02*
X1391924Y427352D01*
X1394424Y428019D01*
X1391924Y428686D01*
X1394424Y429269D01*
G01X1394007Y430327D02*
X1394257Y430577D01*
X1394382Y430869D01*
X1394424Y431202D01*
X1394341Y431619D01*
X1394132Y431911D01*
X1393882Y431994D01*
X1393632Y431952D01*
X1393424Y431786D01*
X1393007Y430952D01*
X1392716Y430577D01*
X1392299Y430327D01*
X1391924Y430244D01*
Y431994D01*
G01X1392216Y433511D02*
X1392007Y433802D01*
X1391924Y434136D01*
X1392007Y434469D01*
X1392257Y434761D01*
X1392632Y434969D01*
X1393007Y435052D01*
X1393466D01*
X1393841Y434969D01*
X1394174Y434761D01*
X1394341Y434511D01*
X1394424Y434219D01*
X1394341Y433886D01*
X1394174Y433636D01*
X1393924Y433469D01*
X1393591Y433386D01*
X1393299Y433469D01*
X1393007Y433677D01*
X1392841Y433927D01*
X1392799Y434219D01*
X1392882Y434552D01*
X1393091Y434802D01*
X1393466Y435052D01*
G01X1381482Y506438D02*
X1381607Y506188D01*
X1381690Y505896D01*
Y505563D01*
X1381565Y505188D01*
X1381357Y504896D01*
X1381107Y504688D01*
X1380690Y504521D01*
X1380315Y504479D01*
X1379940Y504563D01*
X1379690Y504688D01*
X1379440Y504938D01*
X1379273Y505229D01*
X1379190Y505521D01*
Y505813D01*
X1379273Y506104D01*
X1379398Y506354D01*
X1379565Y506563D01*
G01X1379690Y507704D02*
X1379398Y507954D01*
X1379232Y508288D01*
X1379190Y508663D01*
X1379232Y508996D01*
X1379440Y509329D01*
X1379690Y509538D01*
X1379940Y509579D01*
X1380232Y509496D01*
X1380440Y509204D01*
X1380523Y508913D01*
Y508538D01*
G01Y508913D02*
X1380648Y509163D01*
X1380857Y509371D01*
X1381107Y509454D01*
X1381357Y509371D01*
X1381565Y509163D01*
X1381690Y508788D01*
X1381648Y508413D01*
X1381482Y508038D01*
G01X1379190Y510638D02*
X1381690D01*
X1379607Y511721D01*
X1381690Y512804D01*
X1379190D01*
G01Y514821D02*
X1381690D01*
X1381190Y514321D01*
G01X1379190D02*
Y515321D01*
G01X1380232Y517129D02*
X1380523Y517421D01*
X1380690Y517671D01*
X1380773Y518004D01*
X1380690Y518296D01*
X1380523Y518504D01*
X1380273Y518671D01*
X1379982Y518713D01*
X1379732Y518671D01*
X1379482Y518504D01*
X1379273Y518254D01*
X1379190Y517963D01*
X1379273Y517629D01*
X1379523Y517338D01*
X1379898Y517171D01*
X1380315Y517129D01*
X1380857Y517213D01*
X1381148Y517338D01*
X1381440Y517546D01*
X1381648Y517838D01*
X1381690Y518129D01*
X1381607Y518421D01*
X1381398Y518629D01*
G01X1377482Y506438D02*
X1377607Y506188D01*
X1377690Y505896D01*
Y505563D01*
X1377565Y505188D01*
X1377357Y504896D01*
X1377107Y504688D01*
X1376690Y504521D01*
X1376315Y504479D01*
X1375940Y504563D01*
X1375690Y504688D01*
X1375440Y504938D01*
X1375273Y505229D01*
X1375190Y505521D01*
Y505813D01*
X1375273Y506104D01*
X1375398Y506354D01*
X1375565Y506563D01*
G01X1375690Y507704D02*
X1375398Y507954D01*
X1375232Y508288D01*
X1375190Y508663D01*
X1375232Y508996D01*
X1375440Y509329D01*
X1375690Y509538D01*
X1375940Y509579D01*
X1376232Y509496D01*
X1376440Y509204D01*
X1376523Y508913D01*
Y508538D01*
G01Y508913D02*
X1376648Y509163D01*
X1376857Y509371D01*
X1377107Y509454D01*
X1377357Y509371D01*
X1377565Y509163D01*
X1377690Y508788D01*
X1377648Y508413D01*
X1377482Y508038D01*
G01X1375190Y510638D02*
X1377690D01*
X1375607Y511721D01*
X1377690Y512804D01*
X1375190D01*
G01Y514821D02*
X1375232Y515113D01*
X1375357Y515446D01*
X1375565Y515654D01*
X1375857Y515738D01*
X1376148Y515654D01*
X1376398Y515404D01*
X1376523Y515029D01*
Y514613D01*
X1376607Y514363D01*
X1376815Y514154D01*
X1377107Y514071D01*
X1377398Y514196D01*
X1377607Y514488D01*
X1377690Y514821D01*
X1377607Y515154D01*
X1377398Y515446D01*
X1377107Y515571D01*
X1376815Y515488D01*
X1376607Y515279D01*
X1376523Y515029D01*
Y514613D01*
X1376398Y514238D01*
X1376148Y513988D01*
X1375857Y513904D01*
X1375565Y513988D01*
X1375357Y514196D01*
X1375232Y514529D01*
X1375190Y514821D01*
G01X1347605Y526366D02*
X1347730Y526116D01*
X1347813Y525824D01*
Y525491D01*
X1347688Y525116D01*
X1347480Y524824D01*
X1347230Y524616D01*
X1346813Y524449D01*
X1346438Y524407D01*
X1346063Y524491D01*
X1345813Y524616D01*
X1345563Y524866D01*
X1345396Y525157D01*
X1345313Y525449D01*
Y525741D01*
X1345396Y526032D01*
X1345521Y526282D01*
X1345688Y526491D01*
G01X1345813Y527632D02*
X1345521Y527882D01*
X1345355Y528216D01*
X1345313Y528591D01*
X1345355Y528924D01*
X1345563Y529257D01*
X1345813Y529466D01*
X1346063Y529507D01*
X1346355Y529424D01*
X1346563Y529132D01*
X1346646Y528841D01*
Y528466D01*
G01Y528841D02*
X1346771Y529091D01*
X1346980Y529299D01*
X1347230Y529382D01*
X1347480Y529299D01*
X1347688Y529091D01*
X1347813Y528716D01*
X1347771Y528341D01*
X1347605Y527966D01*
G01X1345313Y530566D02*
X1347813D01*
X1345730Y531649D01*
X1347813Y532732D01*
X1345313D01*
G01Y534749D02*
X1347813D01*
X1347313Y534249D01*
G01X1345313D02*
Y535249D01*
G01X1345688Y536932D02*
X1345480Y537182D01*
X1345355Y537474D01*
X1345313Y537849D01*
X1345396Y538224D01*
X1345563Y538516D01*
X1345855Y538724D01*
X1346188Y538766D01*
X1346521Y538682D01*
X1346730Y538474D01*
X1346896Y538182D01*
X1346938Y537891D01*
X1346896Y537599D01*
X1346730Y537224D01*
X1347813Y537349D01*
Y538474D01*
G01X1395983Y506667D02*
Y509167D01*
X1394942D01*
X1394608Y509042D01*
X1394400Y508875D01*
X1394317Y508542D01*
X1394400Y508209D01*
X1394650Y508000D01*
X1394942Y507875D01*
X1395983D01*
G01X1394942D02*
X1394317Y506667D01*
G01X1392133D02*
X1392050Y507209D01*
X1391925Y507667D01*
X1391758Y508084D01*
X1391550Y508542D01*
X1391217Y509167D01*
X1392883D01*
G01X1389742Y507709D02*
X1389450Y508000D01*
X1389200Y508167D01*
X1388867Y508250D01*
X1388575Y508167D01*
X1388367Y508000D01*
X1388200Y507750D01*
X1388158Y507459D01*
X1388200Y507209D01*
X1388367Y506959D01*
X1388617Y506750D01*
X1388908Y506667D01*
X1389242Y506750D01*
X1389533Y507000D01*
X1389700Y507375D01*
X1389742Y507792D01*
X1389658Y508334D01*
X1389533Y508625D01*
X1389325Y508917D01*
X1389033Y509125D01*
X1388742Y509167D01*
X1388450Y509084D01*
X1388242Y508875D01*
G01X1385933Y506667D02*
X1385850Y507209D01*
X1385725Y507667D01*
X1385558Y508084D01*
X1385350Y508542D01*
X1385017Y509167D01*
X1386683D01*
G01X1394524Y502323D02*
Y504823D01*
X1393483D01*
X1393149Y504698D01*
X1392941Y504531D01*
X1392858Y504198D01*
X1392941Y503865D01*
X1393191Y503656D01*
X1393483Y503531D01*
X1394524D01*
G01X1393483D02*
X1392858Y502323D01*
G01X1390674D02*
X1390591Y502865D01*
X1390466Y503323D01*
X1390299Y503740D01*
X1390091Y504198D01*
X1389758Y504823D01*
X1391424D01*
G01X1388283Y503365D02*
X1387991Y503656D01*
X1387741Y503823D01*
X1387408Y503906D01*
X1387116Y503823D01*
X1386908Y503656D01*
X1386741Y503406D01*
X1386699Y503115D01*
X1386741Y502865D01*
X1386908Y502615D01*
X1387158Y502406D01*
X1387449Y502323D01*
X1387783Y502406D01*
X1388074Y502656D01*
X1388241Y503031D01*
X1388283Y503448D01*
X1388199Y503990D01*
X1388074Y504281D01*
X1387866Y504573D01*
X1387574Y504781D01*
X1387283Y504823D01*
X1386991Y504740D01*
X1386783Y504531D01*
G01X1384391Y504823D02*
X1384724Y504740D01*
X1384974Y504531D01*
X1385141Y504281D01*
X1385266Y503948D01*
X1385308Y503573D01*
X1385266Y503198D01*
X1385141Y502865D01*
X1384974Y502615D01*
X1384724Y502406D01*
X1384391Y502323D01*
X1384058Y502406D01*
X1383808Y502615D01*
X1383641Y502865D01*
X1383516Y503198D01*
X1383474Y503573D01*
X1383516Y503948D01*
X1383641Y504281D01*
X1383808Y504531D01*
X1384058Y504740D01*
X1384391Y504823D01*
G01X1389124Y469323D02*
Y471823D01*
X1388083D01*
X1387749Y471698D01*
X1387541Y471531D01*
X1387458Y471198D01*
X1387541Y470865D01*
X1387791Y470656D01*
X1388083Y470531D01*
X1389124D01*
G01X1388083D02*
X1387458Y469323D01*
G01X1385274D02*
X1385191Y469865D01*
X1385066Y470323D01*
X1384899Y470740D01*
X1384691Y471198D01*
X1384358Y471823D01*
X1386024D01*
G01X1382174Y469323D02*
X1382091Y469865D01*
X1381966Y470323D01*
X1381799Y470740D01*
X1381591Y471198D01*
X1381258Y471823D01*
X1382924D01*
G01X1379908Y469698D02*
X1379658Y469490D01*
X1379366Y469365D01*
X1378991Y469323D01*
X1378616Y469406D01*
X1378324Y469573D01*
X1378116Y469865D01*
X1378074Y470198D01*
X1378158Y470531D01*
X1378366Y470740D01*
X1378658Y470906D01*
X1378949Y470948D01*
X1379241Y470906D01*
X1379616Y470740D01*
X1379491Y471823D01*
X1378366D01*
G01X1365183Y499800D02*
Y502300D01*
X1364142D01*
X1363808Y502175D01*
X1363600Y502008D01*
X1363517Y501675D01*
X1363600Y501342D01*
X1363850Y501133D01*
X1364142Y501008D01*
X1365183D01*
G01X1364142D02*
X1363517Y499800D01*
G01X1361333D02*
X1361250Y500342D01*
X1361125Y500800D01*
X1360958Y501217D01*
X1360750Y501675D01*
X1360417Y502300D01*
X1362083D01*
G01X1358942Y500842D02*
X1358650Y501133D01*
X1358400Y501300D01*
X1358067Y501383D01*
X1357775Y501300D01*
X1357567Y501133D01*
X1357400Y500883D01*
X1357358Y500592D01*
X1357400Y500342D01*
X1357567Y500092D01*
X1357817Y499883D01*
X1358108Y499800D01*
X1358442Y499883D01*
X1358733Y500133D01*
X1358900Y500508D01*
X1358942Y500925D01*
X1358858Y501467D01*
X1358733Y501758D01*
X1358525Y502050D01*
X1358233Y502258D01*
X1357942Y502300D01*
X1357650Y502217D01*
X1357442Y502008D01*
G01X1355758Y500092D02*
X1355467Y499883D01*
X1355133Y499800D01*
X1354800Y499883D01*
X1354508Y500133D01*
X1354300Y500508D01*
X1354217Y500883D01*
Y501342D01*
X1354300Y501717D01*
X1354508Y502050D01*
X1354758Y502217D01*
X1355050Y502300D01*
X1355383Y502217D01*
X1355633Y502050D01*
X1355800Y501800D01*
X1355883Y501467D01*
X1355800Y501175D01*
X1355592Y500883D01*
X1355342Y500717D01*
X1355050Y500675D01*
X1354717Y500758D01*
X1354467Y500967D01*
X1354217Y501342D01*
G01X1366333Y473550D02*
Y476050D01*
X1365292D01*
X1364958Y475925D01*
X1364750Y475758D01*
X1364667Y475425D01*
X1364750Y475092D01*
X1365000Y474883D01*
X1365292Y474758D01*
X1366333D01*
G01X1365292D02*
X1364667Y473550D01*
G01X1362483D02*
X1362400Y474092D01*
X1362275Y474550D01*
X1362108Y474967D01*
X1361900Y475425D01*
X1361567Y476050D01*
X1363233D01*
G01X1359383Y473550D02*
X1359300Y474092D01*
X1359175Y474550D01*
X1359008Y474967D01*
X1358800Y475425D01*
X1358467Y476050D01*
X1360133D01*
G01X1356200Y473550D02*
Y476050D01*
X1356700Y475550D01*
G01Y473550D02*
X1355700D01*
G01X1365183Y488400D02*
Y490900D01*
X1364142D01*
X1363808Y490775D01*
X1363600Y490608D01*
X1363517Y490275D01*
X1363600Y489942D01*
X1363850Y489733D01*
X1364142Y489608D01*
X1365183D01*
G01X1364142D02*
X1363517Y488400D01*
G01X1361333D02*
X1361250Y488942D01*
X1361125Y489400D01*
X1360958Y489817D01*
X1360750Y490275D01*
X1360417Y490900D01*
X1362083D01*
G01X1358942Y489442D02*
X1358650Y489733D01*
X1358400Y489900D01*
X1358067Y489983D01*
X1357775Y489900D01*
X1357567Y489733D01*
X1357400Y489483D01*
X1357358Y489192D01*
X1357400Y488942D01*
X1357567Y488692D01*
X1357817Y488483D01*
X1358108Y488400D01*
X1358442Y488483D01*
X1358733Y488733D01*
X1358900Y489108D01*
X1358942Y489525D01*
X1358858Y490067D01*
X1358733Y490358D01*
X1358525Y490650D01*
X1358233Y490858D01*
X1357942Y490900D01*
X1357650Y490817D01*
X1357442Y490608D01*
G01X1355050Y488400D02*
X1354758Y488442D01*
X1354425Y488567D01*
X1354217Y488775D01*
X1354133Y489067D01*
X1354217Y489358D01*
X1354467Y489608D01*
X1354842Y489733D01*
X1355258D01*
X1355508Y489817D01*
X1355717Y490025D01*
X1355800Y490317D01*
X1355675Y490608D01*
X1355383Y490817D01*
X1355050Y490900D01*
X1354717Y490817D01*
X1354425Y490608D01*
X1354300Y490317D01*
X1354383Y490025D01*
X1354592Y489817D01*
X1354842Y489733D01*
X1355258D01*
X1355633Y489608D01*
X1355883Y489358D01*
X1355967Y489067D01*
X1355883Y488775D01*
X1355675Y488567D01*
X1355342Y488442D01*
X1355050Y488400D01*
G01X1366483Y477400D02*
Y479900D01*
X1365442D01*
X1365108Y479775D01*
X1364900Y479608D01*
X1364817Y479275D01*
X1364900Y478942D01*
X1365150Y478733D01*
X1365442Y478608D01*
X1366483D01*
G01X1365442D02*
X1364817Y477400D01*
G01X1362633D02*
X1362550Y477942D01*
X1362425Y478400D01*
X1362258Y478817D01*
X1362050Y479275D01*
X1361717Y479900D01*
X1363383D01*
G01X1359533Y477400D02*
X1359450Y477942D01*
X1359325Y478400D01*
X1359158Y478817D01*
X1358950Y479275D01*
X1358617Y479900D01*
X1360283D01*
G01X1355850Y477400D02*
Y479900D01*
X1357392Y478108D01*
X1355308D01*
G01X1370783Y511250D02*
Y513750D01*
X1369742D01*
X1369408Y513625D01*
X1369200Y513458D01*
X1369117Y513125D01*
X1369200Y512792D01*
X1369450Y512583D01*
X1369742Y512458D01*
X1370783D01*
G01X1369742D02*
X1369117Y511250D01*
G01X1366933D02*
X1366850Y511792D01*
X1366725Y512250D01*
X1366558Y512667D01*
X1366350Y513125D01*
X1366017Y513750D01*
X1367683D01*
G01X1363417Y512583D02*
X1363250Y512708D01*
X1363125Y512917D01*
X1363042Y513208D01*
X1363125Y513458D01*
X1363292Y513625D01*
X1363583Y513750D01*
X1364708D01*
Y511250D01*
X1363333D01*
X1363042Y511417D01*
X1362875Y511667D01*
X1362792Y511958D01*
X1362875Y512250D01*
X1363125Y512500D01*
X1363417Y512583D01*
X1364708D01*
G01X1361442Y513333D02*
X1361192Y513583D01*
X1360900Y513708D01*
X1360567Y513750D01*
X1360150Y513667D01*
X1359858Y513458D01*
X1359775Y513208D01*
X1359817Y512958D01*
X1359983Y512750D01*
X1360817Y512333D01*
X1361192Y512042D01*
X1361442Y511625D01*
X1361525Y511250D01*
X1359775D01*
G01X1357550Y513750D02*
X1357883Y513667D01*
X1358133Y513458D01*
X1358300Y513208D01*
X1358425Y512875D01*
X1358467Y512500D01*
X1358425Y512125D01*
X1358300Y511792D01*
X1358133Y511542D01*
X1357883Y511333D01*
X1357550Y511250D01*
X1357217Y511333D01*
X1356967Y511542D01*
X1356800Y511792D01*
X1356675Y512125D01*
X1356633Y512500D01*
X1356675Y512875D01*
X1356800Y513208D01*
X1356967Y513458D01*
X1357217Y513667D01*
X1357550Y513750D01*
G01X1407093Y508112D02*
X1407343Y508237D01*
X1407635Y508320D01*
X1407968D01*
X1408343Y508195D01*
X1408635Y507987D01*
X1408843Y507737D01*
X1409010Y507320D01*
X1409052Y506945D01*
X1408968Y506570D01*
X1408843Y506320D01*
X1408593Y506070D01*
X1408302Y505903D01*
X1408010Y505820D01*
X1407718D01*
X1407427Y505903D01*
X1407177Y506028D01*
X1406968Y506195D01*
G01X1405827Y506320D02*
X1405577Y506028D01*
X1405243Y505862D01*
X1404868Y505820D01*
X1404535Y505862D01*
X1404202Y506070D01*
X1403993Y506320D01*
X1403952Y506570D01*
X1404035Y506862D01*
X1404327Y507070D01*
X1404618Y507153D01*
X1404993D01*
G01X1404618D02*
X1404368Y507278D01*
X1404160Y507487D01*
X1404077Y507737D01*
X1404160Y507987D01*
X1404368Y508195D01*
X1404743Y508320D01*
X1405118Y508278D01*
X1405493Y508112D01*
G01X1402893Y505820D02*
Y508320D01*
X1401810Y506237D01*
X1400727Y508320D01*
Y505820D01*
G01X1399502Y507903D02*
X1399252Y508153D01*
X1398960Y508278D01*
X1398627Y508320D01*
X1398210Y508237D01*
X1397918Y508028D01*
X1397835Y507778D01*
X1397877Y507528D01*
X1398043Y507320D01*
X1398877Y506903D01*
X1399252Y506612D01*
X1399502Y506195D01*
X1399585Y505820D01*
X1397835D01*
G01X1407093Y503812D02*
X1407343Y503937D01*
X1407635Y504020D01*
X1407968D01*
X1408343Y503895D01*
X1408635Y503687D01*
X1408843Y503437D01*
X1409010Y503020D01*
X1409052Y502645D01*
X1408968Y502270D01*
X1408843Y502020D01*
X1408593Y501770D01*
X1408302Y501603D01*
X1408010Y501520D01*
X1407718D01*
X1407427Y501603D01*
X1407177Y501728D01*
X1406968Y501895D01*
G01X1405827Y502020D02*
X1405577Y501728D01*
X1405243Y501562D01*
X1404868Y501520D01*
X1404535Y501562D01*
X1404202Y501770D01*
X1403993Y502020D01*
X1403952Y502270D01*
X1404035Y502562D01*
X1404327Y502770D01*
X1404618Y502853D01*
X1404993D01*
G01X1404618D02*
X1404368Y502978D01*
X1404160Y503187D01*
X1404077Y503437D01*
X1404160Y503687D01*
X1404368Y503895D01*
X1404743Y504020D01*
X1405118Y503978D01*
X1405493Y503812D01*
G01X1402893Y501520D02*
Y504020D01*
X1401810Y501937D01*
X1400727Y504020D01*
Y501520D01*
G01X1398710D02*
Y504020D01*
X1399210Y503520D01*
G01Y501520D02*
X1398210D01*
G01X1400574Y468015D02*
X1400824Y468140D01*
X1401116Y468223D01*
X1401449D01*
X1401824Y468098D01*
X1402116Y467890D01*
X1402324Y467640D01*
X1402491Y467223D01*
X1402533Y466848D01*
X1402449Y466473D01*
X1402324Y466223D01*
X1402074Y465973D01*
X1401783Y465806D01*
X1401491Y465723D01*
X1401199D01*
X1400908Y465806D01*
X1400658Y465931D01*
X1400449Y466098D01*
G01X1399308Y466223D02*
X1399058Y465931D01*
X1398724Y465765D01*
X1398349Y465723D01*
X1398016Y465765D01*
X1397683Y465973D01*
X1397474Y466223D01*
X1397433Y466473D01*
X1397516Y466765D01*
X1397808Y466973D01*
X1398099Y467056D01*
X1398474D01*
G01X1398099D02*
X1397849Y467181D01*
X1397641Y467390D01*
X1397558Y467640D01*
X1397641Y467890D01*
X1397849Y468098D01*
X1398224Y468223D01*
X1398599Y468181D01*
X1398974Y468015D01*
G01X1396374Y465723D02*
Y468223D01*
X1395291Y466140D01*
X1394208Y468223D01*
Y465723D01*
G01X1393108Y466223D02*
X1392858Y465931D01*
X1392524Y465765D01*
X1392149Y465723D01*
X1391816Y465765D01*
X1391483Y465973D01*
X1391274Y466223D01*
X1391233Y466473D01*
X1391316Y466765D01*
X1391608Y466973D01*
X1391899Y467056D01*
X1392274D01*
G01X1391899D02*
X1391649Y467181D01*
X1391441Y467390D01*
X1391358Y467640D01*
X1391441Y467890D01*
X1391649Y468098D01*
X1392024Y468223D01*
X1392399Y468181D01*
X1392774Y468015D01*
G01X1400574Y472415D02*
X1400824Y472540D01*
X1401116Y472623D01*
X1401449D01*
X1401824Y472498D01*
X1402116Y472290D01*
X1402324Y472040D01*
X1402491Y471623D01*
X1402533Y471248D01*
X1402449Y470873D01*
X1402324Y470623D01*
X1402074Y470373D01*
X1401783Y470206D01*
X1401491Y470123D01*
X1401199D01*
X1400908Y470206D01*
X1400658Y470331D01*
X1400449Y470498D01*
G01X1399308Y470623D02*
X1399058Y470331D01*
X1398724Y470165D01*
X1398349Y470123D01*
X1398016Y470165D01*
X1397683Y470373D01*
X1397474Y470623D01*
X1397433Y470873D01*
X1397516Y471165D01*
X1397808Y471373D01*
X1398099Y471456D01*
X1398474D01*
G01X1398099D02*
X1397849Y471581D01*
X1397641Y471790D01*
X1397558Y472040D01*
X1397641Y472290D01*
X1397849Y472498D01*
X1398224Y472623D01*
X1398599Y472581D01*
X1398974Y472415D01*
G01X1396374Y470123D02*
Y472623D01*
X1395291Y470540D01*
X1394208Y472623D01*
Y470123D01*
G01X1391691D02*
Y472623D01*
X1393233Y470831D01*
X1391149D01*
G01X1380583Y479892D02*
X1380833Y480017D01*
X1381125Y480100D01*
X1381458D01*
X1381833Y479975D01*
X1382125Y479767D01*
X1382333Y479517D01*
X1382500Y479100D01*
X1382542Y478725D01*
X1382458Y478350D01*
X1382333Y478100D01*
X1382083Y477850D01*
X1381792Y477683D01*
X1381500Y477600D01*
X1381208D01*
X1380917Y477683D01*
X1380667Y477808D01*
X1380458Y477975D01*
G01X1379317Y478100D02*
X1379067Y477808D01*
X1378733Y477642D01*
X1378358Y477600D01*
X1378025Y477642D01*
X1377692Y477850D01*
X1377483Y478100D01*
X1377442Y478350D01*
X1377525Y478642D01*
X1377817Y478850D01*
X1378108Y478933D01*
X1378483D01*
G01X1378108D02*
X1377858Y479058D01*
X1377650Y479267D01*
X1377567Y479517D01*
X1377650Y479767D01*
X1377858Y479975D01*
X1378233Y480100D01*
X1378608Y480058D01*
X1378983Y479892D01*
G01X1376383Y477600D02*
Y480100D01*
X1375300Y478017D01*
X1374217Y480100D01*
Y477600D01*
G01X1372200D02*
Y480100D01*
X1372700Y479600D01*
G01Y477600D02*
X1371700D01*
G01X1370017Y478100D02*
X1369767Y477808D01*
X1369433Y477642D01*
X1369058Y477600D01*
X1368725Y477642D01*
X1368392Y477850D01*
X1368183Y478100D01*
X1368142Y478350D01*
X1368225Y478642D01*
X1368517Y478850D01*
X1368808Y478933D01*
X1369183D01*
G01X1368808D02*
X1368558Y479058D01*
X1368350Y479267D01*
X1368267Y479517D01*
X1368350Y479767D01*
X1368558Y479975D01*
X1368933Y480100D01*
X1369308Y480058D01*
X1369683Y479892D01*
G01X1378883Y490942D02*
X1379133Y491067D01*
X1379425Y491150D01*
X1379758D01*
X1380133Y491025D01*
X1380425Y490817D01*
X1380633Y490567D01*
X1380800Y490150D01*
X1380842Y489775D01*
X1380758Y489400D01*
X1380633Y489150D01*
X1380383Y488900D01*
X1380092Y488733D01*
X1379800Y488650D01*
X1379508D01*
X1379217Y488733D01*
X1378967Y488858D01*
X1378758Y489025D01*
G01X1377617Y489150D02*
X1377367Y488858D01*
X1377033Y488692D01*
X1376658Y488650D01*
X1376325Y488692D01*
X1375992Y488900D01*
X1375783Y489150D01*
X1375742Y489400D01*
X1375825Y489692D01*
X1376117Y489900D01*
X1376408Y489983D01*
X1376783D01*
G01X1376408D02*
X1376158Y490108D01*
X1375950Y490317D01*
X1375867Y490567D01*
X1375950Y490817D01*
X1376158Y491025D01*
X1376533Y491150D01*
X1376908Y491108D01*
X1377283Y490942D01*
G01X1374683Y488650D02*
Y491150D01*
X1373600Y489067D01*
X1372517Y491150D01*
Y488650D01*
G01X1370500D02*
Y491150D01*
X1371000Y490650D01*
G01Y488650D02*
X1370000D01*
G01X1368192Y490733D02*
X1367942Y490983D01*
X1367650Y491108D01*
X1367317Y491150D01*
X1366900Y491067D01*
X1366608Y490858D01*
X1366525Y490608D01*
X1366567Y490358D01*
X1366733Y490150D01*
X1367567Y489733D01*
X1367942Y489442D01*
X1368192Y489025D01*
X1368275Y488650D01*
X1366525D01*
G01X1379083Y502292D02*
X1379333Y502417D01*
X1379625Y502500D01*
X1379958D01*
X1380333Y502375D01*
X1380625Y502167D01*
X1380833Y501917D01*
X1381000Y501500D01*
X1381042Y501125D01*
X1380958Y500750D01*
X1380833Y500500D01*
X1380583Y500250D01*
X1380292Y500083D01*
X1380000Y500000D01*
X1379708D01*
X1379417Y500083D01*
X1379167Y500208D01*
X1378958Y500375D01*
G01X1377817Y500500D02*
X1377567Y500208D01*
X1377233Y500042D01*
X1376858Y500000D01*
X1376525Y500042D01*
X1376192Y500250D01*
X1375983Y500500D01*
X1375942Y500750D01*
X1376025Y501042D01*
X1376317Y501250D01*
X1376608Y501333D01*
X1376983D01*
G01X1376608D02*
X1376358Y501458D01*
X1376150Y501667D01*
X1376067Y501917D01*
X1376150Y502167D01*
X1376358Y502375D01*
X1376733Y502500D01*
X1377108Y502458D01*
X1377483Y502292D01*
G01X1374883Y500000D02*
Y502500D01*
X1373800Y500417D01*
X1372717Y502500D01*
Y500000D01*
G01X1370700D02*
Y502500D01*
X1371200Y502000D01*
G01Y500000D02*
X1370200D01*
G01X1367600D02*
Y502500D01*
X1368100Y502000D01*
G01Y500000D02*
X1367100D01*
G01X1380733Y475892D02*
X1380983Y476017D01*
X1381275Y476100D01*
X1381608D01*
X1381983Y475975D01*
X1382275Y475767D01*
X1382483Y475517D01*
X1382650Y475100D01*
X1382692Y474725D01*
X1382608Y474350D01*
X1382483Y474100D01*
X1382233Y473850D01*
X1381942Y473683D01*
X1381650Y473600D01*
X1381358D01*
X1381067Y473683D01*
X1380817Y473808D01*
X1380608Y473975D01*
G01X1379467Y474100D02*
X1379217Y473808D01*
X1378883Y473642D01*
X1378508Y473600D01*
X1378175Y473642D01*
X1377842Y473850D01*
X1377633Y474100D01*
X1377592Y474350D01*
X1377675Y474642D01*
X1377967Y474850D01*
X1378258Y474933D01*
X1378633D01*
G01X1378258D02*
X1378008Y475058D01*
X1377800Y475267D01*
X1377717Y475517D01*
X1377800Y475767D01*
X1378008Y475975D01*
X1378383Y476100D01*
X1378758Y476058D01*
X1379133Y475892D01*
G01X1376533Y473600D02*
Y476100D01*
X1375450Y474017D01*
X1374367Y476100D01*
Y473600D01*
G01X1372350D02*
Y476100D01*
X1372850Y475600D01*
G01Y473600D02*
X1371850D01*
G01X1368750D02*
Y476100D01*
X1370292Y474308D01*
X1368208D01*
G01X1351492Y524967D02*
X1351617Y524717D01*
X1351700Y524425D01*
Y524092D01*
X1351575Y523717D01*
X1351367Y523425D01*
X1351117Y523217D01*
X1350700Y523050D01*
X1350325Y523008D01*
X1349950Y523092D01*
X1349700Y523217D01*
X1349450Y523467D01*
X1349283Y523758D01*
X1349200Y524050D01*
Y524342D01*
X1349283Y524633D01*
X1349408Y524883D01*
X1349575Y525092D01*
G01X1349700Y526233D02*
X1349408Y526483D01*
X1349242Y526817D01*
X1349200Y527192D01*
X1349242Y527525D01*
X1349450Y527858D01*
X1349700Y528067D01*
X1349950Y528108D01*
X1350242Y528025D01*
X1350450Y527733D01*
X1350533Y527442D01*
Y527067D01*
G01Y527442D02*
X1350658Y527692D01*
X1350867Y527900D01*
X1351117Y527983D01*
X1351367Y527900D01*
X1351575Y527692D01*
X1351700Y527317D01*
X1351658Y526942D01*
X1351492Y526567D01*
G01X1349200Y529167D02*
X1351700D01*
X1349617Y530250D01*
X1351700Y531333D01*
X1349200D01*
G01X1349492Y532642D02*
X1349283Y532933D01*
X1349200Y533267D01*
X1349283Y533600D01*
X1349533Y533892D01*
X1349908Y534100D01*
X1350283Y534183D01*
X1350742D01*
X1351117Y534100D01*
X1351450Y533892D01*
X1351617Y533642D01*
X1351700Y533350D01*
X1351617Y533017D01*
X1351450Y532767D01*
X1351200Y532600D01*
X1350867Y532517D01*
X1350575Y532600D01*
X1350283Y532808D01*
X1350117Y533058D01*
X1350075Y533350D01*
X1350158Y533683D01*
X1350367Y533933D01*
X1350742Y534183D01*
G01X1411207Y524631D02*
Y527131D01*
X1410166D01*
X1409832Y527006D01*
X1409624Y526839D01*
X1409541Y526506D01*
X1409624Y526173D01*
X1409874Y525964D01*
X1410166Y525839D01*
X1411207D01*
G01X1410166D02*
X1409541Y524631D01*
G01X1407274D02*
Y527131D01*
X1407774Y526631D01*
G01Y524631D02*
X1406774D01*
G01X1404966Y526714D02*
X1404716Y526964D01*
X1404424Y527089D01*
X1404091Y527131D01*
X1403674Y527048D01*
X1403382Y526839D01*
X1403299Y526589D01*
X1403341Y526339D01*
X1403507Y526131D01*
X1404341Y525714D01*
X1404716Y525423D01*
X1404966Y525006D01*
X1405049Y524631D01*
X1403299D01*
G01X1402324Y527131D02*
X1401741Y524631D01*
X1401074Y527131D01*
X1400407Y524631D01*
X1399824Y527131D01*
G01X1398766Y525673D02*
X1398474Y525964D01*
X1398224Y526131D01*
X1397891Y526214D01*
X1397599Y526131D01*
X1397391Y525964D01*
X1397224Y525714D01*
X1397182Y525423D01*
X1397224Y525173D01*
X1397391Y524923D01*
X1397641Y524714D01*
X1397932Y524631D01*
X1398266Y524714D01*
X1398557Y524964D01*
X1398724Y525339D01*
X1398766Y525756D01*
X1398682Y526298D01*
X1398557Y526589D01*
X1398349Y526881D01*
X1398057Y527089D01*
X1397766Y527131D01*
X1397474Y527048D01*
X1397266Y526839D01*
G01X1355533Y577792D02*
X1355783Y577917D01*
X1356075Y578000D01*
X1356408D01*
X1356783Y577875D01*
X1357075Y577667D01*
X1357283Y577417D01*
X1357450Y577000D01*
X1357492Y576625D01*
X1357408Y576250D01*
X1357283Y576000D01*
X1357033Y575750D01*
X1356742Y575583D01*
X1356450Y575500D01*
X1356158D01*
X1355867Y575583D01*
X1355617Y575708D01*
X1355408Y575875D01*
G01X1354267Y576000D02*
X1354017Y575708D01*
X1353683Y575542D01*
X1353308Y575500D01*
X1352975Y575542D01*
X1352642Y575750D01*
X1352433Y576000D01*
X1352392Y576250D01*
X1352475Y576542D01*
X1352767Y576750D01*
X1353058Y576833D01*
X1353433D01*
G01X1353058D02*
X1352808Y576958D01*
X1352600Y577167D01*
X1352517Y577417D01*
X1352600Y577667D01*
X1352808Y577875D01*
X1353183Y578000D01*
X1353558Y577958D01*
X1353933Y577792D01*
G01X1351083Y578000D02*
Y575500D01*
X1349417D01*
G01X1346650D02*
Y578000D01*
X1348192Y576208D01*
X1346108D01*
G01X1355533Y573792D02*
X1355783Y573917D01*
X1356075Y574000D01*
X1356408D01*
X1356783Y573875D01*
X1357075Y573667D01*
X1357283Y573417D01*
X1357450Y573000D01*
X1357492Y572625D01*
X1357408Y572250D01*
X1357283Y572000D01*
X1357033Y571750D01*
X1356742Y571583D01*
X1356450Y571500D01*
X1356158D01*
X1355867Y571583D01*
X1355617Y571708D01*
X1355408Y571875D01*
G01X1354267Y572000D02*
X1354017Y571708D01*
X1353683Y571542D01*
X1353308Y571500D01*
X1352975Y571542D01*
X1352642Y571750D01*
X1352433Y572000D01*
X1352392Y572250D01*
X1352475Y572542D01*
X1352767Y572750D01*
X1353058Y572833D01*
X1353433D01*
G01X1353058D02*
X1352808Y572958D01*
X1352600Y573167D01*
X1352517Y573417D01*
X1352600Y573667D01*
X1352808Y573875D01*
X1353183Y574000D01*
X1353558Y573958D01*
X1353933Y573792D01*
G01X1351083Y574000D02*
Y571500D01*
X1349417D01*
G01X1347150D02*
Y574000D01*
X1347650Y573500D01*
G01Y571500D02*
X1346650D01*
G01X1344133D02*
X1344050Y572042D01*
X1343925Y572500D01*
X1343758Y572917D01*
X1343550Y573375D01*
X1343217Y574000D01*
X1344883D01*
G01X1355533Y569792D02*
X1355783Y569917D01*
X1356075Y570000D01*
X1356408D01*
X1356783Y569875D01*
X1357075Y569667D01*
X1357283Y569417D01*
X1357450Y569000D01*
X1357492Y568625D01*
X1357408Y568250D01*
X1357283Y568000D01*
X1357033Y567750D01*
X1356742Y567583D01*
X1356450Y567500D01*
X1356158D01*
X1355867Y567583D01*
X1355617Y567708D01*
X1355408Y567875D01*
G01X1354267Y568000D02*
X1354017Y567708D01*
X1353683Y567542D01*
X1353308Y567500D01*
X1352975Y567542D01*
X1352642Y567750D01*
X1352433Y568000D01*
X1352392Y568250D01*
X1352475Y568542D01*
X1352767Y568750D01*
X1353058Y568833D01*
X1353433D01*
G01X1353058D02*
X1352808Y568958D01*
X1352600Y569167D01*
X1352517Y569417D01*
X1352600Y569667D01*
X1352808Y569875D01*
X1353183Y570000D01*
X1353558Y569958D01*
X1353933Y569792D01*
G01X1351083Y570000D02*
Y567500D01*
X1349417D01*
G01X1347150D02*
Y570000D01*
X1347650Y569500D01*
G01Y567500D02*
X1346650D01*
G01X1344842Y568542D02*
X1344550Y568833D01*
X1344300Y569000D01*
X1343967Y569083D01*
X1343675Y569000D01*
X1343467Y568833D01*
X1343300Y568583D01*
X1343258Y568292D01*
X1343300Y568042D01*
X1343467Y567792D01*
X1343717Y567583D01*
X1344008Y567500D01*
X1344342Y567583D01*
X1344633Y567833D01*
X1344800Y568208D01*
X1344842Y568625D01*
X1344758Y569167D01*
X1344633Y569458D01*
X1344425Y569750D01*
X1344133Y569958D01*
X1343842Y570000D01*
X1343550Y569917D01*
X1343342Y569708D01*
G01X1357263Y578880D02*
Y581380D01*
X1356222D01*
X1355888Y581255D01*
X1355680Y581088D01*
X1355597Y580755D01*
X1355680Y580422D01*
X1355930Y580213D01*
X1356222Y580088D01*
X1357263D01*
G01X1356222D02*
X1355597Y578880D01*
G01X1354247Y579380D02*
X1353997Y579088D01*
X1353663Y578922D01*
X1353288Y578880D01*
X1352955Y578922D01*
X1352622Y579130D01*
X1352413Y579380D01*
X1352372Y579630D01*
X1352455Y579922D01*
X1352747Y580130D01*
X1353038Y580213D01*
X1353413D01*
G01X1353038D02*
X1352788Y580338D01*
X1352580Y580547D01*
X1352497Y580797D01*
X1352580Y581047D01*
X1352788Y581255D01*
X1353163Y581380D01*
X1353538Y581338D01*
X1353913Y581172D01*
G01X1351063Y581380D02*
Y578880D01*
X1349397D01*
G01X1347130D02*
X1346838Y578922D01*
X1346505Y579047D01*
X1346297Y579255D01*
X1346213Y579547D01*
X1346297Y579838D01*
X1346547Y580088D01*
X1346922Y580213D01*
X1347338D01*
X1347588Y580297D01*
X1347797Y580505D01*
X1347880Y580797D01*
X1347755Y581088D01*
X1347463Y581297D01*
X1347130Y581380D01*
X1346797Y581297D01*
X1346505Y581088D01*
X1346380Y580797D01*
X1346463Y580505D01*
X1346672Y580297D01*
X1346922Y580213D01*
X1347338D01*
X1347713Y580088D01*
X1347963Y579838D01*
X1348047Y579547D01*
X1347963Y579255D01*
X1347755Y579047D01*
X1347422Y578922D01*
X1347130Y578880D01*
G01X1387133Y572492D02*
X1387383Y572617D01*
X1387675Y572700D01*
X1388008D01*
X1388383Y572575D01*
X1388675Y572367D01*
X1388883Y572117D01*
X1389050Y571700D01*
X1389092Y571325D01*
X1389008Y570950D01*
X1388883Y570700D01*
X1388633Y570450D01*
X1388342Y570283D01*
X1388050Y570200D01*
X1387758D01*
X1387467Y570283D01*
X1387217Y570408D01*
X1387008Y570575D01*
G01X1384950Y572700D02*
Y570200D01*
G01X1385908Y572700D02*
X1383992D01*
G01X1381350Y570200D02*
Y572700D01*
X1382892Y570908D01*
X1380808D01*
G01X1378750Y570200D02*
X1378458Y570242D01*
X1378125Y570367D01*
X1377917Y570575D01*
X1377833Y570867D01*
X1377917Y571158D01*
X1378167Y571408D01*
X1378542Y571533D01*
X1378958D01*
X1379208Y571617D01*
X1379417Y571825D01*
X1379500Y572117D01*
X1379375Y572408D01*
X1379083Y572617D01*
X1378750Y572700D01*
X1378417Y572617D01*
X1378125Y572408D01*
X1378000Y572117D01*
X1378083Y571825D01*
X1378292Y571617D01*
X1378542Y571533D01*
X1378958D01*
X1379333Y571408D01*
X1379583Y571158D01*
X1379667Y570867D01*
X1379583Y570575D01*
X1379375Y570367D01*
X1379042Y570242D01*
X1378750Y570200D01*
G01X1344000Y583000D02*
Y585698D01*
G01X1358189Y585221D02*
X1358439Y585346D01*
X1358731Y585429D01*
X1359064D01*
X1359439Y585304D01*
X1359731Y585096D01*
X1359939Y584846D01*
X1360106Y584429D01*
X1360148Y584054D01*
X1360064Y583679D01*
X1359939Y583429D01*
X1359689Y583179D01*
X1359398Y583012D01*
X1359106Y582929D01*
X1358814D01*
X1358523Y583012D01*
X1358273Y583137D01*
X1358064Y583304D01*
G01X1356089Y582929D02*
X1356006Y583471D01*
X1355881Y583929D01*
X1355714Y584346D01*
X1355506Y584804D01*
X1355173Y585429D01*
X1356839D01*
G01X1353948Y582929D02*
X1352906Y585429D01*
X1351864Y582929D01*
G01X1352239Y583804D02*
X1353573D01*
G01X1350598Y585012D02*
X1350348Y585262D01*
X1350056Y585387D01*
X1349723Y585429D01*
X1349306Y585346D01*
X1349014Y585137D01*
X1348931Y584887D01*
X1348973Y584637D01*
X1349139Y584429D01*
X1349973Y584012D01*
X1350348Y583721D01*
X1350598Y583304D01*
X1350681Y582929D01*
X1348931D01*
G01X1347498Y583971D02*
X1347206Y584262D01*
X1346956Y584429D01*
X1346623Y584512D01*
X1346331Y584429D01*
X1346123Y584262D01*
X1345956Y584012D01*
X1345914Y583721D01*
X1345956Y583471D01*
X1346123Y583221D01*
X1346373Y583012D01*
X1346664Y582929D01*
X1346998Y583012D01*
X1347289Y583262D01*
X1347456Y583637D01*
X1347498Y584054D01*
X1347414Y584596D01*
X1347289Y584887D01*
X1347081Y585179D01*
X1346789Y585387D01*
X1346498Y585429D01*
X1346206Y585346D01*
X1345998Y585137D01*
G01X1360418Y557525D02*
X1360668Y557650D01*
X1360960Y557733D01*
X1361293D01*
X1361668Y557608D01*
X1361960Y557400D01*
X1362168Y557150D01*
X1362335Y556733D01*
X1362377Y556358D01*
X1362293Y555983D01*
X1362168Y555733D01*
X1361918Y555483D01*
X1361627Y555316D01*
X1361335Y555233D01*
X1361043D01*
X1360752Y555316D01*
X1360502Y555441D01*
X1360293Y555608D01*
G01X1358318Y555233D02*
X1358235Y555775D01*
X1358110Y556233D01*
X1357943Y556650D01*
X1357735Y557108D01*
X1357402Y557733D01*
X1359068D01*
G01X1356385D02*
X1355802Y555233D01*
X1355135Y557733D01*
X1354468Y555233D01*
X1353885Y557733D01*
G01X1352035Y555233D02*
Y557733D01*
X1352535Y557233D01*
G01Y555233D02*
X1351535D01*
G01X1349852Y555733D02*
X1349602Y555441D01*
X1349268Y555275D01*
X1348893Y555233D01*
X1348560Y555275D01*
X1348227Y555483D01*
X1348018Y555733D01*
X1347977Y555983D01*
X1348060Y556275D01*
X1348352Y556483D01*
X1348643Y556566D01*
X1349018D01*
G01X1348643D02*
X1348393Y556691D01*
X1348185Y556900D01*
X1348102Y557150D01*
X1348185Y557400D01*
X1348393Y557608D01*
X1348768Y557733D01*
X1349143Y557691D01*
X1349518Y557525D01*
G01X1411564Y564314D02*
X1411814Y564439D01*
X1412106Y564522D01*
X1412439D01*
X1412814Y564397D01*
X1413106Y564189D01*
X1413314Y563939D01*
X1413481Y563522D01*
X1413523Y563147D01*
X1413439Y562772D01*
X1413314Y562522D01*
X1413064Y562272D01*
X1412773Y562105D01*
X1412481Y562022D01*
X1412189D01*
X1411898Y562105D01*
X1411648Y562230D01*
X1411439Y562397D01*
G01X1409464Y562022D02*
X1409381Y562564D01*
X1409256Y563022D01*
X1409089Y563439D01*
X1408881Y563897D01*
X1408548Y564522D01*
X1410214D01*
G01X1407531D02*
X1406948Y562022D01*
X1406281Y564522D01*
X1405614Y562022D01*
X1405031Y564522D01*
G01X1403181Y562022D02*
Y564522D01*
X1403681Y564022D01*
G01Y562022D02*
X1402681D01*
G01X1400081D02*
Y564522D01*
X1400581Y564022D01*
G01Y562022D02*
X1399581D01*
G01X1411987Y568114D02*
X1412237Y568239D01*
X1412529Y568322D01*
X1412862D01*
X1413237Y568197D01*
X1413529Y567989D01*
X1413737Y567739D01*
X1413904Y567322D01*
X1413946Y566947D01*
X1413862Y566572D01*
X1413737Y566322D01*
X1413487Y566072D01*
X1413196Y565905D01*
X1412904Y565822D01*
X1412612D01*
X1412321Y565905D01*
X1412071Y566030D01*
X1411862Y566197D01*
G01X1409887Y565822D02*
X1409804Y566364D01*
X1409679Y566822D01*
X1409512Y567239D01*
X1409304Y567697D01*
X1408971Y568322D01*
X1410637D01*
G01X1407954D02*
X1407371Y565822D01*
X1406704Y568322D01*
X1406037Y565822D01*
X1405454Y568322D01*
G01X1403604Y565822D02*
Y568322D01*
X1404104Y567822D01*
G01Y565822D02*
X1403104D01*
G01X1400504Y568322D02*
X1400837Y568239D01*
X1401087Y568030D01*
X1401254Y567780D01*
X1401379Y567447D01*
X1401421Y567072D01*
X1401379Y566697D01*
X1401254Y566364D01*
X1401087Y566114D01*
X1400837Y565905D01*
X1400504Y565822D01*
X1400171Y565905D01*
X1399921Y566114D01*
X1399754Y566364D01*
X1399629Y566697D01*
X1399587Y567072D01*
X1399629Y567447D01*
X1399754Y567780D01*
X1399921Y568030D01*
X1400171Y568239D01*
X1400504Y568322D01*
G01X1393552Y574047D02*
X1393677Y573797D01*
X1393760Y573505D01*
Y573172D01*
X1393635Y572797D01*
X1393427Y572505D01*
X1393177Y572297D01*
X1392760Y572130D01*
X1392385Y572088D01*
X1392010Y572172D01*
X1391760Y572297D01*
X1391510Y572547D01*
X1391343Y572838D01*
X1391260Y573130D01*
Y573422D01*
X1391343Y573713D01*
X1391468Y573963D01*
X1391635Y574172D01*
G01X1391260Y576147D02*
X1391802Y576230D01*
X1392260Y576355D01*
X1392677Y576522D01*
X1393135Y576730D01*
X1393760Y577063D01*
Y575397D01*
G01Y578080D02*
X1391260Y578663D01*
X1393760Y579330D01*
X1391260Y579997D01*
X1393760Y580580D01*
G01X1391552Y581722D02*
X1391343Y582013D01*
X1391260Y582347D01*
X1391343Y582680D01*
X1391593Y582972D01*
X1391968Y583180D01*
X1392343Y583263D01*
X1392802D01*
X1393177Y583180D01*
X1393510Y582972D01*
X1393677Y582722D01*
X1393760Y582430D01*
X1393677Y582097D01*
X1393510Y581847D01*
X1393260Y581680D01*
X1392927Y581597D01*
X1392635Y581680D01*
X1392343Y581888D01*
X1392177Y582138D01*
X1392135Y582430D01*
X1392218Y582763D01*
X1392427Y583013D01*
X1392802Y583263D01*
G01X1405990Y535750D02*
X1400790D01*
G01X1405990Y528750D02*
X1398190D01*
G01X1392590Y535750D02*
X1401290D01*
G01X1392590Y528750D02*
Y535750D01*
G01X1398990Y528750D02*
X1392590D01*
G01X1406339Y547491D02*
Y549991D01*
X1405298D01*
X1404964Y549866D01*
X1404756Y549699D01*
X1404673Y549366D01*
X1404756Y549033D01*
X1405006Y548824D01*
X1405298Y548699D01*
X1406339D01*
G01X1405298D02*
X1404673Y547491D01*
G01X1402406D02*
Y549991D01*
X1402906Y549491D01*
G01Y547491D02*
X1401906D01*
G01X1400098Y549574D02*
X1399848Y549824D01*
X1399556Y549949D01*
X1399223Y549991D01*
X1398806Y549908D01*
X1398514Y549699D01*
X1398431Y549449D01*
X1398473Y549199D01*
X1398639Y548991D01*
X1399473Y548574D01*
X1399848Y548283D01*
X1400098Y547866D01*
X1400181Y547491D01*
X1398431D01*
G01X1397456Y549991D02*
X1396873Y547491D01*
X1396206Y549991D01*
X1395539Y547491D01*
X1394956Y549991D01*
G01X1393189Y547491D02*
X1393106Y548033D01*
X1392981Y548491D01*
X1392814Y548908D01*
X1392606Y549366D01*
X1392273Y549991D01*
X1393939D01*
G01X1406362Y546432D02*
X1401162D01*
G01X1406362Y539432D02*
X1398562D01*
G01X1392962Y546432D02*
X1401662D01*
G01X1392962Y539432D02*
Y546432D01*
G01X1399362Y539432D02*
X1392962D01*
G01X1391333Y603692D02*
X1391583Y603817D01*
X1391875Y603900D01*
X1392208D01*
X1392583Y603775D01*
X1392875Y603567D01*
X1393083Y603317D01*
X1393250Y602900D01*
X1393292Y602525D01*
X1393208Y602150D01*
X1393083Y601900D01*
X1392833Y601650D01*
X1392542Y601483D01*
X1392250Y601400D01*
X1391958D01*
X1391667Y601483D01*
X1391417Y601608D01*
X1391208Y601775D01*
G01X1390067Y601900D02*
X1389817Y601608D01*
X1389483Y601442D01*
X1389108Y601400D01*
X1388775Y601442D01*
X1388442Y601650D01*
X1388233Y601900D01*
X1388192Y602150D01*
X1388275Y602442D01*
X1388567Y602650D01*
X1388858Y602733D01*
X1389233D01*
G01X1388858D02*
X1388608Y602858D01*
X1388400Y603067D01*
X1388317Y603317D01*
X1388400Y603567D01*
X1388608Y603775D01*
X1388983Y603900D01*
X1389358Y603858D01*
X1389733Y603692D01*
G01X1386883Y603900D02*
Y601400D01*
X1385217D01*
G01X1383742Y603483D02*
X1383492Y603733D01*
X1383200Y603858D01*
X1382867Y603900D01*
X1382450Y603817D01*
X1382158Y603608D01*
X1382075Y603358D01*
X1382117Y603108D01*
X1382283Y602900D01*
X1383117Y602483D01*
X1383492Y602192D01*
X1383742Y601775D01*
X1383825Y601400D01*
X1382075D01*
G01X1391733Y600254D02*
X1391983Y600379D01*
X1392275Y600462D01*
X1392608D01*
X1392983Y600337D01*
X1393275Y600129D01*
X1393483Y599879D01*
X1393650Y599462D01*
X1393692Y599087D01*
X1393608Y598712D01*
X1393483Y598462D01*
X1393233Y598212D01*
X1392942Y598045D01*
X1392650Y597962D01*
X1392358D01*
X1392067Y598045D01*
X1391817Y598170D01*
X1391608Y598337D01*
G01X1390467Y598462D02*
X1390217Y598170D01*
X1389883Y598004D01*
X1389508Y597962D01*
X1389175Y598004D01*
X1388842Y598212D01*
X1388633Y598462D01*
X1388592Y598712D01*
X1388675Y599004D01*
X1388967Y599212D01*
X1389258Y599295D01*
X1389633D01*
G01X1389258D02*
X1389008Y599420D01*
X1388800Y599629D01*
X1388717Y599879D01*
X1388800Y600129D01*
X1389008Y600337D01*
X1389383Y600462D01*
X1389758Y600420D01*
X1390133Y600254D01*
G01X1387283Y600462D02*
Y597962D01*
X1385617D01*
G01X1383350D02*
Y600462D01*
X1383850Y599962D01*
G01Y597962D02*
X1382850D01*
G01X1381167Y598337D02*
X1380917Y598129D01*
X1380625Y598004D01*
X1380250Y597962D01*
X1379875Y598045D01*
X1379583Y598212D01*
X1379375Y598504D01*
X1379333Y598837D01*
X1379417Y599170D01*
X1379625Y599379D01*
X1379917Y599545D01*
X1380208Y599587D01*
X1380500Y599545D01*
X1380875Y599379D01*
X1380750Y600462D01*
X1379625D01*
G01X1391733Y596254D02*
X1391983Y596379D01*
X1392275Y596462D01*
X1392608D01*
X1392983Y596337D01*
X1393275Y596129D01*
X1393483Y595879D01*
X1393650Y595462D01*
X1393692Y595087D01*
X1393608Y594712D01*
X1393483Y594462D01*
X1393233Y594212D01*
X1392942Y594045D01*
X1392650Y593962D01*
X1392358D01*
X1392067Y594045D01*
X1391817Y594170D01*
X1391608Y594337D01*
G01X1390467Y594462D02*
X1390217Y594170D01*
X1389883Y594004D01*
X1389508Y593962D01*
X1389175Y594004D01*
X1388842Y594212D01*
X1388633Y594462D01*
X1388592Y594712D01*
X1388675Y595004D01*
X1388967Y595212D01*
X1389258Y595295D01*
X1389633D01*
G01X1389258D02*
X1389008Y595420D01*
X1388800Y595629D01*
X1388717Y595879D01*
X1388800Y596129D01*
X1389008Y596337D01*
X1389383Y596462D01*
X1389758Y596420D01*
X1390133Y596254D01*
G01X1387283Y596462D02*
Y593962D01*
X1385617D01*
G01X1383350D02*
Y596462D01*
X1383850Y595962D01*
G01Y593962D02*
X1382850D01*
G01X1381167Y594462D02*
X1380917Y594170D01*
X1380583Y594004D01*
X1380208Y593962D01*
X1379875Y594004D01*
X1379542Y594212D01*
X1379333Y594462D01*
X1379292Y594712D01*
X1379375Y595004D01*
X1379667Y595212D01*
X1379958Y595295D01*
X1380333D01*
G01X1379958D02*
X1379708Y595420D01*
X1379500Y595629D01*
X1379417Y595879D01*
X1379500Y596129D01*
X1379708Y596337D01*
X1380083Y596462D01*
X1380458Y596420D01*
X1380833Y596254D01*
G01X1380113Y618290D02*
Y620790D01*
X1379072D01*
X1378738Y620665D01*
X1378530Y620498D01*
X1378447Y620165D01*
X1378530Y619832D01*
X1378780Y619623D01*
X1379072Y619498D01*
X1380113D01*
G01X1379072D02*
X1378447Y618290D01*
G01X1377097Y618790D02*
X1376847Y618498D01*
X1376513Y618332D01*
X1376138Y618290D01*
X1375805Y618332D01*
X1375472Y618540D01*
X1375263Y618790D01*
X1375222Y619040D01*
X1375305Y619332D01*
X1375597Y619540D01*
X1375888Y619623D01*
X1376263D01*
G01X1375888D02*
X1375638Y619748D01*
X1375430Y619957D01*
X1375347Y620207D01*
X1375430Y620457D01*
X1375638Y620665D01*
X1376013Y620790D01*
X1376388Y620748D01*
X1376763Y620582D01*
G01X1373913Y620790D02*
Y618290D01*
X1372247D01*
G01X1370772Y619332D02*
X1370480Y619623D01*
X1370230Y619790D01*
X1369897Y619873D01*
X1369605Y619790D01*
X1369397Y619623D01*
X1369230Y619373D01*
X1369188Y619082D01*
X1369230Y618832D01*
X1369397Y618582D01*
X1369647Y618373D01*
X1369938Y618290D01*
X1370272Y618373D01*
X1370563Y618623D01*
X1370730Y618998D01*
X1370772Y619415D01*
X1370688Y619957D01*
X1370563Y620248D01*
X1370355Y620540D01*
X1370063Y620748D01*
X1369772Y620790D01*
X1369480Y620707D01*
X1369272Y620498D01*
G01X1385992Y610167D02*
X1386117Y609917D01*
X1386200Y609625D01*
Y609292D01*
X1386075Y608917D01*
X1385867Y608625D01*
X1385617Y608417D01*
X1385200Y608250D01*
X1384825Y608208D01*
X1384450Y608292D01*
X1384200Y608417D01*
X1383950Y608667D01*
X1383783Y608958D01*
X1383700Y609250D01*
Y609542D01*
X1383783Y609833D01*
X1383908Y610083D01*
X1384075Y610292D01*
G01X1386200Y612350D02*
X1383700D01*
G01X1386200Y611392D02*
Y613308D01*
G01X1383700Y615950D02*
X1386200D01*
X1384408Y614408D01*
Y616492D01*
G01X1384200Y617633D02*
X1383908Y617883D01*
X1383742Y618217D01*
X1383700Y618592D01*
X1383742Y618925D01*
X1383950Y619258D01*
X1384200Y619467D01*
X1384450Y619508D01*
X1384742Y619425D01*
X1384950Y619133D01*
X1385033Y618842D01*
Y618467D01*
G01Y618842D02*
X1385158Y619092D01*
X1385367Y619300D01*
X1385617Y619383D01*
X1385867Y619300D01*
X1386075Y619092D01*
X1386200Y618717D01*
X1386158Y618342D01*
X1385992Y617967D01*
G01X1344000Y601000D02*
Y598305D01*
G01Y621000D02*
Y618305D01*
G01Y603000D02*
Y605698D01*
G01X1361743Y620832D02*
X1361993Y620957D01*
X1362285Y621040D01*
X1362618D01*
X1362993Y620915D01*
X1363285Y620707D01*
X1363493Y620457D01*
X1363660Y620040D01*
X1363702Y619665D01*
X1363618Y619290D01*
X1363493Y619040D01*
X1363243Y618790D01*
X1362952Y618623D01*
X1362660Y618540D01*
X1362368D01*
X1362077Y618623D01*
X1361827Y618748D01*
X1361618Y618915D01*
G01X1359643Y618540D02*
X1359560Y619082D01*
X1359435Y619540D01*
X1359268Y619957D01*
X1359060Y620415D01*
X1358727Y621040D01*
X1360393D01*
G01X1357502Y618540D02*
X1356460Y621040D01*
X1355418Y618540D01*
G01X1355793Y619415D02*
X1357127D01*
G01X1353360Y618540D02*
Y621040D01*
X1353860Y620540D01*
G01Y618540D02*
X1352860D01*
G01X1350260D02*
X1349968Y618582D01*
X1349635Y618707D01*
X1349427Y618915D01*
X1349343Y619207D01*
X1349427Y619498D01*
X1349677Y619748D01*
X1350052Y619873D01*
X1350468D01*
X1350718Y619957D01*
X1350927Y620165D01*
X1351010Y620457D01*
X1350885Y620748D01*
X1350593Y620957D01*
X1350260Y621040D01*
X1349927Y620957D01*
X1349635Y620748D01*
X1349510Y620457D01*
X1349593Y620165D01*
X1349802Y619957D01*
X1350052Y619873D01*
X1350468D01*
X1350843Y619748D01*
X1351093Y619498D01*
X1351177Y619207D01*
X1351093Y618915D01*
X1350885Y618707D01*
X1350552Y618582D01*
X1350260Y618540D01*
G01X1411200Y656800D02*
Y659800D01*
X1410200D01*
X1409800Y659650D01*
X1409500Y659450D01*
X1409250Y659150D01*
X1409050Y658800D01*
X1409000Y658300D01*
X1409050Y657800D01*
X1409250Y657450D01*
X1409500Y657150D01*
X1409800Y656950D01*
X1410200Y656800D01*
X1411200D01*
G01X1407250Y658150D02*
X1405650D01*
X1405800Y658500D01*
X1406050Y658700D01*
X1406400Y658800D01*
X1406750Y658750D01*
X1407050Y658600D01*
X1407250Y658250D01*
X1407350Y657950D01*
Y657650D01*
X1407250Y657350D01*
X1407000Y657050D01*
X1406700Y656850D01*
X1406350Y656800D01*
X1406000Y656900D01*
X1405650Y657200D01*
G01X1402900Y656800D02*
Y659800D01*
G01X1399300D02*
Y656800D01*
G01X1400000Y658800D02*
X1398600D01*
G01X1394800Y656800D02*
Y658800D01*
G01Y658450D02*
X1395000Y658650D01*
X1395300Y658750D01*
X1395650Y658800D01*
X1396000Y658700D01*
X1396300Y658500D01*
X1396500Y658200D01*
X1396600Y657800D01*
X1396500Y657400D01*
X1396300Y657100D01*
X1396000Y656900D01*
X1395650Y656800D01*
X1395300Y656850D01*
X1395000Y657000D01*
X1394800Y657200D01*
G01X1393600Y655800D02*
X1390600D01*
G01X1389500Y659800D02*
Y656800D01*
X1387500D01*
G01X1386000Y657250D02*
X1385700Y657000D01*
X1385350Y656850D01*
X1384900Y656800D01*
X1384450Y656900D01*
X1384100Y657100D01*
X1383850Y657450D01*
X1383800Y657850D01*
X1383900Y658250D01*
X1384150Y658500D01*
X1384500Y658700D01*
X1384850Y658750D01*
X1385200Y658700D01*
X1385650Y658500D01*
X1385500Y659800D01*
X1384150D01*
G01X1382800Y655800D02*
X1379800D01*
G01X1377700Y656800D02*
Y659800D01*
X1378300Y659200D01*
G01Y656800D02*
X1377100D01*
G01X1374100Y659800D02*
X1374500Y659700D01*
X1374800Y659450D01*
X1375000Y659150D01*
X1375150Y658750D01*
X1375200Y658300D01*
X1375150Y657850D01*
X1375000Y657450D01*
X1374800Y657150D01*
X1374500Y656900D01*
X1374100Y656800D01*
X1373700Y656900D01*
X1373400Y657150D01*
X1373200Y657450D01*
X1373050Y657850D01*
X1373000Y658300D01*
X1373050Y658750D01*
X1373200Y659150D01*
X1373400Y659450D01*
X1373700Y659700D01*
X1374100Y659800D01*
G01X1370500Y658800D02*
Y656800D01*
G01Y659600D02*
X1370600Y659650D01*
Y659750D01*
X1370500Y659800D01*
X1370400Y659750D01*
Y659650D01*
X1370500Y659600D01*
G01X1367750Y656800D02*
Y658800D01*
G01Y658300D02*
X1367550Y658550D01*
X1367250Y658750D01*
X1366850Y658800D01*
X1366500Y658750D01*
X1366200Y658550D01*
X1366050Y658200D01*
Y656800D01*
G01X1362500Y658550D02*
X1362850Y658750D01*
X1363150Y658800D01*
X1363550Y658700D01*
X1363850Y658500D01*
X1364050Y658150D01*
X1364100Y657800D01*
X1364050Y657450D01*
X1363850Y657150D01*
X1363550Y656900D01*
X1363150Y656800D01*
X1362800Y656900D01*
X1362500Y657100D01*
G01X1360550Y656800D02*
Y659800D01*
G01Y658350D02*
X1360300Y658600D01*
X1360050Y658750D01*
X1359650Y658800D01*
X1359350Y658750D01*
X1359000Y658550D01*
X1358850Y658250D01*
Y656800D01*
G01X1453877Y26570D02*
X1456377D01*
Y27611D01*
X1456252Y27945D01*
X1456085Y28153D01*
X1455752Y28236D01*
X1455419Y28153D01*
X1455210Y27903D01*
X1455085Y27611D01*
Y26570D01*
G01Y27611D02*
X1453877Y28236D01*
G01Y30420D02*
X1454419Y30503D01*
X1454877Y30628D01*
X1455294Y30795D01*
X1455752Y31003D01*
X1456377Y31336D01*
Y29670D01*
G01X1455127Y33853D02*
Y34686D01*
X1454377D01*
X1454127Y34436D01*
X1453960Y34145D01*
X1453877Y33728D01*
X1453960Y33311D01*
X1454127Y33020D01*
X1454377Y32770D01*
X1454669Y32603D01*
X1455002Y32520D01*
X1455294D01*
X1455544Y32603D01*
X1455835Y32770D01*
X1456085Y33020D01*
X1456252Y33270D01*
X1456377Y33603D01*
Y33895D01*
X1456294Y34228D01*
X1456127Y34478D01*
G01X1455960Y35911D02*
X1456210Y36161D01*
X1456335Y36453D01*
X1456377Y36786D01*
X1456294Y37203D01*
X1456085Y37495D01*
X1455835Y37578D01*
X1455585Y37536D01*
X1455377Y37370D01*
X1454960Y36536D01*
X1454669Y36161D01*
X1454252Y35911D01*
X1453877Y35828D01*
Y37578D01*
G01Y39803D02*
X1453919Y40095D01*
X1454044Y40428D01*
X1454252Y40636D01*
X1454544Y40720D01*
X1454835Y40636D01*
X1455085Y40386D01*
X1455210Y40011D01*
Y39595D01*
X1455294Y39345D01*
X1455502Y39136D01*
X1455794Y39053D01*
X1456085Y39178D01*
X1456294Y39470D01*
X1456377Y39803D01*
X1456294Y40136D01*
X1456085Y40428D01*
X1455794Y40553D01*
X1455502Y40470D01*
X1455294Y40261D01*
X1455210Y40011D01*
Y39595D01*
X1455085Y39220D01*
X1454835Y38970D01*
X1454544Y38886D01*
X1454252Y38970D01*
X1454044Y39178D01*
X1453919Y39511D01*
X1453877Y39803D01*
G01X1449829Y26545D02*
X1452329D01*
Y27586D01*
X1452204Y27920D01*
X1452037Y28128D01*
X1451704Y28211D01*
X1451371Y28128D01*
X1451162Y27878D01*
X1451037Y27586D01*
Y26545D01*
G01Y27586D02*
X1449829Y28211D01*
G01X1450329Y29561D02*
X1450037Y29811D01*
X1449871Y30145D01*
X1449829Y30520D01*
X1449871Y30853D01*
X1450079Y31186D01*
X1450329Y31395D01*
X1450579Y31436D01*
X1450871Y31353D01*
X1451079Y31061D01*
X1451162Y30770D01*
Y30395D01*
G01Y30770D02*
X1451287Y31020D01*
X1451496Y31228D01*
X1451746Y31311D01*
X1451996Y31228D01*
X1452204Y31020D01*
X1452329Y30645D01*
X1452287Y30270D01*
X1452121Y29895D01*
G01X1452329Y33578D02*
X1449829D01*
G01X1452329Y32620D02*
Y34536D01*
G01X1449829Y36678D02*
X1452329D01*
X1451829Y36178D01*
G01X1449829D02*
Y37178D01*
G01Y40278D02*
X1452329D01*
X1450537Y38736D01*
Y40820D01*
G01X1462900Y26767D02*
X1465400D01*
Y27808D01*
X1465275Y28142D01*
X1465108Y28350D01*
X1464775Y28433D01*
X1464442Y28350D01*
X1464233Y28100D01*
X1464108Y27808D01*
Y26767D01*
G01Y27808D02*
X1462900Y28433D01*
G01Y30617D02*
X1463442Y30700D01*
X1463900Y30825D01*
X1464317Y30992D01*
X1464775Y31200D01*
X1465400Y31533D01*
Y29867D01*
G01X1464150Y34050D02*
Y34883D01*
X1463400D01*
X1463150Y34633D01*
X1462983Y34342D01*
X1462900Y33925D01*
X1462983Y33508D01*
X1463150Y33217D01*
X1463400Y32967D01*
X1463692Y32800D01*
X1464025Y32717D01*
X1464317D01*
X1464567Y32800D01*
X1464858Y32967D01*
X1465108Y33217D01*
X1465275Y33467D01*
X1465400Y33800D01*
Y34092D01*
X1465317Y34425D01*
X1465150Y34675D01*
G01X1464983Y36108D02*
X1465233Y36358D01*
X1465358Y36650D01*
X1465400Y36983D01*
X1465317Y37400D01*
X1465108Y37692D01*
X1464858Y37775D01*
X1464608Y37733D01*
X1464400Y37567D01*
X1463983Y36733D01*
X1463692Y36358D01*
X1463275Y36108D01*
X1462900Y36025D01*
Y37775D01*
G01X1463942Y39208D02*
X1464233Y39500D01*
X1464400Y39750D01*
X1464483Y40083D01*
X1464400Y40375D01*
X1464233Y40583D01*
X1463983Y40750D01*
X1463692Y40792D01*
X1463442Y40750D01*
X1463192Y40583D01*
X1462983Y40333D01*
X1462900Y40042D01*
X1462983Y39708D01*
X1463233Y39417D01*
X1463608Y39250D01*
X1464025Y39208D01*
X1464567Y39292D01*
X1464858Y39417D01*
X1465150Y39625D01*
X1465358Y39917D01*
X1465400Y40208D01*
X1465317Y40500D01*
X1465108Y40708D01*
G01X1443800Y21267D02*
X1446300D01*
Y22308D01*
X1446175Y22642D01*
X1446008Y22850D01*
X1445675Y22933D01*
X1445342Y22850D01*
X1445133Y22600D01*
X1445008Y22308D01*
Y21267D01*
G01Y22308D02*
X1443800Y22933D01*
G01Y25117D02*
X1444342Y25200D01*
X1444800Y25325D01*
X1445217Y25492D01*
X1445675Y25700D01*
X1446300Y26033D01*
Y24367D01*
G01X1445050Y28550D02*
Y29383D01*
X1444300D01*
X1444050Y29133D01*
X1443883Y28842D01*
X1443800Y28425D01*
X1443883Y28008D01*
X1444050Y27717D01*
X1444300Y27467D01*
X1444592Y27300D01*
X1444925Y27217D01*
X1445217D01*
X1445467Y27300D01*
X1445758Y27467D01*
X1446008Y27717D01*
X1446175Y27967D01*
X1446300Y28300D01*
Y28592D01*
X1446217Y28925D01*
X1446050Y29175D01*
G01X1445883Y30608D02*
X1446133Y30858D01*
X1446258Y31150D01*
X1446300Y31483D01*
X1446217Y31900D01*
X1446008Y32192D01*
X1445758Y32275D01*
X1445508Y32233D01*
X1445300Y32067D01*
X1444883Y31233D01*
X1444592Y30858D01*
X1444175Y30608D01*
X1443800Y30525D01*
Y32275D01*
G01X1444092Y33792D02*
X1443883Y34083D01*
X1443800Y34417D01*
X1443883Y34750D01*
X1444133Y35042D01*
X1444508Y35250D01*
X1444883Y35333D01*
X1445342D01*
X1445717Y35250D01*
X1446050Y35042D01*
X1446217Y34792D01*
X1446300Y34500D01*
X1446217Y34167D01*
X1446050Y33917D01*
X1445800Y33750D01*
X1445467Y33667D01*
X1445175Y33750D01*
X1444883Y33958D01*
X1444717Y34208D01*
X1444675Y34500D01*
X1444758Y34833D01*
X1444967Y35083D01*
X1445342Y35333D01*
G01X1417400Y22267D02*
X1419900D01*
Y23308D01*
X1419775Y23642D01*
X1419608Y23850D01*
X1419275Y23933D01*
X1418942Y23850D01*
X1418733Y23600D01*
X1418608Y23308D01*
Y22267D01*
G01Y23308D02*
X1417400Y23933D01*
G01Y26200D02*
X1417442Y26492D01*
X1417567Y26825D01*
X1417775Y27033D01*
X1418067Y27117D01*
X1418358Y27033D01*
X1418608Y26783D01*
X1418733Y26408D01*
Y25992D01*
X1418817Y25742D01*
X1419025Y25533D01*
X1419317Y25450D01*
X1419608Y25575D01*
X1419817Y25867D01*
X1419900Y26200D01*
X1419817Y26533D01*
X1419608Y26825D01*
X1419317Y26950D01*
X1419025Y26867D01*
X1418817Y26658D01*
X1418733Y26408D01*
Y25992D01*
X1418608Y25617D01*
X1418358Y25367D01*
X1418067Y25283D01*
X1417775Y25367D01*
X1417567Y25575D01*
X1417442Y25908D01*
X1417400Y26200D01*
G01X1419900Y28050D02*
X1417400Y28633D01*
X1419900Y29300D01*
X1417400Y29967D01*
X1419900Y30550D01*
G01X1417400Y32400D02*
X1419900D01*
X1419400Y31900D01*
G01X1417400D02*
Y32900D01*
G01X1419900Y35500D02*
X1419817Y35167D01*
X1419608Y34917D01*
X1419358Y34750D01*
X1419025Y34625D01*
X1418650Y34583D01*
X1418275Y34625D01*
X1417942Y34750D01*
X1417692Y34917D01*
X1417483Y35167D01*
X1417400Y35500D01*
X1417483Y35833D01*
X1417692Y36083D01*
X1417942Y36250D01*
X1418275Y36375D01*
X1418650Y36417D01*
X1419025Y36375D01*
X1419358Y36250D01*
X1419608Y36083D01*
X1419817Y35833D01*
X1419900Y35500D01*
G01X1410700Y22367D02*
X1413200D01*
Y23408D01*
X1413075Y23742D01*
X1412908Y23950D01*
X1412575Y24033D01*
X1412242Y23950D01*
X1412033Y23700D01*
X1411908Y23408D01*
Y22367D01*
G01Y23408D02*
X1410700Y24033D01*
G01Y26300D02*
X1410742Y26592D01*
X1410867Y26925D01*
X1411075Y27133D01*
X1411367Y27217D01*
X1411658Y27133D01*
X1411908Y26883D01*
X1412033Y26508D01*
Y26092D01*
X1412117Y25842D01*
X1412325Y25633D01*
X1412617Y25550D01*
X1412908Y25675D01*
X1413117Y25967D01*
X1413200Y26300D01*
X1413117Y26633D01*
X1412908Y26925D01*
X1412617Y27050D01*
X1412325Y26967D01*
X1412117Y26758D01*
X1412033Y26508D01*
Y26092D01*
X1411908Y25717D01*
X1411658Y25467D01*
X1411367Y25383D01*
X1411075Y25467D01*
X1410867Y25675D01*
X1410742Y26008D01*
X1410700Y26300D01*
G01X1413200Y28150D02*
X1410700Y28733D01*
X1413200Y29400D01*
X1410700Y30067D01*
X1413200Y30650D01*
G01X1410700Y32500D02*
X1413200D01*
X1412700Y32000D01*
G01X1410700D02*
Y33000D01*
G01Y35600D02*
X1413200D01*
X1412700Y35100D01*
G01X1410700D02*
Y36100D01*
G01X1407200Y22367D02*
X1409700D01*
Y23408D01*
X1409575Y23742D01*
X1409408Y23950D01*
X1409075Y24033D01*
X1408742Y23950D01*
X1408533Y23700D01*
X1408408Y23408D01*
Y22367D01*
G01Y23408D02*
X1407200Y24033D01*
G01Y26300D02*
X1407242Y26592D01*
X1407367Y26925D01*
X1407575Y27133D01*
X1407867Y27217D01*
X1408158Y27133D01*
X1408408Y26883D01*
X1408533Y26508D01*
Y26092D01*
X1408617Y25842D01*
X1408825Y25633D01*
X1409117Y25550D01*
X1409408Y25675D01*
X1409617Y25967D01*
X1409700Y26300D01*
X1409617Y26633D01*
X1409408Y26925D01*
X1409117Y27050D01*
X1408825Y26967D01*
X1408617Y26758D01*
X1408533Y26508D01*
Y26092D01*
X1408408Y25717D01*
X1408158Y25467D01*
X1407867Y25383D01*
X1407575Y25467D01*
X1407367Y25675D01*
X1407242Y26008D01*
X1407200Y26300D01*
G01X1409700Y28150D02*
X1407200Y28733D01*
X1409700Y29400D01*
X1407200Y30067D01*
X1409700Y30650D01*
G01X1407200Y32500D02*
X1409700D01*
X1409200Y32000D01*
G01X1407200D02*
Y33000D01*
G01X1409283Y34808D02*
X1409533Y35058D01*
X1409658Y35350D01*
X1409700Y35683D01*
X1409617Y36100D01*
X1409408Y36392D01*
X1409158Y36475D01*
X1408908Y36433D01*
X1408700Y36267D01*
X1408283Y35433D01*
X1407992Y35058D01*
X1407575Y34808D01*
X1407200Y34725D01*
Y36475D01*
G01X1439058Y2003D02*
X1438828Y2313D01*
X1438560Y2468D01*
X1438253Y2520D01*
X1437870Y2417D01*
X1437602Y2158D01*
X1437525Y1848D01*
X1437563Y1538D01*
X1437717Y1280D01*
X1438483Y763D01*
X1438828Y402D01*
X1439058Y-115D01*
X1439135Y-580D01*
X1437525D01*
G01X1437600Y-15450D02*
X1434500D01*
X1435120Y-14990D01*
G01X1437600D02*
Y-15910D01*
G01X1435017Y-17822D02*
X1434707Y-18052D01*
X1434552Y-18320D01*
X1434500Y-18627D01*
X1434603Y-19010D01*
X1434862Y-19278D01*
X1435172Y-19355D01*
X1435482Y-19317D01*
X1435740Y-19163D01*
X1436257Y-18397D01*
X1436618Y-18052D01*
X1437135Y-17822D01*
X1437600Y-17745D01*
Y-19355D01*
G01X1413000Y62500D02*
Y85075D01*
G01X1431000Y62500D02*
Y85072D01*
G01Y62500D02*
X1428305D01*
G01X1413000D02*
X1415698D01*
G01X1415700Y97864D02*
X1412138D01*
Y85068D01*
X1415700D01*
G01X1428300Y97864D02*
X1432091D01*
Y85068D01*
X1428300D01*
G01X1446800Y97864D02*
X1450591D01*
Y85068D01*
X1446800D01*
G01X1434200Y97864D02*
X1430638D01*
Y85068D01*
X1434200D01*
G01X1431500Y62500D02*
X1434198D01*
G01X1449500D02*
X1446805D01*
G01X1449500D02*
Y85072D01*
G01X1431500Y62500D02*
Y85075D01*
G01X1463334Y180610D02*
Y166315D01*
X1459000D01*
Y154877D01*
X1459782D01*
G01X1459000D02*
X1479209D01*
G03X1479309Y154977I0J100D01*
G01Y164500D01*
X1482600D01*
Y172500D01*
X1486300D01*
Y181300D01*
X1491500D01*
Y181000D01*
G01X1460667Y112467D02*
X1463167D01*
Y113508D01*
X1463042Y113842D01*
X1462875Y114050D01*
X1462542Y114133D01*
X1462209Y114050D01*
X1462000Y113800D01*
X1461875Y113508D01*
Y112467D01*
G01Y113508D02*
X1460667Y114133D01*
G01Y115442D02*
X1463167D01*
X1460667Y117358D01*
X1463167D01*
G01X1460667Y119500D02*
X1460709Y119792D01*
X1460834Y120125D01*
X1461042Y120333D01*
X1461334Y120417D01*
X1461625Y120333D01*
X1461875Y120083D01*
X1462000Y119708D01*
Y119292D01*
X1462084Y119042D01*
X1462292Y118833D01*
X1462584Y118750D01*
X1462875Y118875D01*
X1463084Y119167D01*
X1463167Y119500D01*
X1463084Y119833D01*
X1462875Y120125D01*
X1462584Y120250D01*
X1462292Y120167D01*
X1462084Y119958D01*
X1462000Y119708D01*
Y119292D01*
X1461875Y118917D01*
X1461625Y118667D01*
X1461334Y118583D01*
X1461042Y118667D01*
X1460834Y118875D01*
X1460709Y119208D01*
X1460667Y119500D01*
G01Y121808D02*
X1463167D01*
Y123392D01*
G01X1461959Y122808D02*
Y121808D01*
G01X1462750Y124908D02*
X1463000Y125158D01*
X1463125Y125450D01*
X1463167Y125783D01*
X1463084Y126200D01*
X1462875Y126492D01*
X1462625Y126575D01*
X1462375Y126533D01*
X1462167Y126367D01*
X1461750Y125533D01*
X1461459Y125158D01*
X1461042Y124908D01*
X1460667Y124825D01*
Y126575D01*
G01X1428267Y141467D02*
X1430767D01*
Y142508D01*
X1430642Y142842D01*
X1430475Y143050D01*
X1430142Y143133D01*
X1429809Y143050D01*
X1429600Y142800D01*
X1429475Y142508D01*
Y141467D01*
G01Y142508D02*
X1428267Y143133D01*
G01Y145400D02*
X1428309Y145692D01*
X1428434Y146025D01*
X1428642Y146233D01*
X1428934Y146317D01*
X1429225Y146233D01*
X1429475Y145983D01*
X1429600Y145608D01*
Y145192D01*
X1429684Y144942D01*
X1429892Y144733D01*
X1430184Y144650D01*
X1430475Y144775D01*
X1430684Y145067D01*
X1430767Y145400D01*
X1430684Y145733D01*
X1430475Y146025D01*
X1430184Y146150D01*
X1429892Y146067D01*
X1429684Y145858D01*
X1429600Y145608D01*
Y145192D01*
X1429475Y144817D01*
X1429225Y144567D01*
X1428934Y144483D01*
X1428642Y144567D01*
X1428434Y144775D01*
X1428309Y145108D01*
X1428267Y145400D01*
G01Y147708D02*
X1430767D01*
Y149292D01*
G01X1429559Y148708D02*
Y147708D01*
G01X1428267Y151600D02*
X1430767D01*
X1430267Y151100D01*
G01X1428267D02*
Y152100D01*
G01X1429309Y153908D02*
X1429600Y154200D01*
X1429767Y154450D01*
X1429850Y154783D01*
X1429767Y155075D01*
X1429600Y155283D01*
X1429350Y155450D01*
X1429059Y155492D01*
X1428809Y155450D01*
X1428559Y155283D01*
X1428350Y155033D01*
X1428267Y154742D01*
X1428350Y154408D01*
X1428600Y154117D01*
X1428975Y153950D01*
X1429392Y153908D01*
X1429934Y153992D01*
X1430225Y154117D01*
X1430517Y154325D01*
X1430725Y154617D01*
X1430767Y154908D01*
X1430684Y155200D01*
X1430475Y155408D01*
G01X1447267Y122267D02*
X1449767D01*
Y123308D01*
X1449642Y123642D01*
X1449475Y123850D01*
X1449142Y123933D01*
X1448809Y123850D01*
X1448600Y123600D01*
X1448475Y123308D01*
Y122267D01*
G01Y123308D02*
X1447267Y123933D01*
G01Y126200D02*
X1447309Y126492D01*
X1447434Y126825D01*
X1447642Y127033D01*
X1447934Y127117D01*
X1448225Y127033D01*
X1448475Y126783D01*
X1448600Y126408D01*
Y125992D01*
X1448684Y125742D01*
X1448892Y125533D01*
X1449184Y125450D01*
X1449475Y125575D01*
X1449684Y125867D01*
X1449767Y126200D01*
X1449684Y126533D01*
X1449475Y126825D01*
X1449184Y126950D01*
X1448892Y126867D01*
X1448684Y126658D01*
X1448600Y126408D01*
Y125992D01*
X1448475Y125617D01*
X1448225Y125367D01*
X1447934Y125283D01*
X1447642Y125367D01*
X1447434Y125575D01*
X1447309Y125908D01*
X1447267Y126200D01*
G01Y128508D02*
X1449767D01*
Y130092D01*
G01X1448559Y129508D02*
Y128508D01*
G01X1447267Y132400D02*
X1449767D01*
X1449267Y131900D01*
G01X1447267D02*
Y132900D01*
G01X1449350Y134708D02*
X1449600Y134958D01*
X1449725Y135250D01*
X1449767Y135583D01*
X1449684Y136000D01*
X1449475Y136292D01*
X1449225Y136375D01*
X1448975Y136333D01*
X1448767Y136167D01*
X1448350Y135333D01*
X1448059Y134958D01*
X1447642Y134708D01*
X1447267Y134625D01*
Y136375D01*
G01X1442467Y129867D02*
X1444967D01*
Y130908D01*
X1444842Y131242D01*
X1444675Y131450D01*
X1444342Y131533D01*
X1444009Y131450D01*
X1443800Y131200D01*
X1443675Y130908D01*
Y129867D01*
G01Y130908D02*
X1442467Y131533D01*
G01Y133800D02*
X1442509Y134092D01*
X1442634Y134425D01*
X1442842Y134633D01*
X1443134Y134717D01*
X1443425Y134633D01*
X1443675Y134383D01*
X1443800Y134008D01*
Y133592D01*
X1443884Y133342D01*
X1444092Y133133D01*
X1444384Y133050D01*
X1444675Y133175D01*
X1444884Y133467D01*
X1444967Y133800D01*
X1444884Y134133D01*
X1444675Y134425D01*
X1444384Y134550D01*
X1444092Y134467D01*
X1443884Y134258D01*
X1443800Y134008D01*
Y133592D01*
X1443675Y133217D01*
X1443425Y132967D01*
X1443134Y132883D01*
X1442842Y132967D01*
X1442634Y133175D01*
X1442509Y133508D01*
X1442467Y133800D01*
G01Y136108D02*
X1444967D01*
Y137692D01*
G01X1443759Y137108D02*
Y136108D01*
G01X1442467Y140000D02*
X1444967D01*
X1444467Y139500D01*
G01X1442467D02*
Y140500D01*
G01X1442967Y142183D02*
X1442675Y142433D01*
X1442509Y142767D01*
X1442467Y143142D01*
X1442509Y143475D01*
X1442717Y143808D01*
X1442967Y144017D01*
X1443217Y144058D01*
X1443509Y143975D01*
X1443717Y143683D01*
X1443800Y143392D01*
Y143017D01*
G01Y143392D02*
X1443925Y143642D01*
X1444134Y143850D01*
X1444384Y143933D01*
X1444634Y143850D01*
X1444842Y143642D01*
X1444967Y143267D01*
X1444925Y142892D01*
X1444759Y142517D01*
G01X1424900Y141617D02*
X1427400D01*
Y142658D01*
X1427275Y142992D01*
X1427108Y143200D01*
X1426775Y143283D01*
X1426442Y143200D01*
X1426233Y142950D01*
X1426108Y142658D01*
Y141617D01*
G01Y142658D02*
X1424900Y143283D01*
G01Y145550D02*
X1424942Y145842D01*
X1425067Y146175D01*
X1425275Y146383D01*
X1425567Y146467D01*
X1425858Y146383D01*
X1426108Y146133D01*
X1426233Y145758D01*
Y145342D01*
X1426317Y145092D01*
X1426525Y144883D01*
X1426817Y144800D01*
X1427108Y144925D01*
X1427317Y145217D01*
X1427400Y145550D01*
X1427317Y145883D01*
X1427108Y146175D01*
X1426817Y146300D01*
X1426525Y146217D01*
X1426317Y146008D01*
X1426233Y145758D01*
Y145342D01*
X1426108Y144967D01*
X1425858Y144717D01*
X1425567Y144633D01*
X1425275Y144717D01*
X1425067Y144925D01*
X1424942Y145258D01*
X1424900Y145550D01*
G01Y147858D02*
X1427400D01*
Y149442D01*
G01X1426192Y148858D02*
Y147858D01*
G01X1424900Y151750D02*
X1427400D01*
X1426900Y151250D01*
G01X1424900D02*
Y152250D01*
G01Y155350D02*
X1427400D01*
X1425608Y153808D01*
Y155892D01*
G01X1468752Y139521D02*
X1469002Y139646D01*
X1469294Y139729D01*
X1469627D01*
X1470002Y139604D01*
X1470294Y139396D01*
X1470502Y139146D01*
X1470669Y138729D01*
X1470711Y138354D01*
X1470627Y137979D01*
X1470502Y137729D01*
X1470252Y137479D01*
X1469961Y137312D01*
X1469669Y137229D01*
X1469377D01*
X1469086Y137312D01*
X1468836Y137437D01*
X1468627Y137604D01*
G01X1466652Y137229D02*
X1466569Y137771D01*
X1466444Y138229D01*
X1466277Y138646D01*
X1466069Y139104D01*
X1465736Y139729D01*
X1467402D01*
G01X1462636Y137229D02*
X1464302D01*
Y139729D01*
X1462636D01*
G01X1463302Y138521D02*
X1464302D01*
G01X1461286Y137729D02*
X1461036Y137437D01*
X1460702Y137271D01*
X1460327Y137229D01*
X1459994Y137271D01*
X1459661Y137479D01*
X1459452Y137729D01*
X1459411Y137979D01*
X1459494Y138271D01*
X1459786Y138479D01*
X1460077Y138562D01*
X1460452D01*
G01X1460077D02*
X1459827Y138687D01*
X1459619Y138896D01*
X1459536Y139146D01*
X1459619Y139396D01*
X1459827Y139604D01*
X1460202Y139729D01*
X1460577Y139687D01*
X1460952Y139521D01*
G01X1419483Y146441D02*
X1419608Y146191D01*
X1419691Y145899D01*
Y145566D01*
X1419566Y145191D01*
X1419358Y144899D01*
X1419108Y144691D01*
X1418691Y144524D01*
X1418316Y144482D01*
X1417941Y144566D01*
X1417691Y144691D01*
X1417441Y144941D01*
X1417274Y145232D01*
X1417191Y145524D01*
Y145816D01*
X1417274Y146107D01*
X1417399Y146357D01*
X1417566Y146566D01*
G01X1417191Y148624D02*
X1417233Y148916D01*
X1417358Y149249D01*
X1417566Y149457D01*
X1417858Y149541D01*
X1418149Y149457D01*
X1418399Y149207D01*
X1418524Y148832D01*
Y148416D01*
X1418608Y148166D01*
X1418816Y147957D01*
X1419108Y147874D01*
X1419399Y147999D01*
X1419608Y148291D01*
X1419691Y148624D01*
X1419608Y148957D01*
X1419399Y149249D01*
X1419108Y149374D01*
X1418816Y149291D01*
X1418608Y149082D01*
X1418524Y148832D01*
Y148416D01*
X1418399Y148041D01*
X1418149Y147791D01*
X1417858Y147707D01*
X1417566Y147791D01*
X1417358Y147999D01*
X1417233Y148332D01*
X1417191Y148624D01*
G01Y150932D02*
X1419691D01*
Y152516D01*
G01X1418483Y151932D02*
Y150932D01*
G01X1417191Y155324D02*
X1419691D01*
X1417899Y153782D01*
Y155866D01*
G01X1423483Y146441D02*
X1423608Y146191D01*
X1423691Y145899D01*
Y145566D01*
X1423566Y145191D01*
X1423358Y144899D01*
X1423108Y144691D01*
X1422691Y144524D01*
X1422316Y144482D01*
X1421941Y144566D01*
X1421691Y144691D01*
X1421441Y144941D01*
X1421274Y145232D01*
X1421191Y145524D01*
Y145816D01*
X1421274Y146107D01*
X1421399Y146357D01*
X1421566Y146566D01*
G01X1421191Y148624D02*
X1421233Y148916D01*
X1421358Y149249D01*
X1421566Y149457D01*
X1421858Y149541D01*
X1422149Y149457D01*
X1422399Y149207D01*
X1422524Y148832D01*
Y148416D01*
X1422608Y148166D01*
X1422816Y147957D01*
X1423108Y147874D01*
X1423399Y147999D01*
X1423608Y148291D01*
X1423691Y148624D01*
X1423608Y148957D01*
X1423399Y149249D01*
X1423108Y149374D01*
X1422816Y149291D01*
X1422608Y149082D01*
X1422524Y148832D01*
Y148416D01*
X1422399Y148041D01*
X1422149Y147791D01*
X1421858Y147707D01*
X1421566Y147791D01*
X1421358Y147999D01*
X1421233Y148332D01*
X1421191Y148624D01*
G01Y150932D02*
X1423691D01*
Y152516D01*
G01X1422483Y151932D02*
Y150932D01*
G01X1421566Y153907D02*
X1421358Y154157D01*
X1421233Y154449D01*
X1421191Y154824D01*
X1421274Y155199D01*
X1421441Y155491D01*
X1421733Y155699D01*
X1422066Y155741D01*
X1422399Y155657D01*
X1422608Y155449D01*
X1422774Y155157D01*
X1422816Y154866D01*
X1422774Y154574D01*
X1422608Y154199D01*
X1423691Y154324D01*
Y155449D01*
G01X1423392Y102017D02*
X1423517Y101767D01*
X1423600Y101475D01*
Y101142D01*
X1423475Y100767D01*
X1423267Y100475D01*
X1423017Y100267D01*
X1422600Y100100D01*
X1422225Y100058D01*
X1421850Y100142D01*
X1421600Y100267D01*
X1421350Y100517D01*
X1421183Y100808D01*
X1421100Y101100D01*
Y101392D01*
X1421183Y101683D01*
X1421308Y101933D01*
X1421475Y102142D01*
G01X1421600Y103283D02*
X1421308Y103533D01*
X1421142Y103867D01*
X1421100Y104242D01*
X1421142Y104575D01*
X1421350Y104908D01*
X1421600Y105117D01*
X1421850Y105158D01*
X1422142Y105075D01*
X1422350Y104783D01*
X1422433Y104492D01*
Y104117D01*
G01Y104492D02*
X1422558Y104742D01*
X1422767Y104950D01*
X1423017Y105033D01*
X1423267Y104950D01*
X1423475Y104742D01*
X1423600Y104367D01*
X1423558Y103992D01*
X1423392Y103617D01*
G01X1423600Y107300D02*
X1421100D01*
G01X1423600Y106342D02*
Y108258D01*
G01X1421100Y110400D02*
X1423600D01*
X1423100Y109900D01*
G01X1421100D02*
Y110900D01*
G01X1421475Y112583D02*
X1421267Y112833D01*
X1421142Y113125D01*
X1421100Y113500D01*
X1421183Y113875D01*
X1421350Y114167D01*
X1421642Y114375D01*
X1421975Y114417D01*
X1422308Y114333D01*
X1422517Y114125D01*
X1422683Y113833D01*
X1422725Y113542D01*
X1422683Y113250D01*
X1422517Y112875D01*
X1423600Y113000D01*
Y114125D01*
G01X1441892Y102017D02*
X1442017Y101767D01*
X1442100Y101475D01*
Y101142D01*
X1441975Y100767D01*
X1441767Y100475D01*
X1441517Y100267D01*
X1441100Y100100D01*
X1440725Y100058D01*
X1440350Y100142D01*
X1440100Y100267D01*
X1439850Y100517D01*
X1439683Y100808D01*
X1439600Y101100D01*
Y101392D01*
X1439683Y101683D01*
X1439808Y101933D01*
X1439975Y102142D01*
G01X1440100Y103283D02*
X1439808Y103533D01*
X1439642Y103867D01*
X1439600Y104242D01*
X1439642Y104575D01*
X1439850Y104908D01*
X1440100Y105117D01*
X1440350Y105158D01*
X1440642Y105075D01*
X1440850Y104783D01*
X1440933Y104492D01*
Y104117D01*
G01Y104492D02*
X1441058Y104742D01*
X1441267Y104950D01*
X1441517Y105033D01*
X1441767Y104950D01*
X1441975Y104742D01*
X1442100Y104367D01*
X1442058Y103992D01*
X1441892Y103617D01*
G01X1442100Y107300D02*
X1439600D01*
G01X1442100Y106342D02*
Y108258D01*
G01X1439600Y110400D02*
X1442100D01*
X1441600Y109900D01*
G01X1439600D02*
Y110900D01*
G01X1440100Y112583D02*
X1439808Y112833D01*
X1439642Y113167D01*
X1439600Y113542D01*
X1439642Y113875D01*
X1439850Y114208D01*
X1440100Y114417D01*
X1440350Y114458D01*
X1440642Y114375D01*
X1440850Y114083D01*
X1440933Y113792D01*
Y113417D01*
G01Y113792D02*
X1441058Y114042D01*
X1441267Y114250D01*
X1441517Y114333D01*
X1441767Y114250D01*
X1441975Y114042D01*
X1442100Y113667D01*
X1442058Y113292D01*
X1441892Y112917D01*
G01X1421092Y121767D02*
X1421217Y121517D01*
X1421300Y121225D01*
Y120892D01*
X1421175Y120517D01*
X1420967Y120225D01*
X1420717Y120017D01*
X1420300Y119850D01*
X1419925Y119808D01*
X1419550Y119892D01*
X1419300Y120017D01*
X1419050Y120267D01*
X1418883Y120558D01*
X1418800Y120850D01*
Y121142D01*
X1418883Y121433D01*
X1419008Y121683D01*
X1419175Y121892D01*
G01X1419300Y123033D02*
X1419008Y123283D01*
X1418842Y123617D01*
X1418800Y123992D01*
X1418842Y124325D01*
X1419050Y124658D01*
X1419300Y124867D01*
X1419550Y124908D01*
X1419842Y124825D01*
X1420050Y124533D01*
X1420133Y124242D01*
Y123867D01*
G01Y124242D02*
X1420258Y124492D01*
X1420467Y124700D01*
X1420717Y124783D01*
X1420967Y124700D01*
X1421175Y124492D01*
X1421300Y124117D01*
X1421258Y123742D01*
X1421092Y123367D01*
G01X1421300Y127050D02*
X1418800D01*
G01X1421300Y126092D02*
Y128008D01*
G01X1419842Y129358D02*
X1420133Y129650D01*
X1420300Y129900D01*
X1420383Y130233D01*
X1420300Y130525D01*
X1420133Y130733D01*
X1419883Y130900D01*
X1419592Y130942D01*
X1419342Y130900D01*
X1419092Y130733D01*
X1418883Y130483D01*
X1418800Y130192D01*
X1418883Y129858D01*
X1419133Y129567D01*
X1419508Y129400D01*
X1419925Y129358D01*
X1420467Y129442D01*
X1420758Y129567D01*
X1421050Y129775D01*
X1421258Y130067D01*
X1421300Y130358D01*
X1421217Y130650D01*
X1421008Y130858D01*
G01X1413300Y139364D02*
X1417091D01*
Y126568D01*
X1413300D01*
G01X1416000Y104000D02*
X1413305D01*
G01X1416000D02*
Y126572D01*
G01X1460500Y96267D02*
X1463000D01*
Y97308D01*
X1462875Y97642D01*
X1462708Y97850D01*
X1462375Y97933D01*
X1462042Y97850D01*
X1461833Y97600D01*
X1461708Y97308D01*
Y96267D01*
G01Y97308D02*
X1460500Y97933D01*
G01Y99242D02*
X1463000D01*
X1460500Y101158D01*
X1463000D01*
G01X1460500Y103300D02*
X1460542Y103592D01*
X1460667Y103925D01*
X1460875Y104133D01*
X1461167Y104217D01*
X1461458Y104133D01*
X1461708Y103883D01*
X1461833Y103508D01*
Y103092D01*
X1461917Y102842D01*
X1462125Y102633D01*
X1462417Y102550D01*
X1462708Y102675D01*
X1462917Y102967D01*
X1463000Y103300D01*
X1462917Y103633D01*
X1462708Y103925D01*
X1462417Y104050D01*
X1462125Y103967D01*
X1461917Y103758D01*
X1461833Y103508D01*
Y103092D01*
X1461708Y102717D01*
X1461458Y102467D01*
X1461167Y102383D01*
X1460875Y102467D01*
X1460667Y102675D01*
X1460542Y103008D01*
X1460500Y103300D01*
G01Y105608D02*
X1463000D01*
Y107192D01*
G01X1461792Y106608D02*
Y105608D01*
G01X1461542Y108708D02*
X1461833Y109000D01*
X1462000Y109250D01*
X1462083Y109583D01*
X1462000Y109875D01*
X1461833Y110083D01*
X1461583Y110250D01*
X1461292Y110292D01*
X1461042Y110250D01*
X1460792Y110083D01*
X1460583Y109833D01*
X1460500Y109542D01*
X1460583Y109208D01*
X1460833Y108917D01*
X1461208Y108750D01*
X1461625Y108708D01*
X1462167Y108792D01*
X1462458Y108917D01*
X1462750Y109125D01*
X1462958Y109417D01*
X1463000Y109708D01*
X1462917Y110000D01*
X1462708Y110208D01*
G01X1455000Y106700D02*
X1459000D01*
Y99300D01*
G01X1465300Y196967D02*
X1462633D01*
Y194867D01*
X1463433Y194167D01*
X1464367Y193700D01*
X1465700Y193467D01*
X1467033Y193700D01*
X1467967Y194167D01*
X1468767Y194867D01*
X1469300Y195684D01*
X1469567Y196617D01*
Y197434D01*
X1469300Y198134D01*
X1468767Y198950D01*
X1467967Y199650D01*
X1467167Y200117D01*
X1466100Y200467D01*
X1465167D01*
X1464100Y200234D01*
X1463300Y199767D01*
G01X1465039Y239092D02*
Y217959D01*
X1461736D01*
Y194090D01*
X1460373D01*
Y186873D01*
G01X1458533Y193667D02*
Y196167D01*
X1457492D01*
X1457158Y196042D01*
X1456950Y195875D01*
X1456867Y195542D01*
X1456950Y195209D01*
X1457200Y195000D01*
X1457492Y194875D01*
X1458533D01*
G01X1457492D02*
X1456867Y193667D01*
G01X1455392Y195750D02*
X1455142Y196000D01*
X1454850Y196125D01*
X1454517Y196167D01*
X1454100Y196084D01*
X1453808Y195875D01*
X1453725Y195625D01*
X1453767Y195375D01*
X1453933Y195167D01*
X1454767Y194750D01*
X1455142Y194459D01*
X1455392Y194042D01*
X1455475Y193667D01*
X1453725D01*
G01X1451500Y196167D02*
Y193667D01*
G01X1452458Y196167D02*
X1450542D01*
G01X1449317Y194042D02*
X1449067Y193834D01*
X1448775Y193709D01*
X1448400Y193667D01*
X1448025Y193750D01*
X1447733Y193917D01*
X1447525Y194209D01*
X1447483Y194542D01*
X1447567Y194875D01*
X1447775Y195084D01*
X1448067Y195250D01*
X1448358Y195292D01*
X1448650Y195250D01*
X1449025Y195084D01*
X1448900Y196167D01*
X1447775D01*
G01X1445300D02*
X1445633Y196084D01*
X1445883Y195875D01*
X1446050Y195625D01*
X1446175Y195292D01*
X1446217Y194917D01*
X1446175Y194542D01*
X1446050Y194209D01*
X1445883Y193959D01*
X1445633Y193750D01*
X1445300Y193667D01*
X1444967Y193750D01*
X1444717Y193959D01*
X1444550Y194209D01*
X1444425Y194542D01*
X1444383Y194917D01*
X1444425Y195292D01*
X1444550Y195625D01*
X1444717Y195875D01*
X1444967Y196084D01*
X1445300Y196167D01*
G01X1438861Y194551D02*
X1439111Y194676D01*
X1439403Y194759D01*
X1439736D01*
X1440111Y194634D01*
X1440403Y194426D01*
X1440611Y194176D01*
X1440778Y193759D01*
X1440820Y193384D01*
X1440736Y193009D01*
X1440611Y192759D01*
X1440361Y192509D01*
X1440070Y192342D01*
X1439778Y192259D01*
X1439486D01*
X1439195Y192342D01*
X1438945Y192467D01*
X1438736Y192634D01*
G01X1437470Y194342D02*
X1437220Y194592D01*
X1436928Y194717D01*
X1436595Y194759D01*
X1436178Y194676D01*
X1435886Y194467D01*
X1435803Y194217D01*
X1435845Y193967D01*
X1436011Y193759D01*
X1436845Y193342D01*
X1437220Y193051D01*
X1437470Y192634D01*
X1437553Y192259D01*
X1435803D01*
G01X1433578Y194759D02*
Y192259D01*
G01X1434536Y194759D02*
X1432620D01*
G01X1431395Y192759D02*
X1431145Y192467D01*
X1430811Y192301D01*
X1430436Y192259D01*
X1430103Y192301D01*
X1429770Y192509D01*
X1429561Y192759D01*
X1429520Y193009D01*
X1429603Y193301D01*
X1429895Y193509D01*
X1430186Y193592D01*
X1430561D01*
G01X1430186D02*
X1429936Y193717D01*
X1429728Y193926D01*
X1429645Y194176D01*
X1429728Y194426D01*
X1429936Y194634D01*
X1430311Y194759D01*
X1430686Y194717D01*
X1431061Y194551D01*
G01X1428295Y192759D02*
X1428045Y192467D01*
X1427711Y192301D01*
X1427336Y192259D01*
X1427003Y192301D01*
X1426670Y192509D01*
X1426461Y192759D01*
X1426420Y193009D01*
X1426503Y193301D01*
X1426795Y193509D01*
X1427086Y193592D01*
X1427461D01*
G01X1427086D02*
X1426836Y193717D01*
X1426628Y193926D01*
X1426545Y194176D01*
X1426628Y194426D01*
X1426836Y194634D01*
X1427211Y194759D01*
X1427586Y194717D01*
X1427961Y194551D01*
G01X1426058Y211237D02*
Y209445D01*
X1425891Y209070D01*
X1425558Y208820D01*
X1425141Y208737D01*
X1424724Y208820D01*
X1424391Y209070D01*
X1424224Y209445D01*
Y211237D01*
G01X1422958Y209237D02*
X1422708Y208945D01*
X1422374Y208779D01*
X1421999Y208737D01*
X1421666Y208779D01*
X1421333Y208987D01*
X1421124Y209237D01*
X1421083Y209487D01*
X1421166Y209779D01*
X1421458Y209987D01*
X1421749Y210070D01*
X1422124D01*
G01X1421749D02*
X1421499Y210195D01*
X1421291Y210404D01*
X1421208Y210654D01*
X1421291Y210904D01*
X1421499Y211112D01*
X1421874Y211237D01*
X1422249Y211195D01*
X1422624Y211029D01*
G01X1419774Y208737D02*
Y211237D01*
X1418774D01*
X1418441Y211112D01*
X1418191Y210820D01*
X1418108Y210487D01*
X1418191Y210154D01*
X1418399Y209904D01*
X1418774Y209779D01*
X1419774D01*
G01X1415841Y208737D02*
Y211237D01*
X1416341Y210737D01*
G01Y208737D02*
X1415341D01*
G01X1445750Y219700D02*
Y215250D01*
X1443250D01*
Y219700D01*
G01X1450200D02*
X1438800D01*
Y199360D01*
X1450200D01*
Y219700D01*
G01X1450887Y191193D02*
Y189401D01*
X1450720Y189026D01*
X1450387Y188776D01*
X1449970Y188693D01*
X1449553Y188776D01*
X1449220Y189026D01*
X1449053Y189401D01*
Y191193D01*
G01X1447662Y190776D02*
X1447412Y191026D01*
X1447120Y191151D01*
X1446787Y191193D01*
X1446370Y191110D01*
X1446078Y190901D01*
X1445995Y190651D01*
X1446037Y190401D01*
X1446203Y190193D01*
X1447037Y189776D01*
X1447412Y189485D01*
X1447662Y189068D01*
X1447745Y188693D01*
X1445995D01*
G01X1443770Y191193D02*
Y188693D01*
G01X1444728Y191193D02*
X1442812D01*
G01X1440170Y188693D02*
Y191193D01*
X1441712Y189401D01*
X1439628D01*
G01X1451788Y186727D02*
X1440388D01*
Y166387D01*
X1451788D01*
Y186727D01*
G01X1447338D02*
Y182277D01*
X1444838D01*
Y186727D01*
G01X1460115Y245834D02*
X1461448D01*
Y250159D01*
X1467165D01*
G01X1426000Y251467D02*
X1428500D01*
Y252508D01*
X1428375Y252842D01*
X1428208Y253050D01*
X1427875Y253133D01*
X1427542Y253050D01*
X1427333Y252800D01*
X1427208Y252508D01*
Y251467D01*
G01Y252508D02*
X1426000Y253133D01*
G01Y255400D02*
X1428500D01*
X1428000Y254900D01*
G01X1426000D02*
Y255900D01*
G01X1428500Y257250D02*
X1426000Y257833D01*
X1428500Y258500D01*
X1426000Y259167D01*
X1428500Y259750D01*
G01X1428083Y260808D02*
X1428333Y261058D01*
X1428458Y261350D01*
X1428500Y261683D01*
X1428417Y262100D01*
X1428208Y262392D01*
X1427958Y262475D01*
X1427708Y262433D01*
X1427500Y262267D01*
X1427083Y261433D01*
X1426792Y261058D01*
X1426375Y260808D01*
X1426000Y260725D01*
Y262475D01*
G01X1427042Y263908D02*
X1427333Y264200D01*
X1427500Y264450D01*
X1427583Y264783D01*
X1427500Y265075D01*
X1427333Y265283D01*
X1427083Y265450D01*
X1426792Y265492D01*
X1426542Y265450D01*
X1426292Y265283D01*
X1426083Y265033D01*
X1426000Y264742D01*
X1426083Y264408D01*
X1426333Y264117D01*
X1426708Y263950D01*
X1427125Y263908D01*
X1427667Y263992D01*
X1427958Y264117D01*
X1428250Y264325D01*
X1428458Y264617D01*
X1428500Y264908D01*
X1428417Y265200D01*
X1428208Y265408D01*
G01X1430000Y265017D02*
X1432500D01*
Y266058D01*
X1432375Y266392D01*
X1432208Y266600D01*
X1431875Y266683D01*
X1431542Y266600D01*
X1431333Y266350D01*
X1431208Y266058D01*
Y265017D01*
G01Y266058D02*
X1430000Y266683D01*
G01X1432083Y268158D02*
X1432333Y268408D01*
X1432458Y268700D01*
X1432500Y269033D01*
X1432417Y269450D01*
X1432208Y269742D01*
X1431958Y269825D01*
X1431708Y269783D01*
X1431500Y269617D01*
X1431083Y268783D01*
X1430792Y268408D01*
X1430375Y268158D01*
X1430000Y268075D01*
Y269825D01*
G01Y271217D02*
X1432500D01*
Y272258D01*
X1432375Y272592D01*
X1432208Y272800D01*
X1431875Y272883D01*
X1431542Y272800D01*
X1431333Y272550D01*
X1431208Y272258D01*
Y271217D01*
G01Y272258D02*
X1430000Y272883D01*
G01X1432083Y274358D02*
X1432333Y274608D01*
X1432458Y274900D01*
X1432500Y275233D01*
X1432417Y275650D01*
X1432208Y275942D01*
X1431958Y276025D01*
X1431708Y275983D01*
X1431500Y275817D01*
X1431083Y274983D01*
X1430792Y274608D01*
X1430375Y274358D01*
X1430000Y274275D01*
Y276025D01*
G01X1413765Y255994D02*
X1416265D01*
Y257035D01*
X1416140Y257369D01*
X1415973Y257577D01*
X1415640Y257660D01*
X1415307Y257577D01*
X1415098Y257327D01*
X1414973Y257035D01*
Y255994D01*
G01Y257035D02*
X1413765Y257660D01*
G01X1415848Y259135D02*
X1416098Y259385D01*
X1416223Y259677D01*
X1416265Y260010D01*
X1416182Y260427D01*
X1415973Y260719D01*
X1415723Y260802D01*
X1415473Y260760D01*
X1415265Y260594D01*
X1414848Y259760D01*
X1414557Y259385D01*
X1414140Y259135D01*
X1413765Y259052D01*
Y260802D01*
G01Y262194D02*
X1416265D01*
Y263235D01*
X1416140Y263569D01*
X1415973Y263777D01*
X1415640Y263860D01*
X1415307Y263777D01*
X1415098Y263527D01*
X1414973Y263235D01*
Y262194D01*
G01Y263235D02*
X1413765Y263860D01*
G01Y266044D02*
X1414307Y266127D01*
X1414765Y266252D01*
X1415182Y266419D01*
X1415640Y266627D01*
X1416265Y266960D01*
Y265294D01*
G01X1421765Y255994D02*
X1424265D01*
Y257035D01*
X1424140Y257369D01*
X1423973Y257577D01*
X1423640Y257660D01*
X1423307Y257577D01*
X1423098Y257327D01*
X1422973Y257035D01*
Y255994D01*
G01Y257035D02*
X1421765Y257660D01*
G01X1423848Y259135D02*
X1424098Y259385D01*
X1424223Y259677D01*
X1424265Y260010D01*
X1424182Y260427D01*
X1423973Y260719D01*
X1423723Y260802D01*
X1423473Y260760D01*
X1423265Y260594D01*
X1422848Y259760D01*
X1422557Y259385D01*
X1422140Y259135D01*
X1421765Y259052D01*
Y260802D01*
G01Y262194D02*
X1424265D01*
Y263235D01*
X1424140Y263569D01*
X1423973Y263777D01*
X1423640Y263860D01*
X1423307Y263777D01*
X1423098Y263527D01*
X1422973Y263235D01*
Y262194D01*
G01Y263235D02*
X1421765Y263860D01*
G01Y266127D02*
X1424265D01*
X1423765Y265627D01*
G01X1421765D02*
Y266627D01*
G01X1417765Y255994D02*
X1420265D01*
Y257035D01*
X1420140Y257369D01*
X1419973Y257577D01*
X1419640Y257660D01*
X1419307Y257577D01*
X1419098Y257327D01*
X1418973Y257035D01*
Y255994D01*
G01Y257035D02*
X1417765Y257660D01*
G01X1419848Y259135D02*
X1420098Y259385D01*
X1420223Y259677D01*
X1420265Y260010D01*
X1420182Y260427D01*
X1419973Y260719D01*
X1419723Y260802D01*
X1419473Y260760D01*
X1419265Y260594D01*
X1418848Y259760D01*
X1418557Y259385D01*
X1418140Y259135D01*
X1417765Y259052D01*
Y260802D01*
G01Y262194D02*
X1420265D01*
Y263235D01*
X1420140Y263569D01*
X1419973Y263777D01*
X1419640Y263860D01*
X1419307Y263777D01*
X1419098Y263527D01*
X1418973Y263235D01*
Y262194D01*
G01Y263235D02*
X1417765Y263860D01*
G01Y266627D02*
X1420265D01*
X1418473Y265085D01*
Y267169D01*
G01X1433500Y260467D02*
X1436000D01*
Y261508D01*
X1435875Y261842D01*
X1435708Y262050D01*
X1435375Y262133D01*
X1435042Y262050D01*
X1434833Y261800D01*
X1434708Y261508D01*
Y260467D01*
G01Y261508D02*
X1433500Y262133D01*
G01Y264317D02*
X1434042Y264400D01*
X1434500Y264525D01*
X1434917Y264692D01*
X1435375Y264900D01*
X1436000Y265233D01*
Y263567D01*
G01X1433500Y268333D02*
Y266667D01*
X1436000D01*
Y268333D01*
G01X1434792Y267667D02*
Y266667D01*
G01X1433500Y270600D02*
X1436000D01*
X1435500Y270100D01*
G01X1433500D02*
Y271100D01*
G01Y273700D02*
X1433542Y273992D01*
X1433667Y274325D01*
X1433875Y274533D01*
X1434167Y274617D01*
X1434458Y274533D01*
X1434708Y274283D01*
X1434833Y273908D01*
Y273492D01*
X1434917Y273242D01*
X1435125Y273033D01*
X1435417Y272950D01*
X1435708Y273075D01*
X1435917Y273367D01*
X1436000Y273700D01*
X1435917Y274033D01*
X1435708Y274325D01*
X1435417Y274450D01*
X1435125Y274367D01*
X1434917Y274158D01*
X1434833Y273908D01*
Y273492D01*
X1434708Y273117D01*
X1434458Y272867D01*
X1434167Y272783D01*
X1433875Y272867D01*
X1433667Y273075D01*
X1433542Y273408D01*
X1433500Y273700D01*
G01X1405765Y256994D02*
X1408265D01*
Y258035D01*
X1408140Y258369D01*
X1407973Y258577D01*
X1407640Y258660D01*
X1407307Y258577D01*
X1407098Y258327D01*
X1406973Y258035D01*
Y256994D01*
G01Y258035D02*
X1405765Y258660D01*
G01X1407848Y260135D02*
X1408098Y260385D01*
X1408223Y260677D01*
X1408265Y261010D01*
X1408182Y261427D01*
X1407973Y261719D01*
X1407723Y261802D01*
X1407473Y261760D01*
X1407265Y261594D01*
X1406848Y260760D01*
X1406557Y260385D01*
X1406140Y260135D01*
X1405765Y260052D01*
Y261802D01*
G01Y263194D02*
X1408265D01*
Y264235D01*
X1408140Y264569D01*
X1407973Y264777D01*
X1407640Y264860D01*
X1407307Y264777D01*
X1407098Y264527D01*
X1406973Y264235D01*
Y263194D01*
G01Y264235D02*
X1405765Y264860D01*
G01X1406807Y266335D02*
X1407098Y266627D01*
X1407265Y266877D01*
X1407348Y267210D01*
X1407265Y267502D01*
X1407098Y267710D01*
X1406848Y267877D01*
X1406557Y267919D01*
X1406307Y267877D01*
X1406057Y267710D01*
X1405848Y267460D01*
X1405765Y267169D01*
X1405848Y266835D01*
X1406098Y266544D01*
X1406473Y266377D01*
X1406890Y266335D01*
X1407432Y266419D01*
X1407723Y266544D01*
X1408015Y266752D01*
X1408223Y267044D01*
X1408265Y267335D01*
X1408182Y267627D01*
X1407973Y267835D01*
G01X1409765Y255494D02*
X1412265D01*
Y256535D01*
X1412140Y256869D01*
X1411973Y257077D01*
X1411640Y257160D01*
X1411307Y257077D01*
X1411098Y256827D01*
X1410973Y256535D01*
Y255494D01*
G01Y256535D02*
X1409765Y257160D01*
G01X1411848Y258635D02*
X1412098Y258885D01*
X1412223Y259177D01*
X1412265Y259510D01*
X1412182Y259927D01*
X1411973Y260219D01*
X1411723Y260302D01*
X1411473Y260260D01*
X1411265Y260094D01*
X1410848Y259260D01*
X1410557Y258885D01*
X1410140Y258635D01*
X1409765Y258552D01*
Y260302D01*
G01Y261694D02*
X1412265D01*
Y262735D01*
X1412140Y263069D01*
X1411973Y263277D01*
X1411640Y263360D01*
X1411307Y263277D01*
X1411098Y263027D01*
X1410973Y262735D01*
Y261694D01*
G01Y262735D02*
X1409765Y263360D01*
G01X1410265Y264710D02*
X1409973Y264960D01*
X1409807Y265294D01*
X1409765Y265669D01*
X1409807Y266002D01*
X1410015Y266335D01*
X1410265Y266544D01*
X1410515Y266585D01*
X1410807Y266502D01*
X1411015Y266210D01*
X1411098Y265919D01*
Y265544D01*
G01Y265919D02*
X1411223Y266169D01*
X1411432Y266377D01*
X1411682Y266460D01*
X1411932Y266377D01*
X1412140Y266169D01*
X1412265Y265794D01*
X1412223Y265419D01*
X1412057Y265044D01*
G01X1416236Y236743D02*
X1418736D01*
Y237784D01*
X1418611Y238118D01*
X1418444Y238326D01*
X1418111Y238409D01*
X1417778Y238326D01*
X1417569Y238076D01*
X1417444Y237784D01*
Y236743D01*
G01Y237784D02*
X1416236Y238409D01*
G01X1416736Y239759D02*
X1416444Y240009D01*
X1416278Y240343D01*
X1416236Y240718D01*
X1416278Y241051D01*
X1416486Y241384D01*
X1416736Y241593D01*
X1416986Y241634D01*
X1417278Y241551D01*
X1417486Y241259D01*
X1417569Y240968D01*
Y240593D01*
G01Y240968D02*
X1417694Y241218D01*
X1417903Y241426D01*
X1418153Y241509D01*
X1418403Y241426D01*
X1418611Y241218D01*
X1418736Y240843D01*
X1418694Y240468D01*
X1418528Y240093D01*
G01X1416236Y242943D02*
X1418736D01*
Y243943D01*
X1418611Y244276D01*
X1418319Y244526D01*
X1417986Y244609D01*
X1417653Y244526D01*
X1417403Y244318D01*
X1417278Y243943D01*
Y242943D01*
G01X1416236Y247376D02*
X1418736D01*
X1416944Y245834D01*
Y247918D01*
G01X1418319Y249184D02*
X1418569Y249434D01*
X1418694Y249726D01*
X1418736Y250059D01*
X1418653Y250476D01*
X1418444Y250768D01*
X1418194Y250851D01*
X1417944Y250809D01*
X1417736Y250643D01*
X1417319Y249809D01*
X1417028Y249434D01*
X1416611Y249184D01*
X1416236Y249101D01*
Y250851D01*
G01X1420000Y237017D02*
X1422500D01*
Y238058D01*
X1422375Y238392D01*
X1422208Y238600D01*
X1421875Y238683D01*
X1421542Y238600D01*
X1421333Y238350D01*
X1421208Y238058D01*
Y237017D01*
G01Y238058D02*
X1420000Y238683D01*
G01X1420500Y240033D02*
X1420208Y240283D01*
X1420042Y240617D01*
X1420000Y240992D01*
X1420042Y241325D01*
X1420250Y241658D01*
X1420500Y241867D01*
X1420750Y241908D01*
X1421042Y241825D01*
X1421250Y241533D01*
X1421333Y241242D01*
Y240867D01*
G01Y241242D02*
X1421458Y241492D01*
X1421667Y241700D01*
X1421917Y241783D01*
X1422167Y241700D01*
X1422375Y241492D01*
X1422500Y241117D01*
X1422458Y240742D01*
X1422292Y240367D01*
G01X1420000Y243217D02*
X1422500D01*
Y244258D01*
X1422375Y244592D01*
X1422208Y244800D01*
X1421875Y244883D01*
X1421542Y244800D01*
X1421333Y244550D01*
X1421208Y244258D01*
Y243217D01*
G01Y244258D02*
X1420000Y244883D01*
G01X1422083Y246358D02*
X1422333Y246608D01*
X1422458Y246900D01*
X1422500Y247233D01*
X1422417Y247650D01*
X1422208Y247942D01*
X1421958Y248025D01*
X1421708Y247983D01*
X1421500Y247817D01*
X1421083Y246983D01*
X1420792Y246608D01*
X1420375Y246358D01*
X1420000Y246275D01*
Y248025D01*
G01X1408236Y236743D02*
X1410736D01*
Y237784D01*
X1410611Y238118D01*
X1410444Y238326D01*
X1410111Y238409D01*
X1409778Y238326D01*
X1409569Y238076D01*
X1409444Y237784D01*
Y236743D01*
G01Y237784D02*
X1408236Y238409D01*
G01X1408736Y239759D02*
X1408444Y240009D01*
X1408278Y240343D01*
X1408236Y240718D01*
X1408278Y241051D01*
X1408486Y241384D01*
X1408736Y241593D01*
X1408986Y241634D01*
X1409278Y241551D01*
X1409486Y241259D01*
X1409569Y240968D01*
Y240593D01*
G01Y240968D02*
X1409694Y241218D01*
X1409903Y241426D01*
X1410153Y241509D01*
X1410403Y241426D01*
X1410611Y241218D01*
X1410736Y240843D01*
X1410694Y240468D01*
X1410528Y240093D01*
G01X1408236Y242943D02*
X1410736D01*
Y243943D01*
X1410611Y244276D01*
X1410319Y244526D01*
X1409986Y244609D01*
X1409653Y244526D01*
X1409403Y244318D01*
X1409278Y243943D01*
Y242943D01*
G01X1408236Y247376D02*
X1410736D01*
X1408944Y245834D01*
Y247918D01*
G01X1409278Y249184D02*
X1409569Y249476D01*
X1409736Y249726D01*
X1409819Y250059D01*
X1409736Y250351D01*
X1409569Y250559D01*
X1409319Y250726D01*
X1409028Y250768D01*
X1408778Y250726D01*
X1408528Y250559D01*
X1408319Y250309D01*
X1408236Y250018D01*
X1408319Y249684D01*
X1408569Y249393D01*
X1408944Y249226D01*
X1409361Y249184D01*
X1409903Y249268D01*
X1410194Y249393D01*
X1410486Y249601D01*
X1410694Y249893D01*
X1410736Y250184D01*
X1410653Y250476D01*
X1410444Y250684D01*
G01X1412236Y236743D02*
X1414736D01*
Y237784D01*
X1414611Y238118D01*
X1414444Y238326D01*
X1414111Y238409D01*
X1413778Y238326D01*
X1413569Y238076D01*
X1413444Y237784D01*
Y236743D01*
G01Y237784D02*
X1412236Y238409D01*
G01X1412736Y239759D02*
X1412444Y240009D01*
X1412278Y240343D01*
X1412236Y240718D01*
X1412278Y241051D01*
X1412486Y241384D01*
X1412736Y241593D01*
X1412986Y241634D01*
X1413278Y241551D01*
X1413486Y241259D01*
X1413569Y240968D01*
Y240593D01*
G01Y240968D02*
X1413694Y241218D01*
X1413903Y241426D01*
X1414153Y241509D01*
X1414403Y241426D01*
X1414611Y241218D01*
X1414736Y240843D01*
X1414694Y240468D01*
X1414528Y240093D01*
G01X1412236Y242943D02*
X1414736D01*
Y243943D01*
X1414611Y244276D01*
X1414319Y244526D01*
X1413986Y244609D01*
X1413653Y244526D01*
X1413403Y244318D01*
X1413278Y243943D01*
Y242943D01*
G01X1412236Y247376D02*
X1414736D01*
X1412944Y245834D01*
Y247918D01*
G01X1412736Y249059D02*
X1412444Y249309D01*
X1412278Y249643D01*
X1412236Y250018D01*
X1412278Y250351D01*
X1412486Y250684D01*
X1412736Y250893D01*
X1412986Y250934D01*
X1413278Y250851D01*
X1413486Y250559D01*
X1413569Y250268D01*
Y249893D01*
G01Y250268D02*
X1413694Y250518D01*
X1413903Y250726D01*
X1414153Y250809D01*
X1414403Y250726D01*
X1414611Y250518D01*
X1414736Y250143D01*
X1414694Y249768D01*
X1414528Y249393D01*
G01X1422283Y254292D02*
X1422533Y254417D01*
X1422825Y254500D01*
X1423158D01*
X1423533Y254375D01*
X1423825Y254167D01*
X1424033Y253917D01*
X1424200Y253500D01*
X1424242Y253125D01*
X1424158Y252750D01*
X1424033Y252500D01*
X1423783Y252250D01*
X1423492Y252083D01*
X1423200Y252000D01*
X1422908D01*
X1422617Y252083D01*
X1422367Y252208D01*
X1422158Y252375D01*
G01X1421017Y252500D02*
X1420767Y252208D01*
X1420433Y252042D01*
X1420058Y252000D01*
X1419725Y252042D01*
X1419392Y252250D01*
X1419183Y252500D01*
X1419142Y252750D01*
X1419225Y253042D01*
X1419517Y253250D01*
X1419808Y253333D01*
X1420183D01*
G01X1419808D02*
X1419558Y253458D01*
X1419350Y253667D01*
X1419267Y253917D01*
X1419350Y254167D01*
X1419558Y254375D01*
X1419933Y254500D01*
X1420308Y254458D01*
X1420683Y254292D01*
G01X1417833Y252000D02*
Y254500D01*
X1416833D01*
X1416500Y254375D01*
X1416250Y254083D01*
X1416167Y253750D01*
X1416250Y253417D01*
X1416458Y253167D01*
X1416833Y253042D01*
X1417833D01*
G01X1413400Y252000D02*
Y254500D01*
X1414942Y252708D01*
X1412858D01*
G01X1411592Y254083D02*
X1411342Y254333D01*
X1411050Y254458D01*
X1410717Y254500D01*
X1410300Y254417D01*
X1410008Y254208D01*
X1409925Y253958D01*
X1409967Y253708D01*
X1410133Y253500D01*
X1410967Y253083D01*
X1411342Y252792D01*
X1411592Y252375D01*
X1411675Y252000D01*
X1409925D01*
G01X1427420Y230403D02*
Y228611D01*
X1427253Y228236D01*
X1426920Y227986D01*
X1426503Y227903D01*
X1426086Y227986D01*
X1425753Y228236D01*
X1425586Y228611D01*
Y230403D01*
G01X1424320Y228403D02*
X1424070Y228111D01*
X1423736Y227945D01*
X1423361Y227903D01*
X1423028Y227945D01*
X1422695Y228153D01*
X1422486Y228403D01*
X1422445Y228653D01*
X1422528Y228945D01*
X1422820Y229153D01*
X1423111Y229236D01*
X1423486D01*
G01X1423111D02*
X1422861Y229361D01*
X1422653Y229570D01*
X1422570Y229820D01*
X1422653Y230070D01*
X1422861Y230278D01*
X1423236Y230403D01*
X1423611Y230361D01*
X1423986Y230195D01*
G01X1421136Y227903D02*
Y230403D01*
X1420136D01*
X1419803Y230278D01*
X1419553Y229986D01*
X1419470Y229653D01*
X1419553Y229320D01*
X1419761Y229070D01*
X1420136Y228945D01*
X1421136D01*
G01X1417995Y229986D02*
X1417745Y230236D01*
X1417453Y230361D01*
X1417120Y230403D01*
X1416703Y230320D01*
X1416411Y230111D01*
X1416328Y229861D01*
X1416370Y229611D01*
X1416536Y229403D01*
X1417370Y228986D01*
X1417745Y228695D01*
X1417995Y228278D01*
X1418078Y227903D01*
X1416328D01*
G01X1452200Y242200D02*
X1440800D01*
Y221860D01*
X1452200D01*
Y242200D01*
G01X1447750D02*
Y237750D01*
X1445250D01*
Y242200D01*
G01X1458653Y273419D02*
X1458903Y273544D01*
X1459195Y273627D01*
X1459528D01*
X1459903Y273502D01*
X1460195Y273294D01*
X1460403Y273044D01*
X1460570Y272627D01*
X1460612Y272252D01*
X1460528Y271877D01*
X1460403Y271627D01*
X1460153Y271377D01*
X1459862Y271210D01*
X1459570Y271127D01*
X1459278D01*
X1458987Y271210D01*
X1458737Y271335D01*
X1458528Y271502D01*
G01X1457262Y273210D02*
X1457012Y273460D01*
X1456720Y273585D01*
X1456387Y273627D01*
X1455970Y273544D01*
X1455678Y273335D01*
X1455595Y273085D01*
X1455637Y272835D01*
X1455803Y272627D01*
X1456637Y272210D01*
X1457012Y271919D01*
X1457262Y271502D01*
X1457345Y271127D01*
X1455595D01*
G01X1454203D02*
Y273627D01*
X1453162D01*
X1452828Y273502D01*
X1452620Y273335D01*
X1452537Y273002D01*
X1452620Y272669D01*
X1452870Y272460D01*
X1453162Y272335D01*
X1454203D01*
G01X1453162D02*
X1452537Y271127D01*
G01X1449770D02*
Y273627D01*
X1451312Y271835D01*
X1449228D01*
G01X1444784Y272807D02*
X1444909Y272557D01*
X1444992Y272265D01*
Y271932D01*
X1444867Y271557D01*
X1444659Y271265D01*
X1444409Y271057D01*
X1443992Y270890D01*
X1443617Y270848D01*
X1443242Y270932D01*
X1442992Y271057D01*
X1442742Y271307D01*
X1442575Y271598D01*
X1442492Y271890D01*
Y272182D01*
X1442575Y272473D01*
X1442700Y272723D01*
X1442867Y272932D01*
G01X1444575Y274198D02*
X1444825Y274448D01*
X1444950Y274740D01*
X1444992Y275073D01*
X1444909Y275490D01*
X1444700Y275782D01*
X1444450Y275865D01*
X1444200Y275823D01*
X1443992Y275657D01*
X1443575Y274823D01*
X1443284Y274448D01*
X1442867Y274198D01*
X1442492Y274115D01*
Y275865D01*
G01Y277257D02*
X1444992D01*
Y278298D01*
X1444867Y278632D01*
X1444700Y278840D01*
X1444367Y278923D01*
X1444034Y278840D01*
X1443825Y278590D01*
X1443700Y278298D01*
Y277257D01*
G01Y278298D02*
X1442492Y278923D01*
G01X1442992Y280273D02*
X1442700Y280523D01*
X1442534Y280857D01*
X1442492Y281232D01*
X1442534Y281565D01*
X1442742Y281898D01*
X1442992Y282107D01*
X1443242Y282148D01*
X1443534Y282065D01*
X1443742Y281773D01*
X1443825Y281482D01*
Y281107D01*
G01Y281482D02*
X1443950Y281732D01*
X1444159Y281940D01*
X1444409Y282023D01*
X1444659Y281940D01*
X1444867Y281732D01*
X1444992Y281357D01*
X1444950Y280982D01*
X1444784Y280607D01*
G01X1428667Y340182D02*
X1431167D01*
Y341223D01*
X1431042Y341557D01*
X1430875Y341765D01*
X1430542Y341848D01*
X1430209Y341765D01*
X1430000Y341515D01*
X1429875Y341223D01*
Y340182D01*
G01Y341223D02*
X1428667Y341848D01*
G01Y344032D02*
X1429209Y344115D01*
X1429667Y344240D01*
X1430084Y344407D01*
X1430542Y344615D01*
X1431167Y344948D01*
Y343282D01*
G01X1430959Y348132D02*
X1431084Y347882D01*
X1431167Y347590D01*
Y347257D01*
X1431042Y346882D01*
X1430834Y346590D01*
X1430584Y346382D01*
X1430167Y346215D01*
X1429792Y346173D01*
X1429417Y346257D01*
X1429167Y346382D01*
X1428917Y346632D01*
X1428750Y346923D01*
X1428667Y347215D01*
Y347507D01*
X1428750Y347798D01*
X1428875Y348048D01*
X1429042Y348257D01*
G01X1428667Y350315D02*
X1431167D01*
X1430667Y349815D01*
G01X1428667D02*
Y350815D01*
G01Y353415D02*
X1431167D01*
X1430667Y352915D01*
G01X1428667D02*
Y353915D01*
G01X1439323Y340942D02*
X1441823D01*
Y341983D01*
X1441698Y342317D01*
X1441531Y342525D01*
X1441198Y342608D01*
X1440865Y342525D01*
X1440656Y342275D01*
X1440531Y341983D01*
Y340942D01*
G01Y341983D02*
X1439323Y342608D01*
G01X1439823Y343958D02*
X1439531Y344208D01*
X1439365Y344542D01*
X1439323Y344917D01*
X1439365Y345250D01*
X1439573Y345583D01*
X1439823Y345792D01*
X1440073Y345833D01*
X1440365Y345750D01*
X1440573Y345458D01*
X1440656Y345167D01*
Y344792D01*
G01Y345167D02*
X1440781Y345417D01*
X1440990Y345625D01*
X1441240Y345708D01*
X1441490Y345625D01*
X1441698Y345417D01*
X1441823Y345042D01*
X1441781Y344667D01*
X1441615Y344292D01*
G01X1439323Y347017D02*
X1441823D01*
X1439323Y348933D01*
X1441823D01*
G01X1439615Y350367D02*
X1439406Y350658D01*
X1439323Y350992D01*
X1439406Y351325D01*
X1439656Y351617D01*
X1440031Y351825D01*
X1440406Y351908D01*
X1440865D01*
X1441240Y351825D01*
X1441573Y351617D01*
X1441740Y351367D01*
X1441823Y351075D01*
X1441740Y350742D01*
X1441573Y350492D01*
X1441323Y350325D01*
X1440990Y350242D01*
X1440698Y350325D01*
X1440406Y350533D01*
X1440240Y350783D01*
X1440198Y351075D01*
X1440281Y351408D01*
X1440490Y351658D01*
X1440865Y351908D01*
G01X1435624Y339607D02*
X1438124D01*
Y340648D01*
X1437999Y340982D01*
X1437832Y341190D01*
X1437499Y341273D01*
X1437166Y341190D01*
X1436957Y340940D01*
X1436832Y340648D01*
Y339607D01*
G01Y340648D02*
X1435624Y341273D01*
G01X1436124Y342623D02*
X1435832Y342873D01*
X1435666Y343207D01*
X1435624Y343582D01*
X1435666Y343915D01*
X1435874Y344248D01*
X1436124Y344457D01*
X1436374Y344498D01*
X1436666Y344415D01*
X1436874Y344123D01*
X1436957Y343832D01*
Y343457D01*
G01Y343832D02*
X1437082Y344082D01*
X1437291Y344290D01*
X1437541Y344373D01*
X1437791Y344290D01*
X1437999Y344082D01*
X1438124Y343707D01*
X1438082Y343332D01*
X1437916Y342957D01*
G01X1435624Y345682D02*
X1438124D01*
X1435624Y347598D01*
X1438124D01*
G01X1435624Y349740D02*
X1438124D01*
X1437624Y349240D01*
G01X1435624D02*
Y350240D01*
G01Y353340D02*
X1438124D01*
X1436332Y351798D01*
Y353882D01*
G01X1443250Y334417D02*
X1445750D01*
Y335458D01*
X1445625Y335792D01*
X1445458Y336000D01*
X1445125Y336083D01*
X1444792Y336000D01*
X1444583Y335750D01*
X1444458Y335458D01*
Y334417D01*
G01Y335458D02*
X1443250Y336083D01*
G01Y338267D02*
X1443792Y338350D01*
X1444250Y338475D01*
X1444667Y338642D01*
X1445125Y338850D01*
X1445750Y339183D01*
Y337517D01*
G01X1445542Y342367D02*
X1445667Y342117D01*
X1445750Y341825D01*
Y341492D01*
X1445625Y341117D01*
X1445417Y340825D01*
X1445167Y340617D01*
X1444750Y340450D01*
X1444375Y340408D01*
X1444000Y340492D01*
X1443750Y340617D01*
X1443500Y340867D01*
X1443333Y341158D01*
X1443250Y341450D01*
Y341742D01*
X1443333Y342033D01*
X1443458Y342283D01*
X1443625Y342492D01*
G01X1445333Y343758D02*
X1445583Y344008D01*
X1445708Y344300D01*
X1445750Y344633D01*
X1445667Y345050D01*
X1445458Y345342D01*
X1445208Y345425D01*
X1444958Y345383D01*
X1444750Y345217D01*
X1444333Y344383D01*
X1444042Y344008D01*
X1443625Y343758D01*
X1443250Y343675D01*
Y345425D01*
G01Y347650D02*
X1445750D01*
X1445250Y347150D01*
G01X1443250D02*
Y348150D01*
G01X1465687Y322238D02*
Y324738D01*
X1464646D01*
X1464312Y324613D01*
X1464104Y324446D01*
X1464021Y324113D01*
X1464104Y323780D01*
X1464354Y323571D01*
X1464646Y323446D01*
X1465687D01*
G01X1464646D02*
X1464021Y322238D01*
G01X1461837D02*
X1461754Y322780D01*
X1461629Y323238D01*
X1461462Y323655D01*
X1461254Y324113D01*
X1460921Y324738D01*
X1462587D01*
G01X1459571Y322238D02*
Y324738D01*
X1458737D01*
X1458404Y324613D01*
X1458154Y324446D01*
X1457946Y324196D01*
X1457779Y323905D01*
X1457737Y323488D01*
X1457779Y323071D01*
X1457946Y322780D01*
X1458154Y322530D01*
X1458404Y322363D01*
X1458737Y322238D01*
X1459571D01*
G01X1455554D02*
Y324738D01*
X1456054Y324238D01*
G01Y322238D02*
X1455054D01*
G01X1452454D02*
X1452162Y322280D01*
X1451829Y322405D01*
X1451621Y322613D01*
X1451537Y322905D01*
X1451621Y323196D01*
X1451871Y323446D01*
X1452246Y323571D01*
X1452662D01*
X1452912Y323655D01*
X1453121Y323863D01*
X1453204Y324155D01*
X1453079Y324446D01*
X1452787Y324655D01*
X1452454Y324738D01*
X1452121Y324655D01*
X1451829Y324446D01*
X1451704Y324155D01*
X1451787Y323863D01*
X1451996Y323655D01*
X1452246Y323571D01*
X1452662D01*
X1453037Y323446D01*
X1453287Y323196D01*
X1453371Y322905D01*
X1453287Y322613D01*
X1453079Y322405D01*
X1452746Y322280D01*
X1452454Y322238D01*
G01X1441033Y318000D02*
Y320500D01*
X1439992D01*
X1439658Y320375D01*
X1439450Y320208D01*
X1439367Y319875D01*
X1439450Y319542D01*
X1439700Y319333D01*
X1439992Y319208D01*
X1441033D01*
G01X1439992D02*
X1439367Y318000D01*
G01X1437183D02*
X1437100Y318542D01*
X1436975Y319000D01*
X1436808Y319417D01*
X1436600Y319875D01*
X1436267Y320500D01*
X1437933D01*
G01X1434917Y318000D02*
Y320500D01*
X1434083D01*
X1433750Y320375D01*
X1433500Y320208D01*
X1433292Y319958D01*
X1433125Y319667D01*
X1433083Y319250D01*
X1433125Y318833D01*
X1433292Y318542D01*
X1433500Y318292D01*
X1433750Y318125D01*
X1434083Y318000D01*
X1434917D01*
G01X1431817Y318500D02*
X1431567Y318208D01*
X1431233Y318042D01*
X1430858Y318000D01*
X1430525Y318042D01*
X1430192Y318250D01*
X1429983Y318500D01*
X1429942Y318750D01*
X1430025Y319042D01*
X1430317Y319250D01*
X1430608Y319333D01*
X1430983D01*
G01X1430608D02*
X1430358Y319458D01*
X1430150Y319667D01*
X1430067Y319917D01*
X1430150Y320167D01*
X1430358Y320375D01*
X1430733Y320500D01*
X1431108Y320458D01*
X1431483Y320292D01*
G01X1427883Y318000D02*
X1427800Y318542D01*
X1427675Y319000D01*
X1427508Y319417D01*
X1427300Y319875D01*
X1426967Y320500D01*
X1428633D01*
G01X1436033Y301000D02*
Y303500D01*
X1434992D01*
X1434658Y303375D01*
X1434450Y303208D01*
X1434367Y302875D01*
X1434450Y302542D01*
X1434700Y302333D01*
X1434992Y302208D01*
X1436033D01*
G01X1434992D02*
X1434367Y301000D01*
G01X1432183D02*
X1432100Y301542D01*
X1431975Y302000D01*
X1431808Y302417D01*
X1431600Y302875D01*
X1431267Y303500D01*
X1432933D01*
G01X1429917Y301000D02*
Y303500D01*
X1429083D01*
X1428750Y303375D01*
X1428500Y303208D01*
X1428292Y302958D01*
X1428125Y302667D01*
X1428083Y302250D01*
X1428125Y301833D01*
X1428292Y301542D01*
X1428500Y301292D01*
X1428750Y301125D01*
X1429083Y301000D01*
X1429917D01*
G01X1426817Y301500D02*
X1426567Y301208D01*
X1426233Y301042D01*
X1425858Y301000D01*
X1425525Y301042D01*
X1425192Y301250D01*
X1424983Y301500D01*
X1424942Y301750D01*
X1425025Y302042D01*
X1425317Y302250D01*
X1425608Y302333D01*
X1425983D01*
G01X1425608D02*
X1425358Y302458D01*
X1425150Y302667D01*
X1425067Y302917D01*
X1425150Y303167D01*
X1425358Y303375D01*
X1425733Y303500D01*
X1426108Y303458D01*
X1426483Y303292D01*
G01X1422800Y301000D02*
X1422508Y301042D01*
X1422175Y301167D01*
X1421967Y301375D01*
X1421883Y301667D01*
X1421967Y301958D01*
X1422217Y302208D01*
X1422592Y302333D01*
X1423008D01*
X1423258Y302417D01*
X1423467Y302625D01*
X1423550Y302917D01*
X1423425Y303208D01*
X1423133Y303417D01*
X1422800Y303500D01*
X1422467Y303417D01*
X1422175Y303208D01*
X1422050Y302917D01*
X1422133Y302625D01*
X1422342Y302417D01*
X1422592Y302333D01*
X1423008D01*
X1423383Y302208D01*
X1423633Y301958D01*
X1423717Y301667D01*
X1423633Y301375D01*
X1423425Y301167D01*
X1423092Y301042D01*
X1422800Y301000D01*
G01X1436033Y297500D02*
Y300000D01*
X1434992D01*
X1434658Y299875D01*
X1434450Y299708D01*
X1434367Y299375D01*
X1434450Y299042D01*
X1434700Y298833D01*
X1434992Y298708D01*
X1436033D01*
G01X1434992D02*
X1434367Y297500D01*
G01X1432183D02*
X1432100Y298042D01*
X1431975Y298500D01*
X1431808Y298917D01*
X1431600Y299375D01*
X1431267Y300000D01*
X1432933D01*
G01X1429917Y297500D02*
Y300000D01*
X1429083D01*
X1428750Y299875D01*
X1428500Y299708D01*
X1428292Y299458D01*
X1428125Y299167D01*
X1428083Y298750D01*
X1428125Y298333D01*
X1428292Y298042D01*
X1428500Y297792D01*
X1428750Y297625D01*
X1429083Y297500D01*
X1429917D01*
G01X1426817Y298000D02*
X1426567Y297708D01*
X1426233Y297542D01*
X1425858Y297500D01*
X1425525Y297542D01*
X1425192Y297750D01*
X1424983Y298000D01*
X1424942Y298250D01*
X1425025Y298542D01*
X1425317Y298750D01*
X1425608Y298833D01*
X1425983D01*
G01X1425608D02*
X1425358Y298958D01*
X1425150Y299167D01*
X1425067Y299417D01*
X1425150Y299667D01*
X1425358Y299875D01*
X1425733Y300000D01*
X1426108Y299958D01*
X1426483Y299792D01*
G01X1423592Y298542D02*
X1423300Y298833D01*
X1423050Y299000D01*
X1422717Y299083D01*
X1422425Y299000D01*
X1422217Y298833D01*
X1422050Y298583D01*
X1422008Y298292D01*
X1422050Y298042D01*
X1422217Y297792D01*
X1422467Y297583D01*
X1422758Y297500D01*
X1423092Y297583D01*
X1423383Y297833D01*
X1423550Y298208D01*
X1423592Y298625D01*
X1423508Y299167D01*
X1423383Y299458D01*
X1423175Y299750D01*
X1422883Y299958D01*
X1422592Y300000D01*
X1422300Y299917D01*
X1422092Y299708D01*
G01X1441033Y322000D02*
Y324500D01*
X1439992D01*
X1439658Y324375D01*
X1439450Y324208D01*
X1439367Y323875D01*
X1439450Y323542D01*
X1439700Y323333D01*
X1439992Y323208D01*
X1441033D01*
G01X1439992D02*
X1439367Y322000D01*
G01X1438017Y322500D02*
X1437767Y322208D01*
X1437433Y322042D01*
X1437058Y322000D01*
X1436725Y322042D01*
X1436392Y322250D01*
X1436183Y322500D01*
X1436142Y322750D01*
X1436225Y323042D01*
X1436517Y323250D01*
X1436808Y323333D01*
X1437183D01*
G01X1436808D02*
X1436558Y323458D01*
X1436350Y323667D01*
X1436267Y323917D01*
X1436350Y324167D01*
X1436558Y324375D01*
X1436933Y324500D01*
X1437308Y324458D01*
X1437683Y324292D01*
G01X1434833Y322000D02*
Y324500D01*
X1433833D01*
X1433500Y324375D01*
X1433250Y324083D01*
X1433167Y323750D01*
X1433250Y323417D01*
X1433458Y323167D01*
X1433833Y323042D01*
X1434833D01*
G01X1431817Y322500D02*
X1431567Y322208D01*
X1431233Y322042D01*
X1430858Y322000D01*
X1430525Y322042D01*
X1430192Y322250D01*
X1429983Y322500D01*
X1429942Y322750D01*
X1430025Y323042D01*
X1430317Y323250D01*
X1430608Y323333D01*
X1430983D01*
G01X1430608D02*
X1430358Y323458D01*
X1430150Y323667D01*
X1430067Y323917D01*
X1430150Y324167D01*
X1430358Y324375D01*
X1430733Y324500D01*
X1431108Y324458D01*
X1431483Y324292D01*
G01X1427300Y322000D02*
Y324500D01*
X1428842Y322708D01*
X1426758D01*
G01X1434809Y341632D02*
X1434934Y341382D01*
X1435017Y341090D01*
Y340757D01*
X1434892Y340382D01*
X1434684Y340090D01*
X1434434Y339882D01*
X1434017Y339715D01*
X1433642Y339673D01*
X1433267Y339757D01*
X1433017Y339882D01*
X1432767Y340132D01*
X1432600Y340423D01*
X1432517Y340715D01*
Y341007D01*
X1432600Y341298D01*
X1432725Y341548D01*
X1432892Y341757D01*
G01X1432517Y343732D02*
X1433059Y343815D01*
X1433517Y343940D01*
X1433934Y344107D01*
X1434392Y344315D01*
X1435017Y344648D01*
Y342982D01*
G01X1434809Y347832D02*
X1434934Y347582D01*
X1435017Y347290D01*
Y346957D01*
X1434892Y346582D01*
X1434684Y346290D01*
X1434434Y346082D01*
X1434017Y345915D01*
X1433642Y345873D01*
X1433267Y345957D01*
X1433017Y346082D01*
X1432767Y346332D01*
X1432600Y346623D01*
X1432517Y346915D01*
Y347207D01*
X1432600Y347498D01*
X1432725Y347748D01*
X1432892Y347957D01*
G01X1432517Y350015D02*
X1435017D01*
X1434517Y349515D01*
G01X1432517D02*
Y350515D01*
G01X1432809Y352407D02*
X1432600Y352698D01*
X1432517Y353032D01*
X1432600Y353365D01*
X1432850Y353657D01*
X1433225Y353865D01*
X1433600Y353948D01*
X1434059D01*
X1434434Y353865D01*
X1434767Y353657D01*
X1434934Y353407D01*
X1435017Y353115D01*
X1434934Y352782D01*
X1434767Y352532D01*
X1434517Y352365D01*
X1434184Y352282D01*
X1433892Y352365D01*
X1433600Y352573D01*
X1433434Y352823D01*
X1433392Y353115D01*
X1433475Y353448D01*
X1433684Y353698D01*
X1434059Y353948D01*
G01X1444680Y295032D02*
X1444805Y294782D01*
X1444888Y294490D01*
Y294157D01*
X1444763Y293782D01*
X1444555Y293490D01*
X1444305Y293282D01*
X1443888Y293115D01*
X1443513Y293073D01*
X1443138Y293157D01*
X1442888Y293282D01*
X1442638Y293532D01*
X1442471Y293823D01*
X1442388Y294115D01*
Y294407D01*
X1442471Y294698D01*
X1442596Y294948D01*
X1442763Y295157D01*
G01X1442888Y296298D02*
X1442596Y296548D01*
X1442430Y296882D01*
X1442388Y297257D01*
X1442430Y297590D01*
X1442638Y297923D01*
X1442888Y298132D01*
X1443138Y298173D01*
X1443430Y298090D01*
X1443638Y297798D01*
X1443721Y297507D01*
Y297132D01*
G01Y297507D02*
X1443846Y297757D01*
X1444055Y297965D01*
X1444305Y298048D01*
X1444555Y297965D01*
X1444763Y297757D01*
X1444888Y297382D01*
X1444846Y297007D01*
X1444680Y296632D01*
G01X1442388Y299482D02*
X1444888D01*
Y300482D01*
X1444763Y300815D01*
X1444471Y301065D01*
X1444138Y301148D01*
X1443805Y301065D01*
X1443555Y300857D01*
X1443430Y300482D01*
Y299482D01*
G01X1442388Y303915D02*
X1444888D01*
X1443096Y302373D01*
Y304457D01*
G01X1442888Y305598D02*
X1442596Y305848D01*
X1442430Y306182D01*
X1442388Y306557D01*
X1442430Y306890D01*
X1442638Y307223D01*
X1442888Y307432D01*
X1443138Y307473D01*
X1443430Y307390D01*
X1443638Y307098D01*
X1443721Y306807D01*
Y306432D01*
G01Y306807D02*
X1443846Y307057D01*
X1444055Y307265D01*
X1444305Y307348D01*
X1444555Y307265D01*
X1444763Y307057D01*
X1444888Y306682D01*
X1444846Y306307D01*
X1444680Y305932D01*
G01X1455468Y287371D02*
X1455718Y287496D01*
X1456010Y287579D01*
X1456343D01*
X1456718Y287454D01*
X1457010Y287246D01*
X1457218Y286996D01*
X1457385Y286579D01*
X1457427Y286204D01*
X1457343Y285829D01*
X1457218Y285579D01*
X1456968Y285329D01*
X1456677Y285162D01*
X1456385Y285079D01*
X1456093D01*
X1455802Y285162D01*
X1455552Y285287D01*
X1455343Y285454D01*
G01X1454077Y287162D02*
X1453827Y287412D01*
X1453535Y287537D01*
X1453202Y287579D01*
X1452785Y287496D01*
X1452493Y287287D01*
X1452410Y287037D01*
X1452452Y286787D01*
X1452618Y286579D01*
X1453452Y286162D01*
X1453827Y285871D01*
X1454077Y285454D01*
X1454160Y285079D01*
X1452410D01*
G01X1451018D02*
Y287579D01*
X1449977D01*
X1449643Y287454D01*
X1449435Y287287D01*
X1449352Y286954D01*
X1449435Y286621D01*
X1449685Y286412D01*
X1449977Y286287D01*
X1451018D01*
G01X1449977D02*
X1449352Y285079D01*
G01X1447085D02*
Y287579D01*
X1447585Y287079D01*
G01Y285079D02*
X1446585D01*
G01X1455475Y283758D02*
X1455725Y283883D01*
X1456017Y283966D01*
X1456350D01*
X1456725Y283841D01*
X1457017Y283633D01*
X1457225Y283383D01*
X1457392Y282966D01*
X1457434Y282591D01*
X1457350Y282216D01*
X1457225Y281966D01*
X1456975Y281716D01*
X1456684Y281549D01*
X1456392Y281466D01*
X1456100D01*
X1455809Y281549D01*
X1455559Y281674D01*
X1455350Y281841D01*
G01X1454084Y283549D02*
X1453834Y283799D01*
X1453542Y283924D01*
X1453209Y283966D01*
X1452792Y283883D01*
X1452500Y283674D01*
X1452417Y283424D01*
X1452459Y283174D01*
X1452625Y282966D01*
X1453459Y282549D01*
X1453834Y282258D01*
X1454084Y281841D01*
X1454167Y281466D01*
X1452417D01*
G01X1451025D02*
Y283966D01*
X1449984D01*
X1449650Y283841D01*
X1449442Y283674D01*
X1449359Y283341D01*
X1449442Y283008D01*
X1449692Y282799D01*
X1449984Y282674D01*
X1451025D01*
G01X1449984D02*
X1449359Y281466D01*
G01X1447884Y283549D02*
X1447634Y283799D01*
X1447342Y283924D01*
X1447009Y283966D01*
X1446592Y283883D01*
X1446300Y283674D01*
X1446217Y283424D01*
X1446259Y283174D01*
X1446425Y282966D01*
X1447259Y282549D01*
X1447634Y282258D01*
X1447884Y281841D01*
X1447967Y281466D01*
X1446217D01*
G01X1458688Y311044D02*
X1458938Y311169D01*
X1459230Y311252D01*
X1459563D01*
X1459938Y311127D01*
X1460230Y310919D01*
X1460438Y310669D01*
X1460605Y310252D01*
X1460647Y309877D01*
X1460563Y309502D01*
X1460438Y309252D01*
X1460188Y309002D01*
X1459897Y308835D01*
X1459605Y308752D01*
X1459313D01*
X1459022Y308835D01*
X1458772Y308960D01*
X1458563Y309127D01*
G01X1457422Y309252D02*
X1457172Y308960D01*
X1456838Y308794D01*
X1456463Y308752D01*
X1456130Y308794D01*
X1455797Y309002D01*
X1455588Y309252D01*
X1455547Y309502D01*
X1455630Y309794D01*
X1455922Y310002D01*
X1456213Y310085D01*
X1456588D01*
G01X1456213D02*
X1455963Y310210D01*
X1455755Y310419D01*
X1455672Y310669D01*
X1455755Y310919D01*
X1455963Y311127D01*
X1456338Y311252D01*
X1456713Y311210D01*
X1457088Y311044D01*
G01X1454238Y308752D02*
Y311252D01*
X1453238D01*
X1452905Y311127D01*
X1452655Y310835D01*
X1452572Y310502D01*
X1452655Y310169D01*
X1452863Y309919D01*
X1453238Y309794D01*
X1454238D01*
G01X1449805Y308752D02*
Y311252D01*
X1451347Y309460D01*
X1449263D01*
G01X1447205Y308752D02*
X1446913Y308794D01*
X1446580Y308919D01*
X1446372Y309127D01*
X1446288Y309419D01*
X1446372Y309710D01*
X1446622Y309960D01*
X1446997Y310085D01*
X1447413D01*
X1447663Y310169D01*
X1447872Y310377D01*
X1447955Y310669D01*
X1447830Y310960D01*
X1447538Y311169D01*
X1447205Y311252D01*
X1446872Y311169D01*
X1446580Y310960D01*
X1446455Y310669D01*
X1446538Y310377D01*
X1446747Y310169D01*
X1446997Y310085D01*
X1447413D01*
X1447788Y309960D01*
X1448038Y309710D01*
X1448122Y309419D01*
X1448038Y309127D01*
X1447830Y308919D01*
X1447497Y308794D01*
X1447205Y308752D01*
G01X1458711Y314334D02*
X1458961Y314459D01*
X1459253Y314542D01*
X1459586D01*
X1459961Y314417D01*
X1460253Y314209D01*
X1460461Y313959D01*
X1460628Y313542D01*
X1460670Y313167D01*
X1460586Y312792D01*
X1460461Y312542D01*
X1460211Y312292D01*
X1459920Y312125D01*
X1459628Y312042D01*
X1459336D01*
X1459045Y312125D01*
X1458795Y312250D01*
X1458586Y312417D01*
G01X1457445Y312542D02*
X1457195Y312250D01*
X1456861Y312084D01*
X1456486Y312042D01*
X1456153Y312084D01*
X1455820Y312292D01*
X1455611Y312542D01*
X1455570Y312792D01*
X1455653Y313084D01*
X1455945Y313292D01*
X1456236Y313375D01*
X1456611D01*
G01X1456236D02*
X1455986Y313500D01*
X1455778Y313709D01*
X1455695Y313959D01*
X1455778Y314209D01*
X1455986Y314417D01*
X1456361Y314542D01*
X1456736Y314500D01*
X1457111Y314334D01*
G01X1454261Y312042D02*
Y314542D01*
X1453261D01*
X1452928Y314417D01*
X1452678Y314125D01*
X1452595Y313792D01*
X1452678Y313459D01*
X1452886Y313209D01*
X1453261Y313084D01*
X1454261D01*
G01X1449828Y312042D02*
Y314542D01*
X1451370Y312750D01*
X1449286D01*
G01X1446728Y312042D02*
Y314542D01*
X1448270Y312750D01*
X1446186D01*
G01X1447982Y291930D02*
X1448107Y291680D01*
X1448190Y291388D01*
Y291055D01*
X1448065Y290680D01*
X1447857Y290388D01*
X1447607Y290180D01*
X1447190Y290013D01*
X1446815Y289971D01*
X1446440Y290055D01*
X1446190Y290180D01*
X1445940Y290430D01*
X1445773Y290721D01*
X1445690Y291013D01*
Y291305D01*
X1445773Y291596D01*
X1445898Y291846D01*
X1446065Y292055D01*
G01X1447773Y293321D02*
X1448023Y293571D01*
X1448148Y293863D01*
X1448190Y294196D01*
X1448107Y294613D01*
X1447898Y294905D01*
X1447648Y294988D01*
X1447398Y294946D01*
X1447190Y294780D01*
X1446773Y293946D01*
X1446482Y293571D01*
X1446065Y293321D01*
X1445690Y293238D01*
Y294988D01*
G01Y296380D02*
X1448190D01*
Y297380D01*
X1448065Y297713D01*
X1447773Y297963D01*
X1447440Y298046D01*
X1447107Y297963D01*
X1446857Y297755D01*
X1446732Y297380D01*
Y296380D01*
G01X1445690Y300230D02*
X1446232Y300313D01*
X1446690Y300438D01*
X1447107Y300605D01*
X1447565Y300813D01*
X1448190Y301146D01*
Y299480D01*
G01X1466640Y282412D02*
X1466765Y282162D01*
X1466848Y281870D01*
Y281537D01*
X1466723Y281162D01*
X1466515Y280870D01*
X1466265Y280662D01*
X1465848Y280495D01*
X1465473Y280453D01*
X1465098Y280537D01*
X1464848Y280662D01*
X1464598Y280912D01*
X1464431Y281203D01*
X1464348Y281495D01*
Y281787D01*
X1464431Y282078D01*
X1464556Y282328D01*
X1464723Y282537D01*
G01X1466431Y283803D02*
X1466681Y284053D01*
X1466806Y284345D01*
X1466848Y284678D01*
X1466765Y285095D01*
X1466556Y285387D01*
X1466306Y285470D01*
X1466056Y285428D01*
X1465848Y285262D01*
X1465431Y284428D01*
X1465140Y284053D01*
X1464723Y283803D01*
X1464348Y283720D01*
Y285470D01*
G01Y286862D02*
X1466848D01*
Y287862D01*
X1466723Y288195D01*
X1466431Y288445D01*
X1466098Y288528D01*
X1465765Y288445D01*
X1465515Y288237D01*
X1465390Y287862D01*
Y286862D01*
G01X1464348Y291295D02*
X1466848D01*
X1465056Y289753D01*
Y291837D01*
G01X1455617Y291993D02*
X1455742Y291743D01*
X1455825Y291451D01*
Y291118D01*
X1455700Y290743D01*
X1455492Y290451D01*
X1455242Y290243D01*
X1454825Y290076D01*
X1454450Y290034D01*
X1454075Y290118D01*
X1453825Y290243D01*
X1453575Y290493D01*
X1453408Y290784D01*
X1453325Y291076D01*
Y291368D01*
X1453408Y291659D01*
X1453533Y291909D01*
X1453700Y292118D01*
G01X1453825Y293259D02*
X1453533Y293509D01*
X1453367Y293843D01*
X1453325Y294218D01*
X1453367Y294551D01*
X1453575Y294884D01*
X1453825Y295093D01*
X1454075Y295134D01*
X1454367Y295051D01*
X1454575Y294759D01*
X1454658Y294468D01*
Y294093D01*
G01Y294468D02*
X1454783Y294718D01*
X1454992Y294926D01*
X1455242Y295009D01*
X1455492Y294926D01*
X1455700Y294718D01*
X1455825Y294343D01*
X1455783Y293968D01*
X1455617Y293593D01*
G01X1453325Y296443D02*
X1455825D01*
Y297484D01*
X1455700Y297818D01*
X1455533Y298026D01*
X1455200Y298109D01*
X1454867Y298026D01*
X1454658Y297776D01*
X1454533Y297484D01*
Y296443D01*
G01Y297484D02*
X1453325Y298109D01*
G01X1455408Y299584D02*
X1455658Y299834D01*
X1455783Y300126D01*
X1455825Y300459D01*
X1455742Y300876D01*
X1455533Y301168D01*
X1455283Y301251D01*
X1455033Y301209D01*
X1454825Y301043D01*
X1454408Y300209D01*
X1454117Y299834D01*
X1453700Y299584D01*
X1453325Y299501D01*
Y301251D01*
G01X1451482Y292033D02*
X1451607Y291783D01*
X1451690Y291491D01*
Y291158D01*
X1451565Y290783D01*
X1451357Y290491D01*
X1451107Y290283D01*
X1450690Y290116D01*
X1450315Y290074D01*
X1449940Y290158D01*
X1449690Y290283D01*
X1449440Y290533D01*
X1449273Y290824D01*
X1449190Y291116D01*
Y291408D01*
X1449273Y291699D01*
X1449398Y291949D01*
X1449565Y292158D01*
G01X1449690Y293299D02*
X1449398Y293549D01*
X1449232Y293883D01*
X1449190Y294258D01*
X1449232Y294591D01*
X1449440Y294924D01*
X1449690Y295133D01*
X1449940Y295174D01*
X1450232Y295091D01*
X1450440Y294799D01*
X1450523Y294508D01*
Y294133D01*
G01Y294508D02*
X1450648Y294758D01*
X1450857Y294966D01*
X1451107Y295049D01*
X1451357Y294966D01*
X1451565Y294758D01*
X1451690Y294383D01*
X1451648Y294008D01*
X1451482Y293633D01*
G01X1449190Y296483D02*
X1451690D01*
Y297483D01*
X1451565Y297816D01*
X1451273Y298066D01*
X1450940Y298149D01*
X1450607Y298066D01*
X1450357Y297858D01*
X1450232Y297483D01*
Y296483D01*
G01X1449190Y300916D02*
X1451690D01*
X1449898Y299374D01*
Y301458D01*
G01X1449190Y303433D02*
X1449732Y303516D01*
X1450190Y303641D01*
X1450607Y303808D01*
X1451065Y304016D01*
X1451690Y304349D01*
Y302683D01*
G01X1466204Y326170D02*
X1466537Y326212D01*
X1466829Y326378D01*
X1467079Y326628D01*
X1467246Y326920D01*
X1467329Y327253D01*
Y327587D01*
X1467246Y327920D01*
X1467079Y328212D01*
X1466829Y328462D01*
X1466537Y328628D01*
X1466204Y328670D01*
X1465871Y328628D01*
X1465579Y328462D01*
X1465329Y328212D01*
X1465162Y327920D01*
X1465079Y327587D01*
Y327253D01*
X1465162Y326920D01*
X1465329Y326628D01*
X1465579Y326378D01*
X1465871Y326212D01*
X1466204Y326170D01*
G01X1465871Y326837D02*
X1465371Y326170D01*
G01X1463187D02*
X1463104Y326712D01*
X1462979Y327170D01*
X1462812Y327587D01*
X1462604Y328045D01*
X1462271Y328670D01*
X1463937D01*
G01X1460921Y326170D02*
Y328670D01*
X1460087D01*
X1459754Y328545D01*
X1459504Y328378D01*
X1459296Y328128D01*
X1459129Y327837D01*
X1459087Y327420D01*
X1459129Y327003D01*
X1459296Y326712D01*
X1459504Y326462D01*
X1459754Y326295D01*
X1460087Y326170D01*
X1460921D01*
G01X1456904D02*
Y328670D01*
X1457404Y328170D01*
G01Y326170D02*
X1456404D01*
G01X1413033Y330225D02*
X1412825Y330558D01*
X1412700Y330933D01*
Y331267D01*
X1412825Y331600D01*
X1413033Y331850D01*
X1413325Y331975D01*
X1413617Y331892D01*
X1413867Y331683D01*
X1414033Y331308D01*
X1414117Y330808D01*
X1414283Y330517D01*
X1414575Y330392D01*
X1414867Y330475D01*
X1415075Y330683D01*
X1415200Y330975D01*
Y331267D01*
X1415117Y331558D01*
X1414908Y331808D01*
G01X1412700Y333325D02*
X1415200D01*
G01Y335075D02*
X1412700D01*
G01X1413950D02*
Y333325D01*
G01X1413200Y336383D02*
X1412908Y336633D01*
X1412742Y336967D01*
X1412700Y337342D01*
X1412742Y337675D01*
X1412950Y338008D01*
X1413200Y338217D01*
X1413450Y338258D01*
X1413742Y338175D01*
X1413950Y337883D01*
X1414033Y337592D01*
Y337217D01*
G01Y337592D02*
X1414158Y337842D01*
X1414367Y338050D01*
X1414617Y338133D01*
X1414867Y338050D01*
X1415075Y337842D01*
X1415200Y337467D01*
X1415158Y337092D01*
X1414992Y336717D01*
G01X1412700Y339567D02*
X1415200D01*
Y340567D01*
X1415075Y340900D01*
X1414783Y341150D01*
X1414450Y341233D01*
X1414117Y341150D01*
X1413867Y340942D01*
X1413742Y340567D01*
Y339567D01*
G01X1412700Y343500D02*
X1415200D01*
X1414700Y343000D01*
G01X1412700D02*
Y344000D01*
G01X1468183Y391700D02*
Y394200D01*
X1467142D01*
X1466808Y394075D01*
X1466600Y393908D01*
X1466517Y393575D01*
X1466600Y393242D01*
X1466850Y393033D01*
X1467142Y392908D01*
X1468183D01*
G01X1467142D02*
X1466517Y391700D01*
G01X1465167Y392200D02*
X1464917Y391908D01*
X1464583Y391742D01*
X1464208Y391700D01*
X1463875Y391742D01*
X1463542Y391950D01*
X1463333Y392200D01*
X1463292Y392450D01*
X1463375Y392742D01*
X1463667Y392950D01*
X1463958Y393033D01*
X1464333D01*
G01X1463958D02*
X1463708Y393158D01*
X1463500Y393367D01*
X1463417Y393617D01*
X1463500Y393867D01*
X1463708Y394075D01*
X1464083Y394200D01*
X1464458Y394158D01*
X1464833Y393992D01*
G01X1462108Y391700D02*
Y394200D01*
X1460192Y391700D01*
Y394200D01*
G01X1457550Y391700D02*
Y394200D01*
X1459092Y392408D01*
X1457008D01*
G01X1447063Y360109D02*
Y362609D01*
X1446022D01*
X1445688Y362484D01*
X1445480Y362317D01*
X1445397Y361984D01*
X1445480Y361651D01*
X1445730Y361442D01*
X1446022Y361317D01*
X1447063D01*
G01X1446022D02*
X1445397Y360109D01*
G01X1444047Y360609D02*
X1443797Y360317D01*
X1443463Y360151D01*
X1443088Y360109D01*
X1442755Y360151D01*
X1442422Y360359D01*
X1442213Y360609D01*
X1442172Y360859D01*
X1442255Y361151D01*
X1442547Y361359D01*
X1442838Y361442D01*
X1443213D01*
G01X1442838D02*
X1442588Y361567D01*
X1442380Y361776D01*
X1442297Y362026D01*
X1442380Y362276D01*
X1442588Y362484D01*
X1442963Y362609D01*
X1443338Y362567D01*
X1443713Y362401D01*
G01X1440988Y360109D02*
Y362609D01*
X1439072Y360109D01*
Y362609D01*
G01X1436930Y360109D02*
Y362609D01*
X1437430Y362109D01*
G01Y360109D02*
X1436430D01*
G01X1434747Y360609D02*
X1434497Y360317D01*
X1434163Y360151D01*
X1433788Y360109D01*
X1433455Y360151D01*
X1433122Y360359D01*
X1432913Y360609D01*
X1432872Y360859D01*
X1432955Y361151D01*
X1433247Y361359D01*
X1433538Y361442D01*
X1433913D01*
G01X1433538D02*
X1433288Y361567D01*
X1433080Y361776D01*
X1432997Y362026D01*
X1433080Y362276D01*
X1433288Y362484D01*
X1433663Y362609D01*
X1434038Y362567D01*
X1434413Y362401D01*
G01X1446788Y356211D02*
Y358711D01*
X1445747D01*
X1445413Y358586D01*
X1445205Y358419D01*
X1445122Y358086D01*
X1445205Y357753D01*
X1445455Y357544D01*
X1445747Y357419D01*
X1446788D01*
G01X1445747D02*
X1445122Y356211D01*
G01X1442938D02*
X1442855Y356753D01*
X1442730Y357211D01*
X1442563Y357628D01*
X1442355Y358086D01*
X1442022Y358711D01*
X1443688D01*
G01X1440672Y356211D02*
Y358711D01*
X1439838D01*
X1439505Y358586D01*
X1439255Y358419D01*
X1439047Y358169D01*
X1438880Y357878D01*
X1438838Y357461D01*
X1438880Y357044D01*
X1439047Y356753D01*
X1439255Y356503D01*
X1439505Y356336D01*
X1439838Y356211D01*
X1440672D01*
G01X1437447Y358294D02*
X1437197Y358544D01*
X1436905Y358669D01*
X1436572Y358711D01*
X1436155Y358628D01*
X1435863Y358419D01*
X1435780Y358169D01*
X1435822Y357919D01*
X1435988Y357711D01*
X1436822Y357294D01*
X1437197Y357003D01*
X1437447Y356586D01*
X1437530Y356211D01*
X1435780D01*
G01X1434472Y356711D02*
X1434222Y356419D01*
X1433888Y356253D01*
X1433513Y356211D01*
X1433180Y356253D01*
X1432847Y356461D01*
X1432638Y356711D01*
X1432597Y356961D01*
X1432680Y357253D01*
X1432972Y357461D01*
X1433263Y357544D01*
X1433638D01*
G01X1433263D02*
X1433013Y357669D01*
X1432805Y357878D01*
X1432722Y358128D01*
X1432805Y358378D01*
X1433013Y358586D01*
X1433388Y358711D01*
X1433763Y358669D01*
X1434138Y358503D01*
G01X1420657Y350861D02*
X1423157D01*
Y351902D01*
X1423032Y352236D01*
X1422865Y352444D01*
X1422532Y352527D01*
X1422199Y352444D01*
X1421990Y352194D01*
X1421865Y351902D01*
Y350861D01*
G01Y351902D02*
X1420657Y352527D01*
G01X1421157Y353877D02*
X1420865Y354127D01*
X1420699Y354461D01*
X1420657Y354836D01*
X1420699Y355169D01*
X1420907Y355502D01*
X1421157Y355711D01*
X1421407Y355752D01*
X1421699Y355669D01*
X1421907Y355377D01*
X1421990Y355086D01*
Y354711D01*
G01Y355086D02*
X1422115Y355336D01*
X1422324Y355544D01*
X1422574Y355627D01*
X1422824Y355544D01*
X1423032Y355336D01*
X1423157Y354961D01*
X1423115Y354586D01*
X1422949Y354211D01*
G01X1420657Y356936D02*
X1423157D01*
X1420657Y358852D01*
X1423157D01*
G01X1422740Y360202D02*
X1422990Y360452D01*
X1423115Y360744D01*
X1423157Y361077D01*
X1423074Y361494D01*
X1422865Y361786D01*
X1422615Y361869D01*
X1422365Y361827D01*
X1422157Y361661D01*
X1421740Y360827D01*
X1421449Y360452D01*
X1421032Y360202D01*
X1420657Y360119D01*
Y361869D01*
G01Y364094D02*
X1423157D01*
X1422657Y363594D01*
G01X1420657D02*
Y364594D01*
G01X1416732Y350829D02*
X1419232D01*
Y351870D01*
X1419107Y352204D01*
X1418940Y352412D01*
X1418607Y352495D01*
X1418274Y352412D01*
X1418065Y352162D01*
X1417940Y351870D01*
Y350829D01*
G01Y351870D02*
X1416732Y352495D01*
G01X1417232Y353845D02*
X1416940Y354095D01*
X1416774Y354429D01*
X1416732Y354804D01*
X1416774Y355137D01*
X1416982Y355470D01*
X1417232Y355679D01*
X1417482Y355720D01*
X1417774Y355637D01*
X1417982Y355345D01*
X1418065Y355054D01*
Y354679D01*
G01Y355054D02*
X1418190Y355304D01*
X1418399Y355512D01*
X1418649Y355595D01*
X1418899Y355512D01*
X1419107Y355304D01*
X1419232Y354929D01*
X1419190Y354554D01*
X1419024Y354179D01*
G01X1416732Y356904D02*
X1419232D01*
X1416732Y358820D01*
X1419232D01*
G01X1418815Y360170D02*
X1419065Y360420D01*
X1419190Y360712D01*
X1419232Y361045D01*
X1419149Y361462D01*
X1418940Y361754D01*
X1418690Y361837D01*
X1418440Y361795D01*
X1418232Y361629D01*
X1417815Y360795D01*
X1417524Y360420D01*
X1417107Y360170D01*
X1416732Y360087D01*
Y361837D01*
G01X1419232Y364062D02*
X1419149Y363729D01*
X1418940Y363479D01*
X1418690Y363312D01*
X1418357Y363187D01*
X1417982Y363145D01*
X1417607Y363187D01*
X1417274Y363312D01*
X1417024Y363479D01*
X1416815Y363729D01*
X1416732Y364062D01*
X1416815Y364395D01*
X1417024Y364645D01*
X1417274Y364812D01*
X1417607Y364937D01*
X1417982Y364979D01*
X1418357Y364937D01*
X1418690Y364812D01*
X1418940Y364645D01*
X1419149Y364395D01*
X1419232Y364062D01*
G01X1449411Y369877D02*
Y372377D01*
X1448370D01*
X1448036Y372252D01*
X1447828Y372085D01*
X1447745Y371752D01*
X1447828Y371419D01*
X1448078Y371210D01*
X1448370Y371085D01*
X1449411D01*
G01X1448370D02*
X1447745Y369877D01*
G01X1446395Y370377D02*
X1446145Y370085D01*
X1445811Y369919D01*
X1445436Y369877D01*
X1445103Y369919D01*
X1444770Y370127D01*
X1444561Y370377D01*
X1444520Y370627D01*
X1444603Y370919D01*
X1444895Y371127D01*
X1445186Y371210D01*
X1445561D01*
G01X1445186D02*
X1444936Y371335D01*
X1444728Y371544D01*
X1444645Y371794D01*
X1444728Y372044D01*
X1444936Y372252D01*
X1445311Y372377D01*
X1445686Y372335D01*
X1446061Y372169D01*
G01X1443211Y369877D02*
Y372377D01*
X1442211D01*
X1441878Y372252D01*
X1441628Y371960D01*
X1441545Y371627D01*
X1441628Y371294D01*
X1441836Y371044D01*
X1442211Y370919D01*
X1443211D01*
G01X1439361Y369877D02*
X1439278Y370419D01*
X1439153Y370877D01*
X1438986Y371294D01*
X1438778Y371752D01*
X1438445Y372377D01*
X1440111D01*
G01X1453366Y383556D02*
Y386056D01*
X1452325D01*
X1451991Y385931D01*
X1451783Y385764D01*
X1451700Y385431D01*
X1451783Y385098D01*
X1452033Y384889D01*
X1452325Y384764D01*
X1453366D01*
G01X1452325D02*
X1451700Y383556D01*
G01X1450350Y384056D02*
X1450100Y383764D01*
X1449766Y383598D01*
X1449391Y383556D01*
X1449058Y383598D01*
X1448725Y383806D01*
X1448516Y384056D01*
X1448475Y384306D01*
X1448558Y384598D01*
X1448850Y384806D01*
X1449141Y384889D01*
X1449516D01*
G01X1449141D02*
X1448891Y385014D01*
X1448683Y385223D01*
X1448600Y385473D01*
X1448683Y385723D01*
X1448891Y385931D01*
X1449266Y386056D01*
X1449641Y386014D01*
X1450016Y385848D01*
G01X1447291Y383556D02*
Y386056D01*
X1445375Y383556D01*
Y386056D01*
G01X1443233Y383556D02*
Y386056D01*
X1443733Y385556D01*
G01Y383556D02*
X1442733D01*
G01X1441050Y383931D02*
X1440800Y383723D01*
X1440508Y383598D01*
X1440133Y383556D01*
X1439758Y383639D01*
X1439466Y383806D01*
X1439258Y384098D01*
X1439216Y384431D01*
X1439300Y384764D01*
X1439508Y384973D01*
X1439800Y385139D01*
X1440091Y385181D01*
X1440383Y385139D01*
X1440758Y384973D01*
X1440633Y386056D01*
X1439508D01*
G01X1451153Y379370D02*
Y381870D01*
X1450112D01*
X1449778Y381745D01*
X1449570Y381578D01*
X1449487Y381245D01*
X1449570Y380912D01*
X1449820Y380703D01*
X1450112Y380578D01*
X1451153D01*
G01X1450112D02*
X1449487Y379370D01*
G01X1448137Y379870D02*
X1447887Y379578D01*
X1447553Y379412D01*
X1447178Y379370D01*
X1446845Y379412D01*
X1446512Y379620D01*
X1446303Y379870D01*
X1446262Y380120D01*
X1446345Y380412D01*
X1446637Y380620D01*
X1446928Y380703D01*
X1447303D01*
G01X1446928D02*
X1446678Y380828D01*
X1446470Y381037D01*
X1446387Y381287D01*
X1446470Y381537D01*
X1446678Y381745D01*
X1447053Y381870D01*
X1447428Y381828D01*
X1447803Y381662D01*
G01X1444953Y379370D02*
Y381870D01*
X1443953D01*
X1443620Y381745D01*
X1443370Y381453D01*
X1443287Y381120D01*
X1443370Y380787D01*
X1443578Y380537D01*
X1443953Y380412D01*
X1444953D01*
G01X1441020Y379370D02*
X1440728Y379412D01*
X1440395Y379537D01*
X1440187Y379745D01*
X1440103Y380037D01*
X1440187Y380328D01*
X1440437Y380578D01*
X1440812Y380703D01*
X1441228D01*
X1441478Y380787D01*
X1441687Y380995D01*
X1441770Y381287D01*
X1441645Y381578D01*
X1441353Y381787D01*
X1441020Y381870D01*
X1440687Y381787D01*
X1440395Y381578D01*
X1440270Y381287D01*
X1440353Y380995D01*
X1440562Y380787D01*
X1440812Y380703D01*
X1441228D01*
X1441603Y380578D01*
X1441853Y380328D01*
X1441937Y380037D01*
X1441853Y379745D01*
X1441645Y379537D01*
X1441312Y379412D01*
X1441020Y379370D01*
G01X1451190Y375334D02*
Y377834D01*
X1450149D01*
X1449815Y377709D01*
X1449607Y377542D01*
X1449524Y377209D01*
X1449607Y376876D01*
X1449857Y376667D01*
X1450149Y376542D01*
X1451190D01*
G01X1450149D02*
X1449524Y375334D01*
G01X1448174Y375834D02*
X1447924Y375542D01*
X1447590Y375376D01*
X1447215Y375334D01*
X1446882Y375376D01*
X1446549Y375584D01*
X1446340Y375834D01*
X1446299Y376084D01*
X1446382Y376376D01*
X1446674Y376584D01*
X1446965Y376667D01*
X1447340D01*
G01X1446965D02*
X1446715Y376792D01*
X1446507Y377001D01*
X1446424Y377251D01*
X1446507Y377501D01*
X1446715Y377709D01*
X1447090Y377834D01*
X1447465Y377792D01*
X1447840Y377626D01*
G01X1445115Y375334D02*
Y377834D01*
X1443199Y375334D01*
Y377834D01*
G01X1441057Y375334D02*
Y377834D01*
X1441557Y377334D01*
G01Y375334D02*
X1440557D01*
G01X1438749Y376376D02*
X1438457Y376667D01*
X1438207Y376834D01*
X1437874Y376917D01*
X1437582Y376834D01*
X1437374Y376667D01*
X1437207Y376417D01*
X1437165Y376126D01*
X1437207Y375876D01*
X1437374Y375626D01*
X1437624Y375417D01*
X1437915Y375334D01*
X1438249Y375417D01*
X1438540Y375667D01*
X1438707Y376042D01*
X1438749Y376459D01*
X1438665Y377001D01*
X1438540Y377292D01*
X1438332Y377584D01*
X1438040Y377792D01*
X1437749Y377834D01*
X1437457Y377751D01*
X1437249Y377542D01*
G01X1455052Y364860D02*
Y367360D01*
X1454011D01*
X1453677Y367235D01*
X1453469Y367068D01*
X1453386Y366735D01*
X1453469Y366402D01*
X1453719Y366193D01*
X1454011Y366068D01*
X1455052D01*
G01X1454011D02*
X1453386Y364860D01*
G01X1451202D02*
X1451119Y365402D01*
X1450994Y365860D01*
X1450827Y366277D01*
X1450619Y366735D01*
X1450286Y367360D01*
X1451952D01*
G01X1449269D02*
X1448686Y364860D01*
X1448019Y367360D01*
X1447352Y364860D01*
X1446769Y367360D01*
G01X1445711Y366943D02*
X1445461Y367193D01*
X1445169Y367318D01*
X1444836Y367360D01*
X1444419Y367277D01*
X1444127Y367068D01*
X1444044Y366818D01*
X1444086Y366568D01*
X1444252Y366360D01*
X1445086Y365943D01*
X1445461Y365652D01*
X1445711Y365235D01*
X1445794Y364860D01*
X1444044D01*
G01X1441819D02*
Y367360D01*
X1442319Y366860D01*
G01Y364860D02*
X1441319D01*
G01X1448819Y399509D02*
X1449069Y399634D01*
X1449361Y399717D01*
X1449694D01*
X1450069Y399592D01*
X1450361Y399384D01*
X1450569Y399134D01*
X1450736Y398717D01*
X1450778Y398342D01*
X1450694Y397967D01*
X1450569Y397717D01*
X1450319Y397467D01*
X1450028Y397300D01*
X1449736Y397217D01*
X1449444D01*
X1449153Y397300D01*
X1448903Y397425D01*
X1448694Y397592D01*
G01X1447553Y397717D02*
X1447303Y397425D01*
X1446969Y397259D01*
X1446594Y397217D01*
X1446261Y397259D01*
X1445928Y397467D01*
X1445719Y397717D01*
X1445678Y397967D01*
X1445761Y398259D01*
X1446053Y398467D01*
X1446344Y398550D01*
X1446719D01*
G01X1446344D02*
X1446094Y398675D01*
X1445886Y398884D01*
X1445803Y399134D01*
X1445886Y399384D01*
X1446094Y399592D01*
X1446469Y399717D01*
X1446844Y399675D01*
X1447219Y399509D01*
G01X1444494Y397217D02*
Y399717D01*
X1442578Y397217D01*
Y399717D01*
G01X1441353Y397717D02*
X1441103Y397425D01*
X1440769Y397259D01*
X1440394Y397217D01*
X1440061Y397259D01*
X1439728Y397467D01*
X1439519Y397717D01*
X1439478Y397967D01*
X1439561Y398259D01*
X1439853Y398467D01*
X1440144Y398550D01*
X1440519D01*
G01X1440144D02*
X1439894Y398675D01*
X1439686Y398884D01*
X1439603Y399134D01*
X1439686Y399384D01*
X1439894Y399592D01*
X1440269Y399717D01*
X1440644Y399675D01*
X1441019Y399509D01*
G01X1437336Y397217D02*
Y399717D01*
X1437836Y399217D01*
G01Y397217D02*
X1436836D01*
G01X1471838Y401062D02*
X1472088Y401187D01*
X1472380Y401270D01*
X1472713D01*
X1473088Y401145D01*
X1473380Y400937D01*
X1473588Y400687D01*
X1473755Y400270D01*
X1473797Y399895D01*
X1473713Y399520D01*
X1473588Y399270D01*
X1473338Y399020D01*
X1473047Y398853D01*
X1472755Y398770D01*
X1472463D01*
X1472172Y398853D01*
X1471922Y398978D01*
X1471713Y399145D01*
G01X1470572Y399270D02*
X1470322Y398978D01*
X1469988Y398812D01*
X1469613Y398770D01*
X1469280Y398812D01*
X1468947Y399020D01*
X1468738Y399270D01*
X1468697Y399520D01*
X1468780Y399812D01*
X1469072Y400020D01*
X1469363Y400103D01*
X1469738D01*
G01X1469363D02*
X1469113Y400228D01*
X1468905Y400437D01*
X1468822Y400687D01*
X1468905Y400937D01*
X1469113Y401145D01*
X1469488Y401270D01*
X1469863Y401228D01*
X1470238Y401062D01*
G01X1467513Y398770D02*
Y401270D01*
X1465597Y398770D01*
Y401270D01*
G01X1464372Y399270D02*
X1464122Y398978D01*
X1463788Y398812D01*
X1463413Y398770D01*
X1463080Y398812D01*
X1462747Y399020D01*
X1462538Y399270D01*
X1462497Y399520D01*
X1462580Y399812D01*
X1462872Y400020D01*
X1463163Y400103D01*
X1463538D01*
G01X1463163D02*
X1462913Y400228D01*
X1462705Y400437D01*
X1462622Y400687D01*
X1462705Y400937D01*
X1462913Y401145D01*
X1463288Y401270D01*
X1463663Y401228D01*
X1464038Y401062D01*
G01X1461147Y400853D02*
X1460897Y401103D01*
X1460605Y401228D01*
X1460272Y401270D01*
X1459855Y401187D01*
X1459563Y400978D01*
X1459480Y400728D01*
X1459522Y400478D01*
X1459688Y400270D01*
X1460522Y399853D01*
X1460897Y399562D01*
X1461147Y399145D01*
X1461230Y398770D01*
X1459480D01*
G01X1425177Y371881D02*
X1425427Y372006D01*
X1425719Y372089D01*
X1426052D01*
X1426427Y371964D01*
X1426719Y371756D01*
X1426927Y371506D01*
X1427094Y371089D01*
X1427136Y370714D01*
X1427052Y370339D01*
X1426927Y370089D01*
X1426677Y369839D01*
X1426386Y369672D01*
X1426094Y369589D01*
X1425802D01*
X1425511Y369672D01*
X1425261Y369797D01*
X1425052Y369964D01*
G01X1423786Y371672D02*
X1423536Y371922D01*
X1423244Y372047D01*
X1422911Y372089D01*
X1422494Y372006D01*
X1422202Y371797D01*
X1422119Y371547D01*
X1422161Y371297D01*
X1422327Y371089D01*
X1423161Y370672D01*
X1423536Y370381D01*
X1423786Y369964D01*
X1423869Y369589D01*
X1422119D01*
G01X1420686Y371672D02*
X1420436Y371922D01*
X1420144Y372047D01*
X1419811Y372089D01*
X1419394Y372006D01*
X1419102Y371797D01*
X1419019Y371547D01*
X1419061Y371297D01*
X1419227Y371089D01*
X1420061Y370672D01*
X1420436Y370381D01*
X1420686Y369964D01*
X1420769Y369589D01*
X1419019D01*
G01X1418044Y372089D02*
X1417461Y369589D01*
X1416794Y372089D01*
X1416127Y369589D01*
X1415544Y372089D01*
G01X1414611Y370089D02*
X1414361Y369797D01*
X1414027Y369631D01*
X1413652Y369589D01*
X1413319Y369631D01*
X1412986Y369839D01*
X1412777Y370089D01*
X1412736Y370339D01*
X1412819Y370631D01*
X1413111Y370839D01*
X1413402Y370922D01*
X1413777D01*
G01X1413402D02*
X1413152Y371047D01*
X1412944Y371256D01*
X1412861Y371506D01*
X1412944Y371756D01*
X1413152Y371964D01*
X1413527Y372089D01*
X1413902Y372047D01*
X1414277Y371881D01*
G01X1410594Y369589D02*
Y372089D01*
X1411094Y371589D01*
G01Y369589D02*
X1410094D01*
G01X1417185Y465031D02*
Y467531D01*
X1416144D01*
X1415810Y467406D01*
X1415602Y467239D01*
X1415519Y466906D01*
X1415602Y466573D01*
X1415852Y466364D01*
X1416144Y466239D01*
X1417185D01*
G01X1416144D02*
X1415519Y465031D01*
G01X1413335D02*
X1413252Y465573D01*
X1413127Y466031D01*
X1412960Y466448D01*
X1412752Y466906D01*
X1412419Y467531D01*
X1414085D01*
G01X1410235Y465031D02*
X1410152Y465573D01*
X1410027Y466031D01*
X1409860Y466448D01*
X1409652Y466906D01*
X1409319Y467531D01*
X1410985D01*
G01X1407760Y465323D02*
X1407469Y465114D01*
X1407135Y465031D01*
X1406802Y465114D01*
X1406510Y465364D01*
X1406302Y465739D01*
X1406219Y466114D01*
Y466573D01*
X1406302Y466948D01*
X1406510Y467281D01*
X1406760Y467448D01*
X1407052Y467531D01*
X1407385Y467448D01*
X1407635Y467281D01*
X1407802Y467031D01*
X1407885Y466698D01*
X1407802Y466406D01*
X1407594Y466114D01*
X1407344Y465948D01*
X1407052Y465906D01*
X1406719Y465989D01*
X1406469Y466198D01*
X1406219Y466573D01*
G01X1435474Y409537D02*
X1435724Y409662D01*
X1436016Y409745D01*
X1436349D01*
X1436724Y409620D01*
X1437016Y409412D01*
X1437224Y409162D01*
X1437391Y408745D01*
X1437433Y408370D01*
X1437349Y407995D01*
X1437224Y407745D01*
X1436974Y407495D01*
X1436683Y407328D01*
X1436391Y407245D01*
X1436099D01*
X1435808Y407328D01*
X1435558Y407453D01*
X1435349Y407620D01*
G01X1434208Y407745D02*
X1433958Y407453D01*
X1433624Y407287D01*
X1433249Y407245D01*
X1432916Y407287D01*
X1432583Y407495D01*
X1432374Y407745D01*
X1432333Y407995D01*
X1432416Y408287D01*
X1432708Y408495D01*
X1432999Y408578D01*
X1433374D01*
G01X1432999D02*
X1432749Y408703D01*
X1432541Y408912D01*
X1432458Y409162D01*
X1432541Y409412D01*
X1432749Y409620D01*
X1433124Y409745D01*
X1433499Y409703D01*
X1433874Y409537D01*
G01X1431149Y407245D02*
Y409745D01*
X1429233Y407245D01*
Y409745D01*
G01X1427883Y409328D02*
X1427633Y409578D01*
X1427341Y409703D01*
X1427008Y409745D01*
X1426591Y409662D01*
X1426299Y409453D01*
X1426216Y409203D01*
X1426258Y408953D01*
X1426424Y408745D01*
X1427258Y408328D01*
X1427633Y408037D01*
X1427883Y407620D01*
X1427966Y407245D01*
X1426216D01*
G01X1423991D02*
X1423699Y407287D01*
X1423366Y407412D01*
X1423158Y407620D01*
X1423074Y407912D01*
X1423158Y408203D01*
X1423408Y408453D01*
X1423783Y408578D01*
X1424199D01*
X1424449Y408662D01*
X1424658Y408870D01*
X1424741Y409162D01*
X1424616Y409453D01*
X1424324Y409662D01*
X1423991Y409745D01*
X1423658Y409662D01*
X1423366Y409453D01*
X1423241Y409162D01*
X1423324Y408870D01*
X1423533Y408662D01*
X1423783Y408578D01*
X1424199D01*
X1424574Y408453D01*
X1424824Y408203D01*
X1424908Y407912D01*
X1424824Y407620D01*
X1424616Y407412D01*
X1424283Y407287D01*
X1423991Y407245D01*
G01X1435824Y413337D02*
X1436074Y413462D01*
X1436366Y413545D01*
X1436699D01*
X1437074Y413420D01*
X1437366Y413212D01*
X1437574Y412962D01*
X1437741Y412545D01*
X1437783Y412170D01*
X1437699Y411795D01*
X1437574Y411545D01*
X1437324Y411295D01*
X1437033Y411128D01*
X1436741Y411045D01*
X1436449D01*
X1436158Y411128D01*
X1435908Y411253D01*
X1435699Y411420D01*
G01X1434558Y411545D02*
X1434308Y411253D01*
X1433974Y411087D01*
X1433599Y411045D01*
X1433266Y411087D01*
X1432933Y411295D01*
X1432724Y411545D01*
X1432683Y411795D01*
X1432766Y412087D01*
X1433058Y412295D01*
X1433349Y412378D01*
X1433724D01*
G01X1433349D02*
X1433099Y412503D01*
X1432891Y412712D01*
X1432808Y412962D01*
X1432891Y413212D01*
X1433099Y413420D01*
X1433474Y413545D01*
X1433849Y413503D01*
X1434224Y413337D01*
G01X1431499Y411045D02*
Y413545D01*
X1429583Y411045D01*
Y413545D01*
G01X1428233Y413128D02*
X1427983Y413378D01*
X1427691Y413503D01*
X1427358Y413545D01*
X1426941Y413462D01*
X1426649Y413253D01*
X1426566Y413003D01*
X1426608Y412753D01*
X1426774Y412545D01*
X1427608Y412128D01*
X1427983Y411837D01*
X1428233Y411420D01*
X1428316Y411045D01*
X1426566D01*
G01X1423841D02*
Y413545D01*
X1425383Y411753D01*
X1423299D01*
G01X1441183Y434692D02*
X1441433Y434817D01*
X1441725Y434900D01*
X1442058D01*
X1442433Y434775D01*
X1442725Y434567D01*
X1442933Y434317D01*
X1443100Y433900D01*
X1443142Y433525D01*
X1443058Y433150D01*
X1442933Y432900D01*
X1442683Y432650D01*
X1442392Y432483D01*
X1442100Y432400D01*
X1441808D01*
X1441517Y432483D01*
X1441267Y432608D01*
X1441058Y432775D01*
G01X1439917Y432900D02*
X1439667Y432608D01*
X1439333Y432442D01*
X1438958Y432400D01*
X1438625Y432442D01*
X1438292Y432650D01*
X1438083Y432900D01*
X1438042Y433150D01*
X1438125Y433442D01*
X1438417Y433650D01*
X1438708Y433733D01*
X1439083D01*
G01X1438708D02*
X1438458Y433858D01*
X1438250Y434067D01*
X1438167Y434317D01*
X1438250Y434567D01*
X1438458Y434775D01*
X1438833Y434900D01*
X1439208Y434858D01*
X1439583Y434692D01*
G01X1436983Y432400D02*
Y434900D01*
X1435900Y432817D01*
X1434817Y434900D01*
Y432400D01*
G01X1432300D02*
Y434900D01*
X1433842Y433108D01*
X1431758D01*
G01X1429700Y434900D02*
X1430033Y434817D01*
X1430283Y434608D01*
X1430450Y434358D01*
X1430575Y434025D01*
X1430617Y433650D01*
X1430575Y433275D01*
X1430450Y432942D01*
X1430283Y432692D01*
X1430033Y432483D01*
X1429700Y432400D01*
X1429367Y432483D01*
X1429117Y432692D01*
X1428950Y432942D01*
X1428825Y433275D01*
X1428783Y433650D01*
X1428825Y434025D01*
X1428950Y434358D01*
X1429117Y434608D01*
X1429367Y434817D01*
X1429700Y434900D01*
G01X1441183Y426692D02*
X1441433Y426817D01*
X1441725Y426900D01*
X1442058D01*
X1442433Y426775D01*
X1442725Y426567D01*
X1442933Y426317D01*
X1443100Y425900D01*
X1443142Y425525D01*
X1443058Y425150D01*
X1442933Y424900D01*
X1442683Y424650D01*
X1442392Y424483D01*
X1442100Y424400D01*
X1441808D01*
X1441517Y424483D01*
X1441267Y424608D01*
X1441058Y424775D01*
G01X1439917Y424900D02*
X1439667Y424608D01*
X1439333Y424442D01*
X1438958Y424400D01*
X1438625Y424442D01*
X1438292Y424650D01*
X1438083Y424900D01*
X1438042Y425150D01*
X1438125Y425442D01*
X1438417Y425650D01*
X1438708Y425733D01*
X1439083D01*
G01X1438708D02*
X1438458Y425858D01*
X1438250Y426067D01*
X1438167Y426317D01*
X1438250Y426567D01*
X1438458Y426775D01*
X1438833Y426900D01*
X1439208Y426858D01*
X1439583Y426692D01*
G01X1436858Y424400D02*
Y426900D01*
X1434942Y424400D01*
Y426900D01*
G01X1432800Y424400D02*
X1432508Y424442D01*
X1432175Y424567D01*
X1431967Y424775D01*
X1431883Y425067D01*
X1431967Y425358D01*
X1432217Y425608D01*
X1432592Y425733D01*
X1433008D01*
X1433258Y425817D01*
X1433467Y426025D01*
X1433550Y426317D01*
X1433425Y426608D01*
X1433133Y426817D01*
X1432800Y426900D01*
X1432467Y426817D01*
X1432175Y426608D01*
X1432050Y426317D01*
X1432133Y426025D01*
X1432342Y425817D01*
X1432592Y425733D01*
X1433008D01*
X1433383Y425608D01*
X1433633Y425358D01*
X1433717Y425067D01*
X1433633Y424775D01*
X1433425Y424567D01*
X1433092Y424442D01*
X1432800Y424400D01*
G01X1441183Y430692D02*
X1441433Y430817D01*
X1441725Y430900D01*
X1442058D01*
X1442433Y430775D01*
X1442725Y430567D01*
X1442933Y430317D01*
X1443100Y429900D01*
X1443142Y429525D01*
X1443058Y429150D01*
X1442933Y428900D01*
X1442683Y428650D01*
X1442392Y428483D01*
X1442100Y428400D01*
X1441808D01*
X1441517Y428483D01*
X1441267Y428608D01*
X1441058Y428775D01*
G01X1439917Y428900D02*
X1439667Y428608D01*
X1439333Y428442D01*
X1438958Y428400D01*
X1438625Y428442D01*
X1438292Y428650D01*
X1438083Y428900D01*
X1438042Y429150D01*
X1438125Y429442D01*
X1438417Y429650D01*
X1438708Y429733D01*
X1439083D01*
G01X1438708D02*
X1438458Y429858D01*
X1438250Y430067D01*
X1438167Y430317D01*
X1438250Y430567D01*
X1438458Y430775D01*
X1438833Y430900D01*
X1439208Y430858D01*
X1439583Y430692D01*
G01X1436983Y428400D02*
Y430900D01*
X1435900Y428817D01*
X1434817Y430900D01*
Y428400D01*
G01X1432300D02*
Y430900D01*
X1433842Y429108D01*
X1431758D01*
G01X1429200Y428400D02*
Y430900D01*
X1430742Y429108D01*
X1428658D01*
G01X1424583Y440092D02*
X1424833Y440217D01*
X1425125Y440300D01*
X1425458D01*
X1425833Y440175D01*
X1426125Y439967D01*
X1426333Y439717D01*
X1426500Y439300D01*
X1426542Y438925D01*
X1426458Y438550D01*
X1426333Y438300D01*
X1426083Y438050D01*
X1425792Y437883D01*
X1425500Y437800D01*
X1425208D01*
X1424917Y437883D01*
X1424667Y438008D01*
X1424458Y438175D01*
G01X1423317Y438300D02*
X1423067Y438008D01*
X1422733Y437842D01*
X1422358Y437800D01*
X1422025Y437842D01*
X1421692Y438050D01*
X1421483Y438300D01*
X1421442Y438550D01*
X1421525Y438842D01*
X1421817Y439050D01*
X1422108Y439133D01*
X1422483D01*
G01X1422108D02*
X1421858Y439258D01*
X1421650Y439467D01*
X1421567Y439717D01*
X1421650Y439967D01*
X1421858Y440175D01*
X1422233Y440300D01*
X1422608Y440258D01*
X1422983Y440092D01*
G01X1420258Y437800D02*
Y440300D01*
X1418342Y437800D01*
Y440300D01*
G01X1416908Y438092D02*
X1416617Y437883D01*
X1416283Y437800D01*
X1415950Y437883D01*
X1415658Y438133D01*
X1415450Y438508D01*
X1415367Y438883D01*
Y439342D01*
X1415450Y439717D01*
X1415658Y440050D01*
X1415908Y440217D01*
X1416200Y440300D01*
X1416533Y440217D01*
X1416783Y440050D01*
X1416950Y439800D01*
X1417033Y439467D01*
X1416950Y439175D01*
X1416742Y438883D01*
X1416492Y438717D01*
X1416200Y438675D01*
X1415867Y438758D01*
X1415617Y438967D01*
X1415367Y439342D01*
G01X1426483Y451192D02*
X1426733Y451317D01*
X1427025Y451400D01*
X1427358D01*
X1427733Y451275D01*
X1428025Y451067D01*
X1428233Y450817D01*
X1428400Y450400D01*
X1428442Y450025D01*
X1428358Y449650D01*
X1428233Y449400D01*
X1427983Y449150D01*
X1427692Y448983D01*
X1427400Y448900D01*
X1427108D01*
X1426817Y448983D01*
X1426567Y449108D01*
X1426358Y449275D01*
G01X1425217Y449400D02*
X1424967Y449108D01*
X1424633Y448942D01*
X1424258Y448900D01*
X1423925Y448942D01*
X1423592Y449150D01*
X1423383Y449400D01*
X1423342Y449650D01*
X1423425Y449942D01*
X1423717Y450150D01*
X1424008Y450233D01*
X1424383D01*
G01X1424008D02*
X1423758Y450358D01*
X1423550Y450567D01*
X1423467Y450817D01*
X1423550Y451067D01*
X1423758Y451275D01*
X1424133Y451400D01*
X1424508Y451358D01*
X1424883Y451192D01*
G01X1422283Y448900D02*
Y451400D01*
X1421200Y449317D01*
X1420117Y451400D01*
Y448900D01*
G01X1417600D02*
Y451400D01*
X1419142Y449608D01*
X1417058D01*
G01X1415000Y448900D02*
Y451400D01*
X1415500Y450900D01*
G01Y448900D02*
X1414500D01*
G01X1426683Y456592D02*
X1426933Y456717D01*
X1427225Y456800D01*
X1427558D01*
X1427933Y456675D01*
X1428225Y456467D01*
X1428433Y456217D01*
X1428600Y455800D01*
X1428642Y455425D01*
X1428558Y455050D01*
X1428433Y454800D01*
X1428183Y454550D01*
X1427892Y454383D01*
X1427600Y454300D01*
X1427308D01*
X1427017Y454383D01*
X1426767Y454508D01*
X1426558Y454675D01*
G01X1425417Y454800D02*
X1425167Y454508D01*
X1424833Y454342D01*
X1424458Y454300D01*
X1424125Y454342D01*
X1423792Y454550D01*
X1423583Y454800D01*
X1423542Y455050D01*
X1423625Y455342D01*
X1423917Y455550D01*
X1424208Y455633D01*
X1424583D01*
G01X1424208D02*
X1423958Y455758D01*
X1423750Y455967D01*
X1423667Y456217D01*
X1423750Y456467D01*
X1423958Y456675D01*
X1424333Y456800D01*
X1424708Y456758D01*
X1425083Y456592D01*
G01X1422483Y454300D02*
Y456800D01*
X1421400Y454717D01*
X1420317Y456800D01*
Y454300D01*
G01X1419217Y454800D02*
X1418967Y454508D01*
X1418633Y454342D01*
X1418258Y454300D01*
X1417925Y454342D01*
X1417592Y454550D01*
X1417383Y454800D01*
X1417342Y455050D01*
X1417425Y455342D01*
X1417717Y455550D01*
X1418008Y455633D01*
X1418383D01*
G01X1418008D02*
X1417758Y455758D01*
X1417550Y455967D01*
X1417467Y456217D01*
X1417550Y456467D01*
X1417758Y456675D01*
X1418133Y456800D01*
X1418508Y456758D01*
X1418883Y456592D01*
G01X1415283Y454300D02*
X1415200Y454842D01*
X1415075Y455300D01*
X1414908Y455717D01*
X1414700Y456175D01*
X1414367Y456800D01*
X1416033D01*
G01X1442183Y420878D02*
X1442433Y421003D01*
X1442725Y421086D01*
X1443058D01*
X1443433Y420961D01*
X1443725Y420753D01*
X1443933Y420503D01*
X1444100Y420086D01*
X1444142Y419711D01*
X1444058Y419336D01*
X1443933Y419086D01*
X1443683Y418836D01*
X1443392Y418669D01*
X1443100Y418586D01*
X1442808D01*
X1442517Y418669D01*
X1442267Y418794D01*
X1442058Y418961D01*
G01X1440917Y419086D02*
X1440667Y418794D01*
X1440333Y418628D01*
X1439958Y418586D01*
X1439625Y418628D01*
X1439292Y418836D01*
X1439083Y419086D01*
X1439042Y419336D01*
X1439125Y419628D01*
X1439417Y419836D01*
X1439708Y419919D01*
X1440083D01*
G01X1439708D02*
X1439458Y420044D01*
X1439250Y420253D01*
X1439167Y420503D01*
X1439250Y420753D01*
X1439458Y420961D01*
X1439833Y421086D01*
X1440208Y421044D01*
X1440583Y420878D01*
G01X1437858Y418586D02*
Y421086D01*
X1435942Y418586D01*
Y421086D01*
G01X1433800Y418586D02*
Y421086D01*
X1434300Y420586D01*
G01Y418586D02*
X1433300D01*
G01X1431617Y419086D02*
X1431367Y418794D01*
X1431033Y418628D01*
X1430658Y418586D01*
X1430325Y418628D01*
X1429992Y418836D01*
X1429783Y419086D01*
X1429742Y419336D01*
X1429825Y419628D01*
X1430117Y419836D01*
X1430408Y419919D01*
X1430783D01*
G01X1430408D02*
X1430158Y420044D01*
X1429950Y420253D01*
X1429867Y420503D01*
X1429950Y420753D01*
X1430158Y420961D01*
X1430533Y421086D01*
X1430908Y421044D01*
X1431283Y420878D01*
G01X1426583Y445592D02*
X1426833Y445717D01*
X1427125Y445800D01*
X1427458D01*
X1427833Y445675D01*
X1428125Y445467D01*
X1428333Y445217D01*
X1428500Y444800D01*
X1428542Y444425D01*
X1428458Y444050D01*
X1428333Y443800D01*
X1428083Y443550D01*
X1427792Y443383D01*
X1427500Y443300D01*
X1427208D01*
X1426917Y443383D01*
X1426667Y443508D01*
X1426458Y443675D01*
G01X1425317Y443800D02*
X1425067Y443508D01*
X1424733Y443342D01*
X1424358Y443300D01*
X1424025Y443342D01*
X1423692Y443550D01*
X1423483Y443800D01*
X1423442Y444050D01*
X1423525Y444342D01*
X1423817Y444550D01*
X1424108Y444633D01*
X1424483D01*
G01X1424108D02*
X1423858Y444758D01*
X1423650Y444967D01*
X1423567Y445217D01*
X1423650Y445467D01*
X1423858Y445675D01*
X1424233Y445800D01*
X1424608Y445758D01*
X1424983Y445592D01*
G01X1422383Y443300D02*
Y445800D01*
X1421300Y443717D01*
X1420217Y445800D01*
Y443300D01*
G01X1417700D02*
Y445800D01*
X1419242Y444008D01*
X1417158D01*
G01X1416017Y443675D02*
X1415767Y443467D01*
X1415475Y443342D01*
X1415100Y443300D01*
X1414725Y443383D01*
X1414433Y443550D01*
X1414225Y443842D01*
X1414183Y444175D01*
X1414267Y444508D01*
X1414475Y444717D01*
X1414767Y444883D01*
X1415058Y444925D01*
X1415350Y444883D01*
X1415725Y444717D01*
X1415600Y445800D01*
X1414475D01*
G01X1410734Y406452D02*
X1410859Y406202D01*
X1410942Y405910D01*
Y405577D01*
X1410817Y405202D01*
X1410609Y404910D01*
X1410359Y404702D01*
X1409942Y404535D01*
X1409567Y404493D01*
X1409192Y404577D01*
X1408942Y404702D01*
X1408692Y404952D01*
X1408525Y405243D01*
X1408442Y405535D01*
Y405827D01*
X1408525Y406118D01*
X1408650Y406368D01*
X1408817Y406577D01*
G01X1410525Y407843D02*
X1410775Y408093D01*
X1410900Y408385D01*
X1410942Y408718D01*
X1410859Y409135D01*
X1410650Y409427D01*
X1410400Y409510D01*
X1410150Y409468D01*
X1409942Y409302D01*
X1409525Y408468D01*
X1409234Y408093D01*
X1408817Y407843D01*
X1408442Y407760D01*
Y409510D01*
G01X1410525Y410943D02*
X1410775Y411193D01*
X1410900Y411485D01*
X1410942Y411818D01*
X1410859Y412235D01*
X1410650Y412527D01*
X1410400Y412610D01*
X1410150Y412568D01*
X1409942Y412402D01*
X1409525Y411568D01*
X1409234Y411193D01*
X1408817Y410943D01*
X1408442Y410860D01*
Y412610D01*
G01X1410942Y413585D02*
X1408442Y414168D01*
X1410942Y414835D01*
X1408442Y415502D01*
X1410942Y416085D01*
G01X1408942Y417018D02*
X1408650Y417268D01*
X1408484Y417602D01*
X1408442Y417977D01*
X1408484Y418310D01*
X1408692Y418643D01*
X1408942Y418852D01*
X1409192Y418893D01*
X1409484Y418810D01*
X1409692Y418518D01*
X1409775Y418227D01*
Y417852D01*
G01Y418227D02*
X1409900Y418477D01*
X1410109Y418685D01*
X1410359Y418768D01*
X1410609Y418685D01*
X1410817Y418477D01*
X1410942Y418102D01*
X1410900Y417727D01*
X1410734Y417352D01*
G01X1408942Y420118D02*
X1408650Y420368D01*
X1408484Y420702D01*
X1408442Y421077D01*
X1408484Y421410D01*
X1408692Y421743D01*
X1408942Y421952D01*
X1409192Y421993D01*
X1409484Y421910D01*
X1409692Y421618D01*
X1409775Y421327D01*
Y420952D01*
G01Y421327D02*
X1409900Y421577D01*
X1410109Y421785D01*
X1410359Y421868D01*
X1410609Y421785D01*
X1410817Y421577D01*
X1410942Y421202D01*
X1410900Y420827D01*
X1410734Y420452D01*
G01X1419500Y508117D02*
X1422000D01*
Y509158D01*
X1421875Y509492D01*
X1421708Y509700D01*
X1421375Y509783D01*
X1421042Y509700D01*
X1420833Y509450D01*
X1420708Y509158D01*
Y508117D01*
G01Y509158D02*
X1419500Y509783D01*
G01X1420000Y511133D02*
X1419708Y511383D01*
X1419542Y511717D01*
X1419500Y512092D01*
X1419542Y512425D01*
X1419750Y512758D01*
X1420000Y512967D01*
X1420250Y513008D01*
X1420542Y512925D01*
X1420750Y512633D01*
X1420833Y512342D01*
Y511967D01*
G01Y512342D02*
X1420958Y512592D01*
X1421167Y512800D01*
X1421417Y512883D01*
X1421667Y512800D01*
X1421875Y512592D01*
X1422000Y512217D01*
X1421958Y511842D01*
X1421792Y511467D01*
G01X1419500Y514067D02*
X1422000D01*
X1419917Y515150D01*
X1422000Y516233D01*
X1419500D01*
G01X1419875Y517333D02*
X1419667Y517583D01*
X1419542Y517875D01*
X1419500Y518250D01*
X1419583Y518625D01*
X1419750Y518917D01*
X1420042Y519125D01*
X1420375Y519167D01*
X1420708Y519083D01*
X1420917Y518875D01*
X1421083Y518583D01*
X1421125Y518292D01*
X1421083Y518000D01*
X1420917Y517625D01*
X1422000Y517750D01*
Y518875D01*
G01X1415500Y508117D02*
X1418000D01*
Y509158D01*
X1417875Y509492D01*
X1417708Y509700D01*
X1417375Y509783D01*
X1417042Y509700D01*
X1416833Y509450D01*
X1416708Y509158D01*
Y508117D01*
G01Y509158D02*
X1415500Y509783D01*
G01X1416000Y511133D02*
X1415708Y511383D01*
X1415542Y511717D01*
X1415500Y512092D01*
X1415542Y512425D01*
X1415750Y512758D01*
X1416000Y512967D01*
X1416250Y513008D01*
X1416542Y512925D01*
X1416750Y512633D01*
X1416833Y512342D01*
Y511967D01*
G01Y512342D02*
X1416958Y512592D01*
X1417167Y512800D01*
X1417417Y512883D01*
X1417667Y512800D01*
X1417875Y512592D01*
X1418000Y512217D01*
X1417958Y511842D01*
X1417792Y511467D01*
G01X1415500Y514067D02*
X1418000D01*
X1415917Y515150D01*
X1418000Y516233D01*
X1415500D01*
G01X1416542Y517458D02*
X1416833Y517750D01*
X1417000Y518000D01*
X1417083Y518333D01*
X1417000Y518625D01*
X1416833Y518833D01*
X1416583Y519000D01*
X1416292Y519042D01*
X1416042Y519000D01*
X1415792Y518833D01*
X1415583Y518583D01*
X1415500Y518292D01*
X1415583Y517958D01*
X1415833Y517667D01*
X1416208Y517500D01*
X1416625Y517458D01*
X1417167Y517542D01*
X1417458Y517667D01*
X1417750Y517875D01*
X1417958Y518167D01*
X1418000Y518458D01*
X1417917Y518750D01*
X1417708Y518958D01*
G01X1411500Y508117D02*
X1414000D01*
Y509158D01*
X1413875Y509492D01*
X1413708Y509700D01*
X1413375Y509783D01*
X1413042Y509700D01*
X1412833Y509450D01*
X1412708Y509158D01*
Y508117D01*
G01Y509158D02*
X1411500Y509783D01*
G01X1412000Y511133D02*
X1411708Y511383D01*
X1411542Y511717D01*
X1411500Y512092D01*
X1411542Y512425D01*
X1411750Y512758D01*
X1412000Y512967D01*
X1412250Y513008D01*
X1412542Y512925D01*
X1412750Y512633D01*
X1412833Y512342D01*
Y511967D01*
G01Y512342D02*
X1412958Y512592D01*
X1413167Y512800D01*
X1413417Y512883D01*
X1413667Y512800D01*
X1413875Y512592D01*
X1414000Y512217D01*
X1413958Y511842D01*
X1413792Y511467D01*
G01X1411500Y514067D02*
X1414000D01*
X1411917Y515150D01*
X1414000Y516233D01*
X1411500D01*
G01X1412000Y517333D02*
X1411708Y517583D01*
X1411542Y517917D01*
X1411500Y518292D01*
X1411542Y518625D01*
X1411750Y518958D01*
X1412000Y519167D01*
X1412250Y519208D01*
X1412542Y519125D01*
X1412750Y518833D01*
X1412833Y518542D01*
Y518167D01*
G01Y518542D02*
X1412958Y518792D01*
X1413167Y519000D01*
X1413417Y519083D01*
X1413667Y519000D01*
X1413875Y518792D01*
X1414000Y518417D01*
X1413958Y518042D01*
X1413792Y517667D01*
G01X1452597Y473223D02*
Y475723D01*
X1451556D01*
X1451222Y475598D01*
X1451014Y475431D01*
X1450931Y475098D01*
X1451014Y474765D01*
X1451264Y474556D01*
X1451556Y474431D01*
X1452597D01*
G01X1451556D02*
X1450931Y473223D01*
G01X1448747D02*
X1448664Y473765D01*
X1448539Y474223D01*
X1448372Y474640D01*
X1448164Y475098D01*
X1447831Y475723D01*
X1449497D01*
G01X1445564Y473223D02*
X1445272Y473265D01*
X1444939Y473390D01*
X1444731Y473598D01*
X1444647Y473890D01*
X1444731Y474181D01*
X1444981Y474431D01*
X1445356Y474556D01*
X1445772D01*
X1446022Y474640D01*
X1446231Y474848D01*
X1446314Y475140D01*
X1446189Y475431D01*
X1445897Y475640D01*
X1445564Y475723D01*
X1445231Y475640D01*
X1444939Y475431D01*
X1444814Y475140D01*
X1444897Y474848D01*
X1445106Y474640D01*
X1445356Y474556D01*
X1445772D01*
X1446147Y474431D01*
X1446397Y474181D01*
X1446481Y473890D01*
X1446397Y473598D01*
X1446189Y473390D01*
X1445856Y473265D01*
X1445564Y473223D01*
G01X1441964D02*
Y475723D01*
X1443506Y473931D01*
X1441422D01*
G01X1452497Y468323D02*
Y470823D01*
X1451456D01*
X1451122Y470698D01*
X1450914Y470531D01*
X1450831Y470198D01*
X1450914Y469865D01*
X1451164Y469656D01*
X1451456Y469531D01*
X1452497D01*
G01X1451456D02*
X1450831Y468323D01*
G01X1448647D02*
X1448564Y468865D01*
X1448439Y469323D01*
X1448272Y469740D01*
X1448064Y470198D01*
X1447731Y470823D01*
X1449397D01*
G01X1445464Y468323D02*
X1445172Y468365D01*
X1444839Y468490D01*
X1444631Y468698D01*
X1444547Y468990D01*
X1444631Y469281D01*
X1444881Y469531D01*
X1445256Y469656D01*
X1445672D01*
X1445922Y469740D01*
X1446131Y469948D01*
X1446214Y470240D01*
X1446089Y470531D01*
X1445797Y470740D01*
X1445464Y470823D01*
X1445131Y470740D01*
X1444839Y470531D01*
X1444714Y470240D01*
X1444797Y469948D01*
X1445006Y469740D01*
X1445256Y469656D01*
X1445672D01*
X1446047Y469531D01*
X1446297Y469281D01*
X1446381Y468990D01*
X1446297Y468698D01*
X1446089Y468490D01*
X1445756Y468365D01*
X1445464Y468323D01*
G01X1443281Y468698D02*
X1443031Y468490D01*
X1442739Y468365D01*
X1442364Y468323D01*
X1441989Y468406D01*
X1441697Y468573D01*
X1441489Y468865D01*
X1441447Y469198D01*
X1441531Y469531D01*
X1441739Y469740D01*
X1442031Y469906D01*
X1442322Y469948D01*
X1442614Y469906D01*
X1442989Y469740D01*
X1442864Y470823D01*
X1441739D01*
G01X1454333Y497100D02*
Y499600D01*
X1453292D01*
X1452958Y499475D01*
X1452750Y499308D01*
X1452667Y498975D01*
X1452750Y498642D01*
X1453000Y498433D01*
X1453292Y498308D01*
X1454333D01*
G01X1453292D02*
X1452667Y497100D01*
G01X1450483D02*
X1450400Y497642D01*
X1450275Y498100D01*
X1450108Y498517D01*
X1449900Y498975D01*
X1449567Y499600D01*
X1451233D01*
G01X1447300Y497100D02*
X1447008Y497142D01*
X1446675Y497267D01*
X1446467Y497475D01*
X1446383Y497767D01*
X1446467Y498058D01*
X1446717Y498308D01*
X1447092Y498433D01*
X1447508D01*
X1447758Y498517D01*
X1447967Y498725D01*
X1448050Y499017D01*
X1447925Y499308D01*
X1447633Y499517D01*
X1447300Y499600D01*
X1446967Y499517D01*
X1446675Y499308D01*
X1446550Y499017D01*
X1446633Y498725D01*
X1446842Y498517D01*
X1447092Y498433D01*
X1447508D01*
X1447883Y498308D01*
X1448133Y498058D01*
X1448217Y497767D01*
X1448133Y497475D01*
X1447925Y497267D01*
X1447592Y497142D01*
X1447300Y497100D01*
G01X1445117Y497600D02*
X1444867Y497308D01*
X1444533Y497142D01*
X1444158Y497100D01*
X1443825Y497142D01*
X1443492Y497350D01*
X1443283Y497600D01*
X1443242Y497850D01*
X1443325Y498142D01*
X1443617Y498350D01*
X1443908Y498433D01*
X1444283D01*
G01X1443908D02*
X1443658Y498558D01*
X1443450Y498767D01*
X1443367Y499017D01*
X1443450Y499267D01*
X1443658Y499475D01*
X1444033Y499600D01*
X1444408Y499558D01*
X1444783Y499392D01*
G01X1454483Y503250D02*
Y505750D01*
X1453442D01*
X1453108Y505625D01*
X1452900Y505458D01*
X1452817Y505125D01*
X1452900Y504792D01*
X1453150Y504583D01*
X1453442Y504458D01*
X1454483D01*
G01X1453442D02*
X1452817Y503250D01*
G01X1450633D02*
X1450550Y503792D01*
X1450425Y504250D01*
X1450258Y504667D01*
X1450050Y505125D01*
X1449717Y505750D01*
X1451383D01*
G01X1447450Y503250D02*
X1447158Y503292D01*
X1446825Y503417D01*
X1446617Y503625D01*
X1446533Y503917D01*
X1446617Y504208D01*
X1446867Y504458D01*
X1447242Y504583D01*
X1447658D01*
X1447908Y504667D01*
X1448117Y504875D01*
X1448200Y505167D01*
X1448075Y505458D01*
X1447783Y505667D01*
X1447450Y505750D01*
X1447117Y505667D01*
X1446825Y505458D01*
X1446700Y505167D01*
X1446783Y504875D01*
X1446992Y504667D01*
X1447242Y504583D01*
X1447658D01*
X1448033Y504458D01*
X1448283Y504208D01*
X1448367Y503917D01*
X1448283Y503625D01*
X1448075Y503417D01*
X1447742Y503292D01*
X1447450Y503250D01*
G01X1445142Y505333D02*
X1444892Y505583D01*
X1444600Y505708D01*
X1444267Y505750D01*
X1443850Y505667D01*
X1443558Y505458D01*
X1443475Y505208D01*
X1443517Y504958D01*
X1443683Y504750D01*
X1444517Y504333D01*
X1444892Y504042D01*
X1445142Y503625D01*
X1445225Y503250D01*
X1443475D01*
G01X1417337Y469086D02*
Y471586D01*
X1416296D01*
X1415962Y471461D01*
X1415754Y471294D01*
X1415671Y470961D01*
X1415754Y470628D01*
X1416004Y470419D01*
X1416296Y470294D01*
X1417337D01*
G01X1416296D02*
X1415671Y469086D01*
G01X1413487D02*
X1413404Y469628D01*
X1413279Y470086D01*
X1413112Y470503D01*
X1412904Y470961D01*
X1412571Y471586D01*
X1414237D01*
G01X1410387Y469086D02*
X1410304Y469628D01*
X1410179Y470086D01*
X1410012Y470503D01*
X1409804Y470961D01*
X1409471Y471586D01*
X1411137D01*
G01X1407204Y469086D02*
X1406912Y469128D01*
X1406579Y469253D01*
X1406371Y469461D01*
X1406287Y469753D01*
X1406371Y470044D01*
X1406621Y470294D01*
X1406996Y470419D01*
X1407412D01*
X1407662Y470503D01*
X1407871Y470711D01*
X1407954Y471003D01*
X1407829Y471294D01*
X1407537Y471503D01*
X1407204Y471586D01*
X1406871Y471503D01*
X1406579Y471294D01*
X1406454Y471003D01*
X1406537Y470711D01*
X1406746Y470503D01*
X1406996Y470419D01*
X1407412D01*
X1407787Y470294D01*
X1408037Y470044D01*
X1408121Y469753D01*
X1408037Y469461D01*
X1407829Y469253D01*
X1407496Y469128D01*
X1407204Y469086D01*
G01X1425724Y502023D02*
Y504523D01*
X1424683D01*
X1424349Y504398D01*
X1424141Y504231D01*
X1424058Y503898D01*
X1424141Y503565D01*
X1424391Y503356D01*
X1424683Y503231D01*
X1425724D01*
G01X1424683D02*
X1424058Y502023D01*
G01X1421874D02*
X1421791Y502565D01*
X1421666Y503023D01*
X1421499Y503440D01*
X1421291Y503898D01*
X1420958Y504523D01*
X1422624D01*
G01X1418691Y502023D02*
X1418399Y502065D01*
X1418066Y502190D01*
X1417858Y502398D01*
X1417774Y502690D01*
X1417858Y502981D01*
X1418108Y503231D01*
X1418483Y503356D01*
X1418899D01*
X1419149Y503440D01*
X1419358Y503648D01*
X1419441Y503940D01*
X1419316Y504231D01*
X1419024Y504440D01*
X1418691Y504523D01*
X1418358Y504440D01*
X1418066Y504231D01*
X1417941Y503940D01*
X1418024Y503648D01*
X1418233Y503440D01*
X1418483Y503356D01*
X1418899D01*
X1419274Y503231D01*
X1419524Y502981D01*
X1419608Y502690D01*
X1419524Y502398D01*
X1419316Y502190D01*
X1418983Y502065D01*
X1418691Y502023D01*
G01X1415591D02*
Y504523D01*
X1416091Y504023D01*
G01Y502023D02*
X1415091D01*
G01X1425724Y497623D02*
Y500123D01*
X1424683D01*
X1424349Y499998D01*
X1424141Y499831D01*
X1424058Y499498D01*
X1424141Y499165D01*
X1424391Y498956D01*
X1424683Y498831D01*
X1425724D01*
G01X1424683D02*
X1424058Y497623D01*
G01X1421874D02*
X1421791Y498165D01*
X1421666Y498623D01*
X1421499Y499040D01*
X1421291Y499498D01*
X1420958Y500123D01*
X1422624D01*
G01X1418691Y497623D02*
X1418399Y497665D01*
X1418066Y497790D01*
X1417858Y497998D01*
X1417774Y498290D01*
X1417858Y498581D01*
X1418108Y498831D01*
X1418483Y498956D01*
X1418899D01*
X1419149Y499040D01*
X1419358Y499248D01*
X1419441Y499540D01*
X1419316Y499831D01*
X1419024Y500040D01*
X1418691Y500123D01*
X1418358Y500040D01*
X1418066Y499831D01*
X1417941Y499540D01*
X1418024Y499248D01*
X1418233Y499040D01*
X1418483Y498956D01*
X1418899D01*
X1419274Y498831D01*
X1419524Y498581D01*
X1419608Y498290D01*
X1419524Y497998D01*
X1419316Y497790D01*
X1418983Y497665D01*
X1418691Y497623D01*
G01X1415591Y500123D02*
X1415924Y500040D01*
X1416174Y499831D01*
X1416341Y499581D01*
X1416466Y499248D01*
X1416508Y498873D01*
X1416466Y498498D01*
X1416341Y498165D01*
X1416174Y497915D01*
X1415924Y497706D01*
X1415591Y497623D01*
X1415258Y497706D01*
X1415008Y497915D01*
X1414841Y498165D01*
X1414716Y498498D01*
X1414674Y498873D01*
X1414716Y499248D01*
X1414841Y499581D01*
X1415008Y499831D01*
X1415258Y500040D01*
X1415591Y500123D01*
G01X1453620Y525101D02*
X1453870Y525226D01*
X1454162Y525309D01*
X1454495D01*
X1454870Y525184D01*
X1455162Y524976D01*
X1455370Y524726D01*
X1455537Y524309D01*
X1455579Y523934D01*
X1455495Y523559D01*
X1455370Y523309D01*
X1455120Y523059D01*
X1454829Y522892D01*
X1454537Y522809D01*
X1454245D01*
X1453954Y522892D01*
X1453704Y523017D01*
X1453495Y523184D01*
G01X1452354Y523309D02*
X1452104Y523017D01*
X1451770Y522851D01*
X1451395Y522809D01*
X1451062Y522851D01*
X1450729Y523059D01*
X1450520Y523309D01*
X1450479Y523559D01*
X1450562Y523851D01*
X1450854Y524059D01*
X1451145Y524142D01*
X1451520D01*
G01X1451145D02*
X1450895Y524267D01*
X1450687Y524476D01*
X1450604Y524726D01*
X1450687Y524976D01*
X1450895Y525184D01*
X1451270Y525309D01*
X1451645Y525267D01*
X1452020Y525101D01*
G01X1449420Y522809D02*
Y525309D01*
X1448337Y523226D01*
X1447254Y525309D01*
Y522809D01*
G01X1446029Y524892D02*
X1445779Y525142D01*
X1445487Y525267D01*
X1445154Y525309D01*
X1444737Y525226D01*
X1444445Y525017D01*
X1444362Y524767D01*
X1444404Y524517D01*
X1444570Y524309D01*
X1445404Y523892D01*
X1445779Y523601D01*
X1446029Y523184D01*
X1446112Y522809D01*
X1444362D01*
G01X1441637D02*
Y525309D01*
X1443179Y523517D01*
X1441095D01*
G01X1444782Y528411D02*
X1444907Y528161D01*
X1444990Y527869D01*
Y527536D01*
X1444865Y527161D01*
X1444657Y526869D01*
X1444407Y526661D01*
X1443990Y526494D01*
X1443615Y526452D01*
X1443240Y526536D01*
X1442990Y526661D01*
X1442740Y526911D01*
X1442573Y527202D01*
X1442490Y527494D01*
Y527786D01*
X1442573Y528077D01*
X1442698Y528327D01*
X1442865Y528536D01*
G01X1442990Y529677D02*
X1442698Y529927D01*
X1442532Y530261D01*
X1442490Y530636D01*
X1442532Y530969D01*
X1442740Y531302D01*
X1442990Y531511D01*
X1443240Y531552D01*
X1443532Y531469D01*
X1443740Y531177D01*
X1443823Y530886D01*
Y530511D01*
G01Y530886D02*
X1443948Y531136D01*
X1444157Y531344D01*
X1444407Y531427D01*
X1444657Y531344D01*
X1444865Y531136D01*
X1444990Y530761D01*
X1444948Y530386D01*
X1444782Y530011D01*
G01X1442490Y532611D02*
X1444990D01*
X1442907Y533694D01*
X1444990Y534777D01*
X1442490D01*
G01X1444573Y536002D02*
X1444823Y536252D01*
X1444948Y536544D01*
X1444990Y536877D01*
X1444907Y537294D01*
X1444698Y537586D01*
X1444448Y537669D01*
X1444198Y537627D01*
X1443990Y537461D01*
X1443573Y536627D01*
X1443282Y536252D01*
X1442865Y536002D01*
X1442490Y535919D01*
Y537669D01*
G01X1444573Y539102D02*
X1444823Y539352D01*
X1444948Y539644D01*
X1444990Y539977D01*
X1444907Y540394D01*
X1444698Y540686D01*
X1444448Y540769D01*
X1444198Y540727D01*
X1443990Y540561D01*
X1443573Y539727D01*
X1443282Y539352D01*
X1442865Y539102D01*
X1442490Y539019D01*
Y540769D01*
G01X1445121Y509151D02*
X1445246Y508901D01*
X1445329Y508609D01*
Y508276D01*
X1445204Y507901D01*
X1444996Y507609D01*
X1444746Y507401D01*
X1444329Y507234D01*
X1443954Y507192D01*
X1443579Y507276D01*
X1443329Y507401D01*
X1443079Y507651D01*
X1442912Y507942D01*
X1442829Y508234D01*
Y508526D01*
X1442912Y508817D01*
X1443037Y509067D01*
X1443204Y509276D01*
G01X1443329Y510417D02*
X1443037Y510667D01*
X1442871Y511001D01*
X1442829Y511376D01*
X1442871Y511709D01*
X1443079Y512042D01*
X1443329Y512251D01*
X1443579Y512292D01*
X1443871Y512209D01*
X1444079Y511917D01*
X1444162Y511626D01*
Y511251D01*
G01Y511626D02*
X1444287Y511876D01*
X1444496Y512084D01*
X1444746Y512167D01*
X1444996Y512084D01*
X1445204Y511876D01*
X1445329Y511501D01*
X1445287Y511126D01*
X1445121Y510751D01*
G01X1442829Y513351D02*
X1445329D01*
X1443246Y514434D01*
X1445329Y515517D01*
X1442829D01*
G01X1443329Y516617D02*
X1443037Y516867D01*
X1442871Y517201D01*
X1442829Y517576D01*
X1442871Y517909D01*
X1443079Y518242D01*
X1443329Y518451D01*
X1443579Y518492D01*
X1443871Y518409D01*
X1444079Y518117D01*
X1444162Y517826D01*
Y517451D01*
G01Y517826D02*
X1444287Y518076D01*
X1444496Y518284D01*
X1444746Y518367D01*
X1444996Y518284D01*
X1445204Y518076D01*
X1445329Y517701D01*
X1445287Y517326D01*
X1445121Y516951D01*
G01X1442829Y520634D02*
X1445329D01*
X1444829Y520134D01*
G01X1442829D02*
Y521134D01*
G01X1432397Y468915D02*
X1432647Y469040D01*
X1432939Y469123D01*
X1433272D01*
X1433647Y468998D01*
X1433939Y468790D01*
X1434147Y468540D01*
X1434314Y468123D01*
X1434356Y467748D01*
X1434272Y467373D01*
X1434147Y467123D01*
X1433897Y466873D01*
X1433606Y466706D01*
X1433314Y466623D01*
X1433022D01*
X1432731Y466706D01*
X1432481Y466831D01*
X1432272Y466998D01*
G01X1431131Y467123D02*
X1430881Y466831D01*
X1430547Y466665D01*
X1430172Y466623D01*
X1429839Y466665D01*
X1429506Y466873D01*
X1429297Y467123D01*
X1429256Y467373D01*
X1429339Y467665D01*
X1429631Y467873D01*
X1429922Y467956D01*
X1430297D01*
G01X1429922D02*
X1429672Y468081D01*
X1429464Y468290D01*
X1429381Y468540D01*
X1429464Y468790D01*
X1429672Y468998D01*
X1430047Y469123D01*
X1430422Y469081D01*
X1430797Y468915D01*
G01X1428197Y466623D02*
Y469123D01*
X1427114Y467040D01*
X1426031Y469123D01*
Y466623D01*
G01X1424806Y468706D02*
X1424556Y468956D01*
X1424264Y469081D01*
X1423931Y469123D01*
X1423514Y469040D01*
X1423222Y468831D01*
X1423139Y468581D01*
X1423181Y468331D01*
X1423347Y468123D01*
X1424181Y467706D01*
X1424556Y467415D01*
X1424806Y466998D01*
X1424889Y466623D01*
X1423139D01*
G01X1421831Y466998D02*
X1421581Y466790D01*
X1421289Y466665D01*
X1420914Y466623D01*
X1420539Y466706D01*
X1420247Y466873D01*
X1420039Y467165D01*
X1419997Y467498D01*
X1420081Y467831D01*
X1420289Y468040D01*
X1420581Y468206D01*
X1420872Y468248D01*
X1421164Y468206D01*
X1421539Y468040D01*
X1421414Y469123D01*
X1420289D01*
G01X1468133Y499542D02*
X1468383Y499667D01*
X1468675Y499750D01*
X1469008D01*
X1469383Y499625D01*
X1469675Y499417D01*
X1469883Y499167D01*
X1470050Y498750D01*
X1470092Y498375D01*
X1470008Y498000D01*
X1469883Y497750D01*
X1469633Y497500D01*
X1469342Y497333D01*
X1469050Y497250D01*
X1468758D01*
X1468467Y497333D01*
X1468217Y497458D01*
X1468008Y497625D01*
G01X1466867Y497750D02*
X1466617Y497458D01*
X1466283Y497292D01*
X1465908Y497250D01*
X1465575Y497292D01*
X1465242Y497500D01*
X1465033Y497750D01*
X1464992Y498000D01*
X1465075Y498292D01*
X1465367Y498500D01*
X1465658Y498583D01*
X1466033D01*
G01X1465658D02*
X1465408Y498708D01*
X1465200Y498917D01*
X1465117Y499167D01*
X1465200Y499417D01*
X1465408Y499625D01*
X1465783Y499750D01*
X1466158Y499708D01*
X1466533Y499542D01*
G01X1463933Y497250D02*
Y499750D01*
X1462850Y497667D01*
X1461767Y499750D01*
Y497250D01*
G01X1460667Y497750D02*
X1460417Y497458D01*
X1460083Y497292D01*
X1459708Y497250D01*
X1459375Y497292D01*
X1459042Y497500D01*
X1458833Y497750D01*
X1458792Y498000D01*
X1458875Y498292D01*
X1459167Y498500D01*
X1459458Y498583D01*
X1459833D01*
G01X1459458D02*
X1459208Y498708D01*
X1459000Y498917D01*
X1458917Y499167D01*
X1459000Y499417D01*
X1459208Y499625D01*
X1459583Y499750D01*
X1459958Y499708D01*
X1460333Y499542D01*
G01X1457442Y498292D02*
X1457150Y498583D01*
X1456900Y498750D01*
X1456567Y498833D01*
X1456275Y498750D01*
X1456067Y498583D01*
X1455900Y498333D01*
X1455858Y498042D01*
X1455900Y497792D01*
X1456067Y497542D01*
X1456317Y497333D01*
X1456608Y497250D01*
X1456942Y497333D01*
X1457233Y497583D01*
X1457400Y497958D01*
X1457442Y498375D01*
X1457358Y498917D01*
X1457233Y499208D01*
X1457025Y499500D01*
X1456733Y499708D01*
X1456442Y499750D01*
X1456150Y499667D01*
X1455942Y499458D01*
G01X1468933Y505642D02*
X1469183Y505767D01*
X1469475Y505850D01*
X1469808D01*
X1470183Y505725D01*
X1470475Y505517D01*
X1470683Y505267D01*
X1470850Y504850D01*
X1470892Y504475D01*
X1470808Y504100D01*
X1470683Y503850D01*
X1470433Y503600D01*
X1470142Y503433D01*
X1469850Y503350D01*
X1469558D01*
X1469267Y503433D01*
X1469017Y503558D01*
X1468808Y503725D01*
G01X1467667Y503850D02*
X1467417Y503558D01*
X1467083Y503392D01*
X1466708Y503350D01*
X1466375Y503392D01*
X1466042Y503600D01*
X1465833Y503850D01*
X1465792Y504100D01*
X1465875Y504392D01*
X1466167Y504600D01*
X1466458Y504683D01*
X1466833D01*
G01X1466458D02*
X1466208Y504808D01*
X1466000Y505017D01*
X1465917Y505267D01*
X1466000Y505517D01*
X1466208Y505725D01*
X1466583Y505850D01*
X1466958Y505808D01*
X1467333Y505642D01*
G01X1464733Y503350D02*
Y505850D01*
X1463650Y503767D01*
X1462567Y505850D01*
Y503350D01*
G01X1461467Y503850D02*
X1461217Y503558D01*
X1460883Y503392D01*
X1460508Y503350D01*
X1460175Y503392D01*
X1459842Y503600D01*
X1459633Y503850D01*
X1459592Y504100D01*
X1459675Y504392D01*
X1459967Y504600D01*
X1460258Y504683D01*
X1460633D01*
G01X1460258D02*
X1460008Y504808D01*
X1459800Y505017D01*
X1459717Y505267D01*
X1459800Y505517D01*
X1460008Y505725D01*
X1460383Y505850D01*
X1460758Y505808D01*
X1461133Y505642D01*
G01X1458367Y503725D02*
X1458117Y503517D01*
X1457825Y503392D01*
X1457450Y503350D01*
X1457075Y503433D01*
X1456783Y503600D01*
X1456575Y503892D01*
X1456533Y504225D01*
X1456617Y504558D01*
X1456825Y504767D01*
X1457117Y504933D01*
X1457408Y504975D01*
X1457700Y504933D01*
X1458075Y504767D01*
X1457950Y505850D01*
X1456825D01*
G01X1466947Y475265D02*
X1467197Y475390D01*
X1467489Y475473D01*
X1467822D01*
X1468197Y475348D01*
X1468489Y475140D01*
X1468697Y474890D01*
X1468864Y474473D01*
X1468906Y474098D01*
X1468822Y473723D01*
X1468697Y473473D01*
X1468447Y473223D01*
X1468156Y473056D01*
X1467864Y472973D01*
X1467572D01*
X1467281Y473056D01*
X1467031Y473181D01*
X1466822Y473348D01*
G01X1465681Y473473D02*
X1465431Y473181D01*
X1465097Y473015D01*
X1464722Y472973D01*
X1464389Y473015D01*
X1464056Y473223D01*
X1463847Y473473D01*
X1463806Y473723D01*
X1463889Y474015D01*
X1464181Y474223D01*
X1464472Y474306D01*
X1464847D01*
G01X1464472D02*
X1464222Y474431D01*
X1464014Y474640D01*
X1463931Y474890D01*
X1464014Y475140D01*
X1464222Y475348D01*
X1464597Y475473D01*
X1464972Y475431D01*
X1465347Y475265D01*
G01X1462747Y472973D02*
Y475473D01*
X1461664Y473390D01*
X1460581Y475473D01*
Y472973D01*
G01X1459481Y473473D02*
X1459231Y473181D01*
X1458897Y473015D01*
X1458522Y472973D01*
X1458189Y473015D01*
X1457856Y473223D01*
X1457647Y473473D01*
X1457606Y473723D01*
X1457689Y474015D01*
X1457981Y474223D01*
X1458272Y474306D01*
X1458647D01*
G01X1458272D02*
X1458022Y474431D01*
X1457814Y474640D01*
X1457731Y474890D01*
X1457814Y475140D01*
X1458022Y475348D01*
X1458397Y475473D01*
X1458772Y475431D01*
X1459147Y475265D01*
G01X1456381Y473473D02*
X1456131Y473181D01*
X1455797Y473015D01*
X1455422Y472973D01*
X1455089Y473015D01*
X1454756Y473223D01*
X1454547Y473473D01*
X1454506Y473723D01*
X1454589Y474015D01*
X1454881Y474223D01*
X1455172Y474306D01*
X1455547D01*
G01X1455172D02*
X1454922Y474431D01*
X1454714Y474640D01*
X1454631Y474890D01*
X1454714Y475140D01*
X1454922Y475348D01*
X1455297Y475473D01*
X1455672Y475431D01*
X1456047Y475265D01*
G01X1467047Y470765D02*
X1467297Y470890D01*
X1467589Y470973D01*
X1467922D01*
X1468297Y470848D01*
X1468589Y470640D01*
X1468797Y470390D01*
X1468964Y469973D01*
X1469006Y469598D01*
X1468922Y469223D01*
X1468797Y468973D01*
X1468547Y468723D01*
X1468256Y468556D01*
X1467964Y468473D01*
X1467672D01*
X1467381Y468556D01*
X1467131Y468681D01*
X1466922Y468848D01*
G01X1465781Y468973D02*
X1465531Y468681D01*
X1465197Y468515D01*
X1464822Y468473D01*
X1464489Y468515D01*
X1464156Y468723D01*
X1463947Y468973D01*
X1463906Y469223D01*
X1463989Y469515D01*
X1464281Y469723D01*
X1464572Y469806D01*
X1464947D01*
G01X1464572D02*
X1464322Y469931D01*
X1464114Y470140D01*
X1464031Y470390D01*
X1464114Y470640D01*
X1464322Y470848D01*
X1464697Y470973D01*
X1465072Y470931D01*
X1465447Y470765D01*
G01X1462847Y468473D02*
Y470973D01*
X1461764Y468890D01*
X1460681Y470973D01*
Y468473D01*
G01X1459581Y468973D02*
X1459331Y468681D01*
X1458997Y468515D01*
X1458622Y468473D01*
X1458289Y468515D01*
X1457956Y468723D01*
X1457747Y468973D01*
X1457706Y469223D01*
X1457789Y469515D01*
X1458081Y469723D01*
X1458372Y469806D01*
X1458747D01*
G01X1458372D02*
X1458122Y469931D01*
X1457914Y470140D01*
X1457831Y470390D01*
X1457914Y470640D01*
X1458122Y470848D01*
X1458497Y470973D01*
X1458872Y470931D01*
X1459247Y470765D01*
G01X1455064Y468473D02*
Y470973D01*
X1456606Y469181D01*
X1454522D01*
G01X1439974Y499365D02*
X1440224Y499490D01*
X1440516Y499573D01*
X1440849D01*
X1441224Y499448D01*
X1441516Y499240D01*
X1441724Y498990D01*
X1441891Y498573D01*
X1441933Y498198D01*
X1441849Y497823D01*
X1441724Y497573D01*
X1441474Y497323D01*
X1441183Y497156D01*
X1440891Y497073D01*
X1440599D01*
X1440308Y497156D01*
X1440058Y497281D01*
X1439849Y497448D01*
G01X1438708Y497573D02*
X1438458Y497281D01*
X1438124Y497115D01*
X1437749Y497073D01*
X1437416Y497115D01*
X1437083Y497323D01*
X1436874Y497573D01*
X1436833Y497823D01*
X1436916Y498115D01*
X1437208Y498323D01*
X1437499Y498406D01*
X1437874D01*
G01X1437499D02*
X1437249Y498531D01*
X1437041Y498740D01*
X1436958Y498990D01*
X1437041Y499240D01*
X1437249Y499448D01*
X1437624Y499573D01*
X1437999Y499531D01*
X1438374Y499365D01*
G01X1435774Y497073D02*
Y499573D01*
X1434691Y497490D01*
X1433608Y499573D01*
Y497073D01*
G01X1432508Y497573D02*
X1432258Y497281D01*
X1431924Y497115D01*
X1431549Y497073D01*
X1431216Y497115D01*
X1430883Y497323D01*
X1430674Y497573D01*
X1430633Y497823D01*
X1430716Y498115D01*
X1431008Y498323D01*
X1431299Y498406D01*
X1431674D01*
G01X1431299D02*
X1431049Y498531D01*
X1430841Y498740D01*
X1430758Y498990D01*
X1430841Y499240D01*
X1431049Y499448D01*
X1431424Y499573D01*
X1431799Y499531D01*
X1432174Y499365D01*
G01X1429283Y499156D02*
X1429033Y499406D01*
X1428741Y499531D01*
X1428408Y499573D01*
X1427991Y499490D01*
X1427699Y499281D01*
X1427616Y499031D01*
X1427658Y498781D01*
X1427824Y498573D01*
X1428658Y498156D01*
X1429033Y497865D01*
X1429283Y497448D01*
X1429366Y497073D01*
X1427616D01*
G01X1439974Y503765D02*
X1440224Y503890D01*
X1440516Y503973D01*
X1440849D01*
X1441224Y503848D01*
X1441516Y503640D01*
X1441724Y503390D01*
X1441891Y502973D01*
X1441933Y502598D01*
X1441849Y502223D01*
X1441724Y501973D01*
X1441474Y501723D01*
X1441183Y501556D01*
X1440891Y501473D01*
X1440599D01*
X1440308Y501556D01*
X1440058Y501681D01*
X1439849Y501848D01*
G01X1438708Y501973D02*
X1438458Y501681D01*
X1438124Y501515D01*
X1437749Y501473D01*
X1437416Y501515D01*
X1437083Y501723D01*
X1436874Y501973D01*
X1436833Y502223D01*
X1436916Y502515D01*
X1437208Y502723D01*
X1437499Y502806D01*
X1437874D01*
G01X1437499D02*
X1437249Y502931D01*
X1437041Y503140D01*
X1436958Y503390D01*
X1437041Y503640D01*
X1437249Y503848D01*
X1437624Y503973D01*
X1437999Y503931D01*
X1438374Y503765D01*
G01X1435774Y501473D02*
Y503973D01*
X1434691Y501890D01*
X1433608Y503973D01*
Y501473D01*
G01X1432383Y503556D02*
X1432133Y503806D01*
X1431841Y503931D01*
X1431508Y503973D01*
X1431091Y503890D01*
X1430799Y503681D01*
X1430716Y503431D01*
X1430758Y503181D01*
X1430924Y502973D01*
X1431758Y502556D01*
X1432133Y502265D01*
X1432383Y501848D01*
X1432466Y501473D01*
X1430716D01*
G01X1428491D02*
X1428199Y501515D01*
X1427866Y501640D01*
X1427658Y501848D01*
X1427574Y502140D01*
X1427658Y502431D01*
X1427908Y502681D01*
X1428283Y502806D01*
X1428699D01*
X1428949Y502890D01*
X1429158Y503098D01*
X1429241Y503390D01*
X1429116Y503681D01*
X1428824Y503890D01*
X1428491Y503973D01*
X1428158Y503890D01*
X1427866Y503681D01*
X1427741Y503390D01*
X1427824Y503098D01*
X1428033Y502890D01*
X1428283Y502806D01*
X1428699D01*
X1429074Y502681D01*
X1429324Y502431D01*
X1429408Y502140D01*
X1429324Y501848D01*
X1429116Y501640D01*
X1428783Y501515D01*
X1428491Y501473D01*
G01X1432397Y473315D02*
X1432647Y473440D01*
X1432939Y473523D01*
X1433272D01*
X1433647Y473398D01*
X1433939Y473190D01*
X1434147Y472940D01*
X1434314Y472523D01*
X1434356Y472148D01*
X1434272Y471773D01*
X1434147Y471523D01*
X1433897Y471273D01*
X1433606Y471106D01*
X1433314Y471023D01*
X1433022D01*
X1432731Y471106D01*
X1432481Y471231D01*
X1432272Y471398D01*
G01X1431131Y471523D02*
X1430881Y471231D01*
X1430547Y471065D01*
X1430172Y471023D01*
X1429839Y471065D01*
X1429506Y471273D01*
X1429297Y471523D01*
X1429256Y471773D01*
X1429339Y472065D01*
X1429631Y472273D01*
X1429922Y472356D01*
X1430297D01*
G01X1429922D02*
X1429672Y472481D01*
X1429464Y472690D01*
X1429381Y472940D01*
X1429464Y473190D01*
X1429672Y473398D01*
X1430047Y473523D01*
X1430422Y473481D01*
X1430797Y473315D01*
G01X1428197Y471023D02*
Y473523D01*
X1427114Y471440D01*
X1426031Y473523D01*
Y471023D01*
G01X1424806Y473106D02*
X1424556Y473356D01*
X1424264Y473481D01*
X1423931Y473523D01*
X1423514Y473440D01*
X1423222Y473231D01*
X1423139Y472981D01*
X1423181Y472731D01*
X1423347Y472523D01*
X1424181Y472106D01*
X1424556Y471815D01*
X1424806Y471398D01*
X1424889Y471023D01*
X1423139D01*
G01X1421706Y472065D02*
X1421414Y472356D01*
X1421164Y472523D01*
X1420831Y472606D01*
X1420539Y472523D01*
X1420331Y472356D01*
X1420164Y472106D01*
X1420122Y471815D01*
X1420164Y471565D01*
X1420331Y471315D01*
X1420581Y471106D01*
X1420872Y471023D01*
X1421206Y471106D01*
X1421497Y471356D01*
X1421664Y471731D01*
X1421706Y472148D01*
X1421622Y472690D01*
X1421497Y472981D01*
X1421289Y473273D01*
X1420997Y473481D01*
X1420706Y473523D01*
X1420414Y473440D01*
X1420206Y473231D01*
G01X1446829Y507542D02*
X1449329D01*
Y509126D01*
G01X1448121Y508542D02*
Y507542D01*
G01X1448162Y511767D02*
X1448287Y511934D01*
X1448496Y512059D01*
X1448787Y512142D01*
X1449037Y512059D01*
X1449204Y511892D01*
X1449329Y511601D01*
Y510476D01*
X1446829D01*
Y511851D01*
X1446996Y512142D01*
X1447246Y512309D01*
X1447537Y512392D01*
X1447829Y512309D01*
X1448079Y512059D01*
X1448162Y511767D01*
Y510476D01*
G01X1447329Y513617D02*
X1447037Y513867D01*
X1446871Y514201D01*
X1446829Y514576D01*
X1446871Y514909D01*
X1447079Y515242D01*
X1447329Y515451D01*
X1447579Y515492D01*
X1447871Y515409D01*
X1448079Y515117D01*
X1448162Y514826D01*
Y514451D01*
G01Y514826D02*
X1448287Y515076D01*
X1448496Y515284D01*
X1448746Y515367D01*
X1448996Y515284D01*
X1449204Y515076D01*
X1449329Y514701D01*
X1449287Y514326D01*
X1449121Y513951D01*
G01X1446829Y516551D02*
X1449329D01*
X1447246Y517634D01*
X1449329Y518717D01*
X1446829D01*
G01Y521234D02*
X1449329D01*
X1447537Y519692D01*
Y521776D01*
G01X1447348Y526762D02*
X1449848D01*
Y528346D01*
G01X1448640Y527762D02*
Y526762D01*
G01X1448681Y530987D02*
X1448806Y531154D01*
X1449015Y531279D01*
X1449306Y531362D01*
X1449556Y531279D01*
X1449723Y531112D01*
X1449848Y530821D01*
Y529696D01*
X1447348D01*
Y531071D01*
X1447515Y531362D01*
X1447765Y531529D01*
X1448056Y531612D01*
X1448348Y531529D01*
X1448598Y531279D01*
X1448681Y530987D01*
Y529696D01*
G01X1447848Y532837D02*
X1447556Y533087D01*
X1447390Y533421D01*
X1447348Y533796D01*
X1447390Y534129D01*
X1447598Y534462D01*
X1447848Y534671D01*
X1448098Y534712D01*
X1448390Y534629D01*
X1448598Y534337D01*
X1448681Y534046D01*
Y533671D01*
G01Y534046D02*
X1448806Y534296D01*
X1449015Y534504D01*
X1449265Y534587D01*
X1449515Y534504D01*
X1449723Y534296D01*
X1449848Y533921D01*
X1449806Y533546D01*
X1449640Y533171D01*
G01X1447348Y535771D02*
X1449848D01*
X1447765Y536854D01*
X1449848Y537937D01*
X1447348D01*
G01X1449431Y539162D02*
X1449681Y539412D01*
X1449806Y539704D01*
X1449848Y540037D01*
X1449765Y540454D01*
X1449556Y540746D01*
X1449306Y540829D01*
X1449056Y540787D01*
X1448848Y540621D01*
X1448431Y539787D01*
X1448140Y539412D01*
X1447723Y539162D01*
X1447348Y539079D01*
Y540829D01*
G01X1426483Y539900D02*
Y542400D01*
X1425442D01*
X1425108Y542275D01*
X1424900Y542108D01*
X1424817Y541775D01*
X1424900Y541442D01*
X1425150Y541233D01*
X1425442Y541108D01*
X1426483D01*
G01X1425442D02*
X1424817Y539900D01*
G01X1423467Y540400D02*
X1423217Y540108D01*
X1422883Y539942D01*
X1422508Y539900D01*
X1422175Y539942D01*
X1421842Y540150D01*
X1421633Y540400D01*
X1421592Y540650D01*
X1421675Y540942D01*
X1421967Y541150D01*
X1422258Y541233D01*
X1422633D01*
G01X1422258D02*
X1422008Y541358D01*
X1421800Y541567D01*
X1421717Y541817D01*
X1421800Y542067D01*
X1422008Y542275D01*
X1422383Y542400D01*
X1422758Y542358D01*
X1423133Y542192D01*
G01X1420283Y542400D02*
Y539900D01*
X1418617D01*
G01X1416350D02*
Y542400D01*
X1416850Y541900D01*
G01Y539900D02*
X1415850D01*
G01X1414167Y540400D02*
X1413917Y540108D01*
X1413583Y539942D01*
X1413208Y539900D01*
X1412875Y539942D01*
X1412542Y540150D01*
X1412333Y540400D01*
X1412292Y540650D01*
X1412375Y540942D01*
X1412667Y541150D01*
X1412958Y541233D01*
X1413333D01*
G01X1412958D02*
X1412708Y541358D01*
X1412500Y541567D01*
X1412417Y541817D01*
X1412500Y542067D01*
X1412708Y542275D01*
X1413083Y542400D01*
X1413458Y542358D01*
X1413833Y542192D01*
G01X1426633Y543900D02*
Y546400D01*
X1425592D01*
X1425258Y546275D01*
X1425050Y546108D01*
X1424967Y545775D01*
X1425050Y545442D01*
X1425300Y545233D01*
X1425592Y545108D01*
X1426633D01*
G01X1425592D02*
X1424967Y543900D01*
G01X1423617Y544400D02*
X1423367Y544108D01*
X1423033Y543942D01*
X1422658Y543900D01*
X1422325Y543942D01*
X1421992Y544150D01*
X1421783Y544400D01*
X1421742Y544650D01*
X1421825Y544942D01*
X1422117Y545150D01*
X1422408Y545233D01*
X1422783D01*
G01X1422408D02*
X1422158Y545358D01*
X1421950Y545567D01*
X1421867Y545817D01*
X1421950Y546067D01*
X1422158Y546275D01*
X1422533Y546400D01*
X1422908Y546358D01*
X1423283Y546192D01*
G01X1420433Y546400D02*
Y543900D01*
X1418767D01*
G01X1416500D02*
Y546400D01*
X1417000Y545900D01*
G01Y543900D02*
X1416000D01*
G01X1413400D02*
Y546400D01*
X1413900Y545900D01*
G01Y543900D02*
X1412900D01*
G01X1453104Y544162D02*
X1453354Y544287D01*
X1453646Y544370D01*
X1453979D01*
X1454354Y544245D01*
X1454646Y544037D01*
X1454854Y543787D01*
X1455021Y543370D01*
X1455063Y542995D01*
X1454979Y542620D01*
X1454854Y542370D01*
X1454604Y542120D01*
X1454313Y541953D01*
X1454021Y541870D01*
X1453729D01*
X1453438Y541953D01*
X1453188Y542078D01*
X1452979Y542245D01*
G01X1451838Y542370D02*
X1451588Y542078D01*
X1451254Y541912D01*
X1450879Y541870D01*
X1450546Y541912D01*
X1450213Y542120D01*
X1450004Y542370D01*
X1449963Y542620D01*
X1450046Y542912D01*
X1450338Y543120D01*
X1450629Y543203D01*
X1451004D01*
G01X1450629D02*
X1450379Y543328D01*
X1450171Y543537D01*
X1450088Y543787D01*
X1450171Y544037D01*
X1450379Y544245D01*
X1450754Y544370D01*
X1451129Y544328D01*
X1451504Y544162D01*
G01X1448904Y541870D02*
Y544370D01*
X1447821Y542287D01*
X1446738Y544370D01*
Y541870D01*
G01X1444721D02*
Y544370D01*
X1445221Y543870D01*
G01Y541870D02*
X1444221D01*
G01X1441621D02*
X1441329Y541912D01*
X1440996Y542037D01*
X1440788Y542245D01*
X1440704Y542537D01*
X1440788Y542828D01*
X1441038Y543078D01*
X1441413Y543203D01*
X1441829D01*
X1442079Y543287D01*
X1442288Y543495D01*
X1442371Y543787D01*
X1442246Y544078D01*
X1441954Y544287D01*
X1441621Y544370D01*
X1441288Y544287D01*
X1440996Y544078D01*
X1440871Y543787D01*
X1440954Y543495D01*
X1441163Y543287D01*
X1441413Y543203D01*
X1441829D01*
X1442204Y543078D01*
X1442454Y542828D01*
X1442538Y542537D01*
X1442454Y542245D01*
X1442246Y542037D01*
X1441913Y541912D01*
X1441621Y541870D01*
G01X1465520Y564919D02*
X1465645Y564669D01*
X1465728Y564377D01*
Y564044D01*
X1465603Y563669D01*
X1465395Y563377D01*
X1465145Y563169D01*
X1464728Y563002D01*
X1464353Y562960D01*
X1463978Y563044D01*
X1463728Y563169D01*
X1463478Y563419D01*
X1463311Y563710D01*
X1463228Y564002D01*
Y564294D01*
X1463311Y564585D01*
X1463436Y564835D01*
X1463603Y565044D01*
G01X1463728Y566185D02*
X1463436Y566435D01*
X1463270Y566769D01*
X1463228Y567144D01*
X1463270Y567477D01*
X1463478Y567810D01*
X1463728Y568019D01*
X1463978Y568060D01*
X1464270Y567977D01*
X1464478Y567685D01*
X1464561Y567394D01*
Y567019D01*
G01Y567394D02*
X1464686Y567644D01*
X1464895Y567852D01*
X1465145Y567935D01*
X1465395Y567852D01*
X1465603Y567644D01*
X1465728Y567269D01*
X1465686Y566894D01*
X1465520Y566519D01*
G01X1465728Y569369D02*
X1463228D01*
Y571035D01*
G01X1465311Y572510D02*
X1465561Y572760D01*
X1465686Y573052D01*
X1465728Y573385D01*
X1465645Y573802D01*
X1465436Y574094D01*
X1465186Y574177D01*
X1464936Y574135D01*
X1464728Y573969D01*
X1464311Y573135D01*
X1464020Y572760D01*
X1463603Y572510D01*
X1463228Y572427D01*
Y574177D01*
G01Y576402D02*
X1465728D01*
X1465228Y575902D01*
G01X1463228D02*
Y576902D01*
G01X1469200Y547136D02*
X1465409D01*
Y559932D01*
X1469200D01*
G01X1439459Y551217D02*
X1439584Y550967D01*
X1439667Y550675D01*
Y550342D01*
X1439542Y549967D01*
X1439334Y549675D01*
X1439084Y549467D01*
X1438667Y549300D01*
X1438292Y549258D01*
X1437917Y549342D01*
X1437667Y549467D01*
X1437417Y549717D01*
X1437250Y550008D01*
X1437167Y550300D01*
Y550592D01*
X1437250Y550883D01*
X1437375Y551133D01*
X1437542Y551342D01*
G01X1437667Y552483D02*
X1437375Y552733D01*
X1437209Y553067D01*
X1437167Y553442D01*
X1437209Y553775D01*
X1437417Y554108D01*
X1437667Y554317D01*
X1437917Y554358D01*
X1438209Y554275D01*
X1438417Y553983D01*
X1438500Y553692D01*
Y553317D01*
G01Y553692D02*
X1438625Y553942D01*
X1438834Y554150D01*
X1439084Y554233D01*
X1439334Y554150D01*
X1439542Y553942D01*
X1439667Y553567D01*
X1439625Y553192D01*
X1439459Y552817D01*
G01X1439667Y555667D02*
X1437167D01*
Y557333D01*
G01Y559600D02*
X1439667D01*
X1439167Y559100D01*
G01X1437167D02*
Y560100D01*
G01Y562700D02*
X1437209Y562992D01*
X1437334Y563325D01*
X1437542Y563533D01*
X1437834Y563617D01*
X1438125Y563533D01*
X1438375Y563283D01*
X1438500Y562908D01*
Y562492D01*
X1438584Y562242D01*
X1438792Y562033D01*
X1439084Y561950D01*
X1439375Y562075D01*
X1439584Y562367D01*
X1439667Y562700D01*
X1439584Y563033D01*
X1439375Y563325D01*
X1439084Y563450D01*
X1438792Y563367D01*
X1438584Y563158D01*
X1438500Y562908D01*
Y562492D01*
X1438375Y562117D01*
X1438125Y561867D01*
X1437834Y561783D01*
X1437542Y561867D01*
X1437334Y562075D01*
X1437209Y562408D01*
X1437167Y562700D01*
G01X1445300Y548936D02*
X1441509D01*
Y561732D01*
X1445300D01*
G01X1457900Y548936D02*
X1461462D01*
Y561732D01*
X1457900D01*
G01X1460600Y584300D02*
X1457902D01*
G01X1442600D02*
X1445295D01*
G01X1442600D02*
Y561728D01*
G01X1460600Y584300D02*
Y561725D01*
G01X1416733Y554859D02*
X1416983Y554984D01*
X1417275Y555067D01*
X1417608D01*
X1417983Y554942D01*
X1418275Y554734D01*
X1418483Y554484D01*
X1418650Y554067D01*
X1418692Y553692D01*
X1418608Y553317D01*
X1418483Y553067D01*
X1418233Y552817D01*
X1417942Y552650D01*
X1417650Y552567D01*
X1417358D01*
X1417067Y552650D01*
X1416817Y552775D01*
X1416608Y552942D01*
G01X1415342Y552567D02*
Y555067D01*
X1413758D01*
G01X1414342Y553859D02*
X1415342D01*
G01X1411450Y552567D02*
Y555067D01*
X1411950Y554567D01*
G01Y552567D02*
X1410950D01*
G01X1408350D02*
X1408058Y552609D01*
X1407725Y552734D01*
X1407517Y552942D01*
X1407433Y553234D01*
X1407517Y553525D01*
X1407767Y553775D01*
X1408142Y553900D01*
X1408558D01*
X1408808Y553984D01*
X1409017Y554192D01*
X1409100Y554484D01*
X1408975Y554775D01*
X1408683Y554984D01*
X1408350Y555067D01*
X1408017Y554984D01*
X1407725Y554775D01*
X1407600Y554484D01*
X1407683Y554192D01*
X1407892Y553984D01*
X1408142Y553900D01*
X1408558D01*
X1408933Y553775D01*
X1409183Y553525D01*
X1409267Y553234D01*
X1409183Y552942D01*
X1408975Y552734D01*
X1408642Y552609D01*
X1408350Y552567D01*
G01X1431133Y555092D02*
X1431383Y555217D01*
X1431675Y555300D01*
X1432008D01*
X1432383Y555175D01*
X1432675Y554967D01*
X1432883Y554717D01*
X1433050Y554300D01*
X1433092Y553925D01*
X1433008Y553550D01*
X1432883Y553300D01*
X1432633Y553050D01*
X1432342Y552883D01*
X1432050Y552800D01*
X1431758D01*
X1431467Y552883D01*
X1431217Y553008D01*
X1431008Y553175D01*
G01X1429742Y552800D02*
Y555300D01*
X1428158D01*
G01X1428742Y554092D02*
X1429742D01*
G01X1425850Y552800D02*
Y555300D01*
X1426350Y554800D01*
G01Y552800D02*
X1425350D01*
G01X1422833D02*
X1422750Y553342D01*
X1422625Y553800D01*
X1422458Y554217D01*
X1422250Y554675D01*
X1421917Y555300D01*
X1423583D01*
G01X1423733Y568792D02*
X1423983Y568917D01*
X1424275Y569000D01*
X1424608D01*
X1424983Y568875D01*
X1425275Y568667D01*
X1425483Y568417D01*
X1425650Y568000D01*
X1425692Y567625D01*
X1425608Y567250D01*
X1425483Y567000D01*
X1425233Y566750D01*
X1424942Y566583D01*
X1424650Y566500D01*
X1424358D01*
X1424067Y566583D01*
X1423817Y566708D01*
X1423608Y566875D01*
G01X1421633Y566500D02*
X1421550Y567042D01*
X1421425Y567500D01*
X1421258Y567917D01*
X1421050Y568375D01*
X1420717Y569000D01*
X1422383D01*
G01X1419700D02*
X1419117Y566500D01*
X1418450Y569000D01*
X1417783Y566500D01*
X1417200Y569000D01*
G01X1415433Y566500D02*
X1415350Y567042D01*
X1415225Y567500D01*
X1415058Y567917D01*
X1414850Y568375D01*
X1414517Y569000D01*
X1416183D01*
G01X1423733Y583592D02*
X1423983Y583717D01*
X1424275Y583800D01*
X1424608D01*
X1424983Y583675D01*
X1425275Y583467D01*
X1425483Y583217D01*
X1425650Y582800D01*
X1425692Y582425D01*
X1425608Y582050D01*
X1425483Y581800D01*
X1425233Y581550D01*
X1424942Y581383D01*
X1424650Y581300D01*
X1424358D01*
X1424067Y581383D01*
X1423817Y581508D01*
X1423608Y581675D01*
G01X1421633Y581300D02*
X1421550Y581842D01*
X1421425Y582300D01*
X1421258Y582717D01*
X1421050Y583175D01*
X1420717Y583800D01*
X1422383D01*
G01X1419700D02*
X1419117Y581300D01*
X1418450Y583800D01*
X1417783Y581300D01*
X1417200Y583800D01*
G01X1416142Y582342D02*
X1415850Y582633D01*
X1415600Y582800D01*
X1415267Y582883D01*
X1414975Y582800D01*
X1414767Y582633D01*
X1414600Y582383D01*
X1414558Y582092D01*
X1414600Y581842D01*
X1414767Y581592D01*
X1415017Y581383D01*
X1415308Y581300D01*
X1415642Y581383D01*
X1415933Y581633D01*
X1416100Y582008D01*
X1416142Y582425D01*
X1416058Y582967D01*
X1415933Y583258D01*
X1415725Y583550D01*
X1415433Y583758D01*
X1415142Y583800D01*
X1414850Y583717D01*
X1414642Y583508D01*
G01X1443489Y590168D02*
X1443614Y589918D01*
X1443697Y589626D01*
Y589293D01*
X1443572Y588918D01*
X1443364Y588626D01*
X1443114Y588418D01*
X1442697Y588251D01*
X1442322Y588209D01*
X1441947Y588293D01*
X1441697Y588418D01*
X1441447Y588668D01*
X1441280Y588959D01*
X1441197Y589251D01*
Y589543D01*
X1441280Y589834D01*
X1441405Y590084D01*
X1441572Y590293D01*
G01X1441197Y592268D02*
X1441739Y592351D01*
X1442197Y592476D01*
X1442614Y592643D01*
X1443072Y592851D01*
X1443697Y593184D01*
Y591518D01*
G01Y594201D02*
X1441197Y594784D01*
X1443697Y595451D01*
X1441197Y596118D01*
X1443697Y596701D01*
G01X1441197Y598551D02*
X1443697D01*
X1443197Y598051D01*
G01X1441197D02*
Y599051D01*
G01X1443280Y600859D02*
X1443530Y601109D01*
X1443655Y601401D01*
X1443697Y601734D01*
X1443614Y602151D01*
X1443405Y602443D01*
X1443155Y602526D01*
X1442905Y602484D01*
X1442697Y602318D01*
X1442280Y601484D01*
X1441989Y601109D01*
X1441572Y600859D01*
X1441197Y600776D01*
Y602526D01*
G01X1439859Y584567D02*
X1439984Y584317D01*
X1440067Y584025D01*
Y583692D01*
X1439942Y583317D01*
X1439734Y583025D01*
X1439484Y582817D01*
X1439067Y582650D01*
X1438692Y582608D01*
X1438317Y582692D01*
X1438067Y582817D01*
X1437817Y583067D01*
X1437650Y583358D01*
X1437567Y583650D01*
Y583942D01*
X1437650Y584233D01*
X1437775Y584483D01*
X1437942Y584692D01*
G01X1439650Y585958D02*
X1439900Y586208D01*
X1440025Y586500D01*
X1440067Y586833D01*
X1439984Y587250D01*
X1439775Y587542D01*
X1439525Y587625D01*
X1439275Y587583D01*
X1439067Y587417D01*
X1438650Y586583D01*
X1438359Y586208D01*
X1437942Y585958D01*
X1437567Y585875D01*
Y587625D01*
G01X1439650Y589058D02*
X1439900Y589308D01*
X1440025Y589600D01*
X1440067Y589933D01*
X1439984Y590350D01*
X1439775Y590642D01*
X1439525Y590725D01*
X1439275Y590683D01*
X1439067Y590517D01*
X1438650Y589683D01*
X1438359Y589308D01*
X1437942Y589058D01*
X1437567Y588975D01*
Y590725D01*
G01X1440067Y591700D02*
X1437567Y592283D01*
X1440067Y592950D01*
X1437567Y593617D01*
X1440067Y594200D01*
G01X1439650Y595258D02*
X1439900Y595508D01*
X1440025Y595800D01*
X1440067Y596133D01*
X1439984Y596550D01*
X1439775Y596842D01*
X1439525Y596925D01*
X1439275Y596883D01*
X1439067Y596717D01*
X1438650Y595883D01*
X1438359Y595508D01*
X1437942Y595258D01*
X1437567Y595175D01*
Y596925D01*
G01X1438067Y598233D02*
X1437775Y598483D01*
X1437609Y598817D01*
X1437567Y599192D01*
X1437609Y599525D01*
X1437817Y599858D01*
X1438067Y600067D01*
X1438317Y600108D01*
X1438609Y600025D01*
X1438817Y599733D01*
X1438900Y599442D01*
Y599067D01*
G01Y599442D02*
X1439025Y599692D01*
X1439234Y599900D01*
X1439484Y599983D01*
X1439734Y599900D01*
X1439942Y599692D01*
X1440067Y599317D01*
X1440025Y598942D01*
X1439859Y598567D01*
G01X1436159Y584067D02*
X1436284Y583817D01*
X1436367Y583525D01*
Y583192D01*
X1436242Y582817D01*
X1436034Y582525D01*
X1435784Y582317D01*
X1435367Y582150D01*
X1434992Y582108D01*
X1434617Y582192D01*
X1434367Y582317D01*
X1434117Y582567D01*
X1433950Y582858D01*
X1433867Y583150D01*
Y583442D01*
X1433950Y583733D01*
X1434075Y583983D01*
X1434242Y584192D01*
G01X1435950Y585458D02*
X1436200Y585708D01*
X1436325Y586000D01*
X1436367Y586333D01*
X1436284Y586750D01*
X1436075Y587042D01*
X1435825Y587125D01*
X1435575Y587083D01*
X1435367Y586917D01*
X1434950Y586083D01*
X1434659Y585708D01*
X1434242Y585458D01*
X1433867Y585375D01*
Y587125D01*
G01X1435950Y588558D02*
X1436200Y588808D01*
X1436325Y589100D01*
X1436367Y589433D01*
X1436284Y589850D01*
X1436075Y590142D01*
X1435825Y590225D01*
X1435575Y590183D01*
X1435367Y590017D01*
X1434950Y589183D01*
X1434659Y588808D01*
X1434242Y588558D01*
X1433867Y588475D01*
Y590225D01*
G01X1436367Y591200D02*
X1433867Y591783D01*
X1436367Y592450D01*
X1433867Y593117D01*
X1436367Y593700D01*
G01X1435950Y594758D02*
X1436200Y595008D01*
X1436325Y595300D01*
X1436367Y595633D01*
X1436284Y596050D01*
X1436075Y596342D01*
X1435825Y596425D01*
X1435575Y596383D01*
X1435367Y596217D01*
X1434950Y595383D01*
X1434659Y595008D01*
X1434242Y594758D01*
X1433867Y594675D01*
Y596425D01*
G01Y598567D02*
X1434409Y598650D01*
X1434867Y598775D01*
X1435284Y598942D01*
X1435742Y599150D01*
X1436367Y599483D01*
Y597817D01*
G01X1431589Y581858D02*
X1431714Y581608D01*
X1431797Y581316D01*
Y580983D01*
X1431672Y580608D01*
X1431464Y580316D01*
X1431214Y580108D01*
X1430797Y579941D01*
X1430422Y579899D01*
X1430047Y579983D01*
X1429797Y580108D01*
X1429547Y580358D01*
X1429380Y580649D01*
X1429297Y580941D01*
Y581233D01*
X1429380Y581524D01*
X1429505Y581774D01*
X1429672Y581983D01*
G01X1431380Y583249D02*
X1431630Y583499D01*
X1431755Y583791D01*
X1431797Y584124D01*
X1431714Y584541D01*
X1431505Y584833D01*
X1431255Y584916D01*
X1431005Y584874D01*
X1430797Y584708D01*
X1430380Y583874D01*
X1430089Y583499D01*
X1429672Y583249D01*
X1429297Y583166D01*
Y584916D01*
G01X1431380Y586349D02*
X1431630Y586599D01*
X1431755Y586891D01*
X1431797Y587224D01*
X1431714Y587641D01*
X1431505Y587933D01*
X1431255Y588016D01*
X1431005Y587974D01*
X1430797Y587808D01*
X1430380Y586974D01*
X1430089Y586599D01*
X1429672Y586349D01*
X1429297Y586266D01*
Y588016D01*
G01X1431797Y588991D02*
X1429297Y589574D01*
X1431797Y590241D01*
X1429297Y590908D01*
X1431797Y591491D01*
G01X1431380Y592549D02*
X1431630Y592799D01*
X1431755Y593091D01*
X1431797Y593424D01*
X1431714Y593841D01*
X1431505Y594133D01*
X1431255Y594216D01*
X1431005Y594174D01*
X1430797Y594008D01*
X1430380Y593174D01*
X1430089Y592799D01*
X1429672Y592549D01*
X1429297Y592466D01*
Y594216D01*
G01X1430339Y595649D02*
X1430630Y595941D01*
X1430797Y596191D01*
X1430880Y596524D01*
X1430797Y596816D01*
X1430630Y597024D01*
X1430380Y597191D01*
X1430089Y597233D01*
X1429839Y597191D01*
X1429589Y597024D01*
X1429380Y596774D01*
X1429297Y596483D01*
X1429380Y596149D01*
X1429630Y595858D01*
X1430005Y595691D01*
X1430422Y595649D01*
X1430964Y595733D01*
X1431255Y595858D01*
X1431547Y596066D01*
X1431755Y596358D01*
X1431797Y596649D01*
X1431714Y596941D01*
X1431505Y597149D01*
G01X1405990Y535750D02*
Y528750D01*
G01X1406362Y546432D02*
Y539432D01*
G01X1463659Y611967D02*
X1463784Y611717D01*
X1463867Y611425D01*
Y611092D01*
X1463742Y610717D01*
X1463534Y610425D01*
X1463284Y610217D01*
X1462867Y610050D01*
X1462492Y610008D01*
X1462117Y610092D01*
X1461867Y610217D01*
X1461617Y610467D01*
X1461450Y610758D01*
X1461367Y611050D01*
Y611342D01*
X1461450Y611633D01*
X1461575Y611883D01*
X1461742Y612092D01*
G01X1461867Y613233D02*
X1461575Y613483D01*
X1461409Y613817D01*
X1461367Y614192D01*
X1461409Y614525D01*
X1461617Y614858D01*
X1461867Y615067D01*
X1462117Y615108D01*
X1462409Y615025D01*
X1462617Y614733D01*
X1462700Y614442D01*
Y614067D01*
G01Y614442D02*
X1462825Y614692D01*
X1463034Y614900D01*
X1463284Y614983D01*
X1463534Y614900D01*
X1463742Y614692D01*
X1463867Y614317D01*
X1463825Y613942D01*
X1463659Y613567D01*
G01X1463867Y616417D02*
X1461367D01*
Y618083D01*
G01Y620350D02*
X1463867D01*
X1463367Y619850D01*
G01X1461367D02*
Y620850D01*
G01X1470293Y593246D02*
X1470543Y593371D01*
X1470835Y593454D01*
X1471168D01*
X1471543Y593329D01*
X1471835Y593121D01*
X1472043Y592871D01*
X1472210Y592454D01*
X1472252Y592079D01*
X1472168Y591704D01*
X1472043Y591454D01*
X1471793Y591204D01*
X1471502Y591037D01*
X1471210Y590954D01*
X1470918D01*
X1470627Y591037D01*
X1470377Y591162D01*
X1470168Y591329D01*
G01X1468902Y593037D02*
X1468652Y593287D01*
X1468360Y593412D01*
X1468027Y593454D01*
X1467610Y593371D01*
X1467318Y593162D01*
X1467235Y592912D01*
X1467277Y592662D01*
X1467443Y592454D01*
X1468277Y592037D01*
X1468652Y591746D01*
X1468902Y591329D01*
X1468985Y590954D01*
X1467235D01*
G01X1465802Y593037D02*
X1465552Y593287D01*
X1465260Y593412D01*
X1464927Y593454D01*
X1464510Y593371D01*
X1464218Y593162D01*
X1464135Y592912D01*
X1464177Y592662D01*
X1464343Y592454D01*
X1465177Y592037D01*
X1465552Y591746D01*
X1465802Y591329D01*
X1465885Y590954D01*
X1464135D01*
G01X1463160Y593454D02*
X1462577Y590954D01*
X1461910Y593454D01*
X1461243Y590954D01*
X1460660Y593454D01*
G01X1459602Y593037D02*
X1459352Y593287D01*
X1459060Y593412D01*
X1458727Y593454D01*
X1458310Y593371D01*
X1458018Y593162D01*
X1457935Y592912D01*
X1457977Y592662D01*
X1458143Y592454D01*
X1458977Y592037D01*
X1459352Y591746D01*
X1459602Y591329D01*
X1459685Y590954D01*
X1457935D01*
G01X1455210D02*
Y593454D01*
X1456752Y591662D01*
X1454668D01*
G01X1413963Y594002D02*
X1414213Y594127D01*
X1414505Y594210D01*
X1414838D01*
X1415213Y594085D01*
X1415505Y593877D01*
X1415713Y593627D01*
X1415880Y593210D01*
X1415922Y592835D01*
X1415838Y592460D01*
X1415713Y592210D01*
X1415463Y591960D01*
X1415172Y591793D01*
X1414880Y591710D01*
X1414588D01*
X1414297Y591793D01*
X1414047Y591918D01*
X1413838Y592085D01*
G01X1411863Y591710D02*
X1411780Y592252D01*
X1411655Y592710D01*
X1411488Y593127D01*
X1411280Y593585D01*
X1410947Y594210D01*
X1412613D01*
G01X1409930D02*
X1409347Y591710D01*
X1408680Y594210D01*
X1408013Y591710D01*
X1407430Y594210D01*
G01X1405580Y591710D02*
X1405288Y591752D01*
X1404955Y591877D01*
X1404747Y592085D01*
X1404663Y592377D01*
X1404747Y592668D01*
X1404997Y592918D01*
X1405372Y593043D01*
X1405788D01*
X1406038Y593127D01*
X1406247Y593335D01*
X1406330Y593627D01*
X1406205Y593918D01*
X1405913Y594127D01*
X1405580Y594210D01*
X1405247Y594127D01*
X1404955Y593918D01*
X1404830Y593627D01*
X1404913Y593335D01*
X1405122Y593127D01*
X1405372Y593043D01*
X1405788D01*
X1406163Y592918D01*
X1406413Y592668D01*
X1406497Y592377D01*
X1406413Y592085D01*
X1406205Y591877D01*
X1405872Y591752D01*
X1405580Y591710D01*
G01X1603000Y-53600D02*
Y-56600D01*
X1601000D01*
G01X1598400D02*
Y-53600D01*
X1599000Y-54200D01*
G01Y-56600D02*
X1597800D01*
G01X1594200D02*
Y-53600D01*
X1596050Y-55750D01*
X1593550D01*
G01X1588600Y-53600D02*
Y-56600D01*
X1586600D01*
G01X1584000D02*
Y-53600D01*
X1584600Y-54200D01*
G01Y-56600D02*
X1583400D01*
G01X1581350Y-54100D02*
X1581050Y-53800D01*
X1580700Y-53650D01*
X1580300Y-53600D01*
X1579800Y-53700D01*
X1579450Y-53950D01*
X1579350Y-54250D01*
X1579400Y-54550D01*
X1579600Y-54800D01*
X1580600Y-55300D01*
X1581050Y-55650D01*
X1581350Y-56150D01*
X1581450Y-56600D01*
X1579350D01*
G01X1574200Y-53600D02*
Y-56600D01*
X1572200D01*
G01X1569600D02*
Y-53600D01*
X1570200Y-54200D01*
G01Y-56600D02*
X1569000D01*
G01X1566000Y-53600D02*
X1566400Y-53700D01*
X1566700Y-53950D01*
X1566900Y-54250D01*
X1567050Y-54650D01*
X1567100Y-55100D01*
X1567050Y-55550D01*
X1566900Y-55950D01*
X1566700Y-56250D01*
X1566400Y-56500D01*
X1566000Y-56600D01*
X1565600Y-56500D01*
X1565300Y-56250D01*
X1565100Y-55950D01*
X1564950Y-55550D01*
X1564900Y-55100D01*
X1564950Y-54650D01*
X1565100Y-54250D01*
X1565300Y-53950D01*
X1565600Y-53700D01*
X1566000Y-53600D01*
G01X1559800D02*
Y-56600D01*
X1557800D01*
G01X1555200D02*
Y-53600D01*
X1555800Y-54200D01*
G01Y-56600D02*
X1554600D01*
G01X1553100Y-57600D02*
X1550100D01*
G01X1548000Y-56600D02*
Y-53600D01*
X1548600Y-54200D01*
G01Y-56600D02*
X1547400D01*
G01X1544400Y-53600D02*
X1544800Y-53700D01*
X1545100Y-53950D01*
X1545300Y-54250D01*
X1545450Y-54650D01*
X1545500Y-55100D01*
X1545450Y-55550D01*
X1545300Y-55950D01*
X1545100Y-56250D01*
X1544800Y-56500D01*
X1544400Y-56600D01*
X1544000Y-56500D01*
X1543700Y-56250D01*
X1543500Y-55950D01*
X1543350Y-55550D01*
X1543300Y-55100D01*
X1543350Y-54650D01*
X1543500Y-54250D01*
X1543700Y-53950D01*
X1544000Y-53700D01*
X1544400Y-53600D01*
G01X1540800D02*
X1541200Y-53700D01*
X1541500Y-53950D01*
X1541700Y-54250D01*
X1541850Y-54650D01*
X1541900Y-55100D01*
X1541850Y-55550D01*
X1541700Y-55950D01*
X1541500Y-56250D01*
X1541200Y-56500D01*
X1540800Y-56600D01*
X1540400Y-56500D01*
X1540100Y-56250D01*
X1539900Y-55950D01*
X1539750Y-55550D01*
X1539700Y-55100D01*
X1539750Y-54650D01*
X1539900Y-54250D01*
X1540100Y-53950D01*
X1540400Y-53700D01*
X1540800Y-53600D01*
G01X1537200Y-56600D02*
X1537600Y-56550D01*
X1537950Y-56350D01*
X1538250Y-56050D01*
X1538450Y-55700D01*
X1538550Y-55300D01*
Y-54900D01*
X1538450Y-54500D01*
X1538250Y-54150D01*
X1537950Y-53850D01*
X1537600Y-53650D01*
X1537200Y-53600D01*
X1536800Y-53650D01*
X1536450Y-53850D01*
X1536150Y-54150D01*
X1535950Y-54500D01*
X1535850Y-54900D01*
Y-55300D01*
X1535950Y-55700D01*
X1536150Y-56050D01*
X1536450Y-56350D01*
X1536800Y-56550D01*
X1537200Y-56600D01*
G01X1534450D02*
Y-53600D01*
G01Y-55050D02*
X1534200Y-54800D01*
X1533950Y-54650D01*
X1533550Y-54600D01*
X1533250Y-54650D01*
X1532900Y-54850D01*
X1532750Y-55150D01*
Y-56600D01*
G01X1531500D02*
Y-54600D01*
G01Y-55150D02*
X1531350Y-54900D01*
X1531100Y-54700D01*
X1530750Y-54600D01*
X1530400Y-54700D01*
X1530150Y-54900D01*
X1530000Y-55150D01*
Y-56600D01*
G01Y-55150D02*
X1529850Y-54900D01*
X1529600Y-54700D01*
X1529250Y-54600D01*
X1528900Y-54700D01*
X1528650Y-54900D01*
X1528500Y-55200D01*
Y-56600D01*
G01X1527900Y-57600D02*
X1524900D01*
G01X1523900Y-56600D02*
Y-53600D01*
X1522900D01*
X1522500Y-53750D01*
X1522200Y-53950D01*
X1521950Y-54250D01*
X1521750Y-54600D01*
X1521700Y-55100D01*
X1521750Y-55600D01*
X1521950Y-55950D01*
X1522200Y-56250D01*
X1522500Y-56450D01*
X1522900Y-56600D01*
X1523900D01*
G01X1478487Y16367D02*
X1482076D01*
Y14474D01*
X1485355Y16367D01*
X1482076Y18260D01*
Y16367D01*
G01X1485355Y18260D02*
Y14474D01*
G01X1489778Y16367D02*
X1485355D01*
G01X1466400Y26867D02*
X1468900D01*
Y27908D01*
X1468775Y28242D01*
X1468608Y28450D01*
X1468275Y28533D01*
X1467942Y28450D01*
X1467733Y28200D01*
X1467608Y27908D01*
Y26867D01*
G01Y27908D02*
X1466400Y28533D01*
G01Y30717D02*
X1466942Y30800D01*
X1467400Y30925D01*
X1467817Y31092D01*
X1468275Y31300D01*
X1468900Y31633D01*
Y29967D01*
G01X1467650Y34150D02*
Y34983D01*
X1466900D01*
X1466650Y34733D01*
X1466483Y34442D01*
X1466400Y34025D01*
X1466483Y33608D01*
X1466650Y33317D01*
X1466900Y33067D01*
X1467192Y32900D01*
X1467525Y32817D01*
X1467817D01*
X1468067Y32900D01*
X1468358Y33067D01*
X1468608Y33317D01*
X1468775Y33567D01*
X1468900Y33900D01*
Y34192D01*
X1468817Y34525D01*
X1468650Y34775D01*
G01X1468483Y36208D02*
X1468733Y36458D01*
X1468858Y36750D01*
X1468900Y37083D01*
X1468817Y37500D01*
X1468608Y37792D01*
X1468358Y37875D01*
X1468108Y37833D01*
X1467900Y37667D01*
X1467483Y36833D01*
X1467192Y36458D01*
X1466775Y36208D01*
X1466400Y36125D01*
Y37875D01*
G01Y40017D02*
X1466942Y40100D01*
X1467400Y40225D01*
X1467817Y40392D01*
X1468275Y40600D01*
X1468900Y40933D01*
Y39267D01*
G01X1475900Y27967D02*
X1478400D01*
Y29008D01*
X1478275Y29342D01*
X1478108Y29550D01*
X1477775Y29633D01*
X1477442Y29550D01*
X1477233Y29300D01*
X1477108Y29008D01*
Y27967D01*
G01Y29008D02*
X1475900Y29633D01*
G01Y31817D02*
X1476442Y31900D01*
X1476900Y32025D01*
X1477317Y32192D01*
X1477775Y32400D01*
X1478400Y32733D01*
Y31067D01*
G01X1477150Y35250D02*
Y36083D01*
X1476400D01*
X1476150Y35833D01*
X1475983Y35542D01*
X1475900Y35125D01*
X1475983Y34708D01*
X1476150Y34417D01*
X1476400Y34167D01*
X1476692Y34000D01*
X1477025Y33917D01*
X1477317D01*
X1477567Y34000D01*
X1477858Y34167D01*
X1478108Y34417D01*
X1478275Y34667D01*
X1478400Y35000D01*
Y35292D01*
X1478317Y35625D01*
X1478150Y35875D01*
G01X1476400Y37183D02*
X1476108Y37433D01*
X1475942Y37767D01*
X1475900Y38142D01*
X1475942Y38475D01*
X1476150Y38808D01*
X1476400Y39017D01*
X1476650Y39058D01*
X1476942Y38975D01*
X1477150Y38683D01*
X1477233Y38392D01*
Y38017D01*
G01Y38392D02*
X1477358Y38642D01*
X1477567Y38850D01*
X1477817Y38933D01*
X1478067Y38850D01*
X1478275Y38642D01*
X1478400Y38267D01*
X1478358Y37892D01*
X1478192Y37517D01*
G01X1475900Y41200D02*
X1478400D01*
X1477900Y40700D01*
G01X1475900D02*
Y41700D01*
G01X1506583Y15900D02*
Y18400D01*
X1505542D01*
X1505208Y18275D01*
X1505000Y18108D01*
X1504917Y17775D01*
X1505000Y17442D01*
X1505250Y17233D01*
X1505542Y17108D01*
X1506583D01*
G01X1505542D02*
X1504917Y15900D01*
G01X1502650D02*
X1502358Y15942D01*
X1502025Y16067D01*
X1501817Y16275D01*
X1501733Y16567D01*
X1501817Y16858D01*
X1502067Y17108D01*
X1502442Y17233D01*
X1502858D01*
X1503108Y17317D01*
X1503317Y17525D01*
X1503400Y17817D01*
X1503275Y18108D01*
X1502983Y18317D01*
X1502650Y18400D01*
X1502317Y18317D01*
X1502025Y18108D01*
X1501900Y17817D01*
X1501983Y17525D01*
X1502192Y17317D01*
X1502442Y17233D01*
X1502858D01*
X1503233Y17108D01*
X1503483Y16858D01*
X1503567Y16567D01*
X1503483Y16275D01*
X1503275Y16067D01*
X1502942Y15942D01*
X1502650Y15900D01*
G01X1500800Y18400D02*
X1500217Y15900D01*
X1499550Y18400D01*
X1498883Y15900D01*
X1498300Y18400D01*
G01X1496450Y15900D02*
Y18400D01*
X1496950Y17900D01*
G01Y15900D02*
X1495950D01*
G01X1494267Y16275D02*
X1494017Y16067D01*
X1493725Y15942D01*
X1493350Y15900D01*
X1492975Y15983D01*
X1492683Y16150D01*
X1492475Y16442D01*
X1492433Y16775D01*
X1492517Y17108D01*
X1492725Y17317D01*
X1493017Y17483D01*
X1493308Y17525D01*
X1493600Y17483D01*
X1493975Y17317D01*
X1493850Y18400D01*
X1492725D01*
G01X1532667Y19700D02*
Y17908D01*
X1532500Y17533D01*
X1532167Y17283D01*
X1531750Y17200D01*
X1531333Y17283D01*
X1531000Y17533D01*
X1530833Y17908D01*
Y19700D01*
G01X1528650Y17200D02*
X1528358Y17242D01*
X1528025Y17367D01*
X1527817Y17575D01*
X1527733Y17867D01*
X1527817Y18158D01*
X1528067Y18408D01*
X1528442Y18533D01*
X1528858D01*
X1529108Y18617D01*
X1529317Y18825D01*
X1529400Y19117D01*
X1529275Y19408D01*
X1528983Y19617D01*
X1528650Y19700D01*
X1528317Y19617D01*
X1528025Y19408D01*
X1527900Y19117D01*
X1527983Y18825D01*
X1528192Y18617D01*
X1528442Y18533D01*
X1528858D01*
X1529233Y18408D01*
X1529483Y18158D01*
X1529567Y17867D01*
X1529483Y17575D01*
X1529275Y17367D01*
X1528942Y17242D01*
X1528650Y17200D01*
G01X1526800Y19700D02*
X1526217Y17200D01*
X1525550Y19700D01*
X1524883Y17200D01*
X1524300Y19700D01*
G01X1522450Y17200D02*
Y19700D01*
X1522950Y19200D01*
G01Y17200D02*
X1521950D01*
G01X1527230Y33690D02*
X1527480Y33815D01*
X1527772Y33898D01*
X1528105D01*
X1528480Y33773D01*
X1528772Y33565D01*
X1528980Y33315D01*
X1529147Y32898D01*
X1529189Y32523D01*
X1529105Y32148D01*
X1528980Y31898D01*
X1528730Y31648D01*
X1528439Y31481D01*
X1528147Y31398D01*
X1527855D01*
X1527564Y31481D01*
X1527314Y31606D01*
X1527105Y31773D01*
G01X1525964Y31898D02*
X1525714Y31606D01*
X1525380Y31440D01*
X1525005Y31398D01*
X1524672Y31440D01*
X1524339Y31648D01*
X1524130Y31898D01*
X1524089Y32148D01*
X1524172Y32440D01*
X1524464Y32648D01*
X1524755Y32731D01*
X1525130D01*
G01X1524755D02*
X1524505Y32856D01*
X1524297Y33065D01*
X1524214Y33315D01*
X1524297Y33565D01*
X1524505Y33773D01*
X1524880Y33898D01*
X1525255Y33856D01*
X1525630Y33690D01*
G01X1522739Y33481D02*
X1522489Y33731D01*
X1522197Y33856D01*
X1521864Y33898D01*
X1521447Y33815D01*
X1521155Y33606D01*
X1521072Y33356D01*
X1521114Y33106D01*
X1521280Y32898D01*
X1522114Y32481D01*
X1522489Y32190D01*
X1522739Y31773D01*
X1522822Y31398D01*
X1521072D01*
G01X1520097Y33898D02*
X1519514Y31398D01*
X1518847Y33898D01*
X1518180Y31398D01*
X1517597Y33898D01*
G01X1516664Y31898D02*
X1516414Y31606D01*
X1516080Y31440D01*
X1515705Y31398D01*
X1515372Y31440D01*
X1515039Y31648D01*
X1514830Y31898D01*
X1514789Y32148D01*
X1514872Y32440D01*
X1515164Y32648D01*
X1515455Y32731D01*
X1515830D01*
G01X1515455D02*
X1515205Y32856D01*
X1514997Y33065D01*
X1514914Y33315D01*
X1514997Y33565D01*
X1515205Y33773D01*
X1515580Y33898D01*
X1515955Y33856D01*
X1516330Y33690D01*
G01X1501492Y-5033D02*
X1501617Y-5283D01*
X1501700Y-5575D01*
Y-5908D01*
X1501575Y-6283D01*
X1501367Y-6575D01*
X1501117Y-6783D01*
X1500700Y-6950D01*
X1500325Y-6992D01*
X1499950Y-6908D01*
X1499700Y-6783D01*
X1499450Y-6533D01*
X1499283Y-6242D01*
X1499200Y-5950D01*
Y-5658D01*
X1499283Y-5367D01*
X1499408Y-5117D01*
X1499575Y-4908D01*
G01X1499200Y-2850D02*
X1499242Y-2558D01*
X1499367Y-2225D01*
X1499575Y-2017D01*
X1499867Y-1933D01*
X1500158Y-2017D01*
X1500408Y-2267D01*
X1500533Y-2642D01*
Y-3058D01*
X1500617Y-3308D01*
X1500825Y-3517D01*
X1501117Y-3600D01*
X1501408Y-3475D01*
X1501617Y-3183D01*
X1501700Y-2850D01*
X1501617Y-2517D01*
X1501408Y-2225D01*
X1501117Y-2100D01*
X1500825Y-2183D01*
X1500617Y-2392D01*
X1500533Y-2642D01*
Y-3058D01*
X1500408Y-3433D01*
X1500158Y-3683D01*
X1499867Y-3767D01*
X1499575Y-3683D01*
X1499367Y-3475D01*
X1499242Y-3142D01*
X1499200Y-2850D01*
G01X1501700Y-1000D02*
X1499200Y-417D01*
X1501700Y250D01*
X1499200Y917D01*
X1501700Y1500D01*
G01X1500242Y2558D02*
X1500533Y2850D01*
X1500700Y3100D01*
X1500783Y3433D01*
X1500700Y3725D01*
X1500533Y3933D01*
X1500283Y4100D01*
X1499992Y4142D01*
X1499742Y4100D01*
X1499492Y3933D01*
X1499283Y3683D01*
X1499200Y3392D01*
X1499283Y3058D01*
X1499533Y2767D01*
X1499908Y2600D01*
X1500325Y2558D01*
X1500867Y2642D01*
X1501158Y2767D01*
X1501450Y2975D01*
X1501658Y3267D01*
X1501700Y3558D01*
X1501617Y3850D01*
X1501408Y4058D01*
G01X1497492Y1967D02*
X1497617Y1717D01*
X1497700Y1425D01*
Y1092D01*
X1497575Y717D01*
X1497367Y425D01*
X1497117Y217D01*
X1496700Y50D01*
X1496325Y8D01*
X1495950Y92D01*
X1495700Y217D01*
X1495450Y467D01*
X1495283Y758D01*
X1495200Y1050D01*
Y1342D01*
X1495283Y1633D01*
X1495408Y1883D01*
X1495575Y2092D01*
G01X1495200Y4150D02*
X1495242Y4442D01*
X1495367Y4775D01*
X1495575Y4983D01*
X1495867Y5067D01*
X1496158Y4983D01*
X1496408Y4733D01*
X1496533Y4358D01*
Y3942D01*
X1496617Y3692D01*
X1496825Y3483D01*
X1497117Y3400D01*
X1497408Y3525D01*
X1497617Y3817D01*
X1497700Y4150D01*
X1497617Y4483D01*
X1497408Y4775D01*
X1497117Y4900D01*
X1496825Y4817D01*
X1496617Y4608D01*
X1496533Y4358D01*
Y3942D01*
X1496408Y3567D01*
X1496158Y3317D01*
X1495867Y3233D01*
X1495575Y3317D01*
X1495367Y3525D01*
X1495242Y3858D01*
X1495200Y4150D01*
G01X1497700Y6000D02*
X1495200Y6583D01*
X1497700Y7250D01*
X1495200Y7917D01*
X1497700Y8500D01*
G01X1495575Y9433D02*
X1495367Y9683D01*
X1495242Y9975D01*
X1495200Y10350D01*
X1495283Y10725D01*
X1495450Y11017D01*
X1495742Y11225D01*
X1496075Y11267D01*
X1496408Y11183D01*
X1496617Y10975D01*
X1496783Y10683D01*
X1496825Y10392D01*
X1496783Y10100D01*
X1496617Y9725D01*
X1497700Y9850D01*
Y10975D01*
G01X1493855Y31899D02*
X1494105Y32024D01*
X1494397Y32107D01*
X1494730D01*
X1495105Y31982D01*
X1495397Y31774D01*
X1495605Y31524D01*
X1495772Y31107D01*
X1495814Y30732D01*
X1495730Y30357D01*
X1495605Y30107D01*
X1495355Y29857D01*
X1495064Y29690D01*
X1494772Y29607D01*
X1494480D01*
X1494189Y29690D01*
X1493939Y29815D01*
X1493730Y29982D01*
G01X1492505Y29607D02*
Y32107D01*
X1491464D01*
X1491130Y31982D01*
X1490922Y31815D01*
X1490839Y31482D01*
X1490922Y31149D01*
X1491172Y30940D01*
X1491464Y30815D01*
X1492505D01*
G01X1491464D02*
X1490839Y29607D01*
G01X1489489Y30107D02*
X1489239Y29815D01*
X1488905Y29649D01*
X1488530Y29607D01*
X1488197Y29649D01*
X1487864Y29857D01*
X1487655Y30107D01*
X1487614Y30357D01*
X1487697Y30649D01*
X1487989Y30857D01*
X1488280Y30940D01*
X1488655D01*
G01X1488280D02*
X1488030Y31065D01*
X1487822Y31274D01*
X1487739Y31524D01*
X1487822Y31774D01*
X1488030Y31982D01*
X1488405Y32107D01*
X1488780Y32065D01*
X1489155Y31899D01*
G01X1486389Y32107D02*
Y30315D01*
X1486222Y29940D01*
X1485889Y29690D01*
X1485472Y29607D01*
X1485055Y29690D01*
X1484722Y29940D01*
X1484555Y30315D01*
Y32107D01*
G01X1482372Y29607D02*
Y32107D01*
X1482872Y31607D01*
G01Y29607D02*
X1481872D01*
G01X1489900Y26000D02*
Y26300D01*
X1478700D01*
Y26000D01*
G01X1489900Y19400D02*
Y19100D01*
X1478700D01*
Y19400D01*
G01X1519567Y19700D02*
Y17908D01*
X1519400Y17533D01*
X1519067Y17283D01*
X1518650Y17200D01*
X1518233Y17283D01*
X1517900Y17533D01*
X1517733Y17908D01*
Y19700D01*
G01X1515550Y17200D02*
X1515258Y17242D01*
X1514925Y17367D01*
X1514717Y17575D01*
X1514633Y17867D01*
X1514717Y18158D01*
X1514967Y18408D01*
X1515342Y18533D01*
X1515758D01*
X1516008Y18617D01*
X1516217Y18825D01*
X1516300Y19117D01*
X1516175Y19408D01*
X1515883Y19617D01*
X1515550Y19700D01*
X1515217Y19617D01*
X1514925Y19408D01*
X1514800Y19117D01*
X1514883Y18825D01*
X1515092Y18617D01*
X1515342Y18533D01*
X1515758D01*
X1516133Y18408D01*
X1516383Y18158D01*
X1516467Y17867D01*
X1516383Y17575D01*
X1516175Y17367D01*
X1515842Y17242D01*
X1515550Y17200D01*
G01X1513700Y19700D02*
X1513117Y17200D01*
X1512450Y19700D01*
X1511783Y17200D01*
X1511200Y19700D01*
G01X1510142Y19283D02*
X1509892Y19533D01*
X1509600Y19658D01*
X1509267Y19700D01*
X1508850Y19617D01*
X1508558Y19408D01*
X1508475Y19158D01*
X1508517Y18908D01*
X1508683Y18700D01*
X1509517Y18283D01*
X1509892Y17992D01*
X1510142Y17575D01*
X1510225Y17200D01*
X1508475D01*
G01X1492970Y-21940D02*
Y-18840D01*
X1493430Y-19460D01*
G01Y-21940D02*
X1492510D01*
G01X1489870D02*
Y-18840D01*
X1490330Y-19460D01*
G01Y-21940D02*
X1489410D01*
G01X1485200Y86567D02*
X1487700D01*
Y87608D01*
X1487575Y87942D01*
X1487408Y88150D01*
X1487075Y88233D01*
X1486742Y88150D01*
X1486533Y87900D01*
X1486408Y87608D01*
Y86567D01*
G01Y87608D02*
X1485200Y88233D01*
G01Y89542D02*
X1487700D01*
X1485200Y91458D01*
X1487700D01*
G01X1485200Y93600D02*
X1485242Y93892D01*
X1485367Y94225D01*
X1485575Y94433D01*
X1485867Y94517D01*
X1486158Y94433D01*
X1486408Y94183D01*
X1486533Y93808D01*
Y93392D01*
X1486617Y93142D01*
X1486825Y92933D01*
X1487117Y92850D01*
X1487408Y92975D01*
X1487617Y93267D01*
X1487700Y93600D01*
X1487617Y93933D01*
X1487408Y94225D01*
X1487117Y94350D01*
X1486825Y94267D01*
X1486617Y94058D01*
X1486533Y93808D01*
Y93392D01*
X1486408Y93017D01*
X1486158Y92767D01*
X1485867Y92683D01*
X1485575Y92767D01*
X1485367Y92975D01*
X1485242Y93308D01*
X1485200Y93600D01*
G01Y95908D02*
X1487700D01*
Y97492D01*
G01X1486492Y96908D02*
Y95908D01*
G01X1485200Y100300D02*
X1487700D01*
X1485908Y98758D01*
Y100842D01*
G01X1485626Y56163D02*
X1488126D01*
Y57204D01*
X1488001Y57538D01*
X1487834Y57746D01*
X1487501Y57829D01*
X1487168Y57746D01*
X1486959Y57496D01*
X1486834Y57204D01*
Y56163D01*
G01Y57204D02*
X1485626Y57829D01*
G01Y59138D02*
X1488126D01*
X1485626Y61054D01*
X1488126D01*
G01X1485626Y63196D02*
X1485668Y63488D01*
X1485793Y63821D01*
X1486001Y64029D01*
X1486293Y64113D01*
X1486584Y64029D01*
X1486834Y63779D01*
X1486959Y63404D01*
Y62988D01*
X1487043Y62738D01*
X1487251Y62529D01*
X1487543Y62446D01*
X1487834Y62571D01*
X1488043Y62863D01*
X1488126Y63196D01*
X1488043Y63529D01*
X1487834Y63821D01*
X1487543Y63946D01*
X1487251Y63863D01*
X1487043Y63654D01*
X1486959Y63404D01*
Y62988D01*
X1486834Y62613D01*
X1486584Y62363D01*
X1486293Y62279D01*
X1486001Y62363D01*
X1485793Y62571D01*
X1485668Y62904D01*
X1485626Y63196D01*
G01Y65504D02*
X1488126D01*
Y67088D01*
G01X1486918Y66504D02*
Y65504D01*
G01X1486126Y68479D02*
X1485834Y68729D01*
X1485668Y69063D01*
X1485626Y69438D01*
X1485668Y69771D01*
X1485876Y70104D01*
X1486126Y70313D01*
X1486376Y70354D01*
X1486668Y70271D01*
X1486876Y69979D01*
X1486959Y69688D01*
Y69313D01*
G01Y69688D02*
X1487084Y69938D01*
X1487293Y70146D01*
X1487543Y70229D01*
X1487793Y70146D01*
X1488001Y69938D01*
X1488126Y69563D01*
X1488084Y69188D01*
X1487918Y68813D01*
G01X1524947Y60231D02*
Y62731D01*
X1523906D01*
X1523572Y62606D01*
X1523364Y62439D01*
X1523281Y62106D01*
X1523364Y61773D01*
X1523614Y61564D01*
X1523906Y61439D01*
X1524947D01*
G01X1523906D02*
X1523281Y60231D01*
G01X1521931Y60731D02*
X1521681Y60439D01*
X1521347Y60273D01*
X1520972Y60231D01*
X1520639Y60273D01*
X1520306Y60481D01*
X1520097Y60731D01*
X1520056Y60981D01*
X1520139Y61273D01*
X1520431Y61481D01*
X1520722Y61564D01*
X1521097D01*
G01X1520722D02*
X1520472Y61689D01*
X1520264Y61898D01*
X1520181Y62148D01*
X1520264Y62398D01*
X1520472Y62606D01*
X1520847Y62731D01*
X1521222Y62689D01*
X1521597Y62523D01*
G01X1518706Y62314D02*
X1518456Y62564D01*
X1518164Y62689D01*
X1517831Y62731D01*
X1517414Y62648D01*
X1517122Y62439D01*
X1517039Y62189D01*
X1517081Y61939D01*
X1517247Y61731D01*
X1518081Y61314D01*
X1518456Y61023D01*
X1518706Y60606D01*
X1518789Y60231D01*
X1517039D01*
G01X1516064Y62731D02*
X1515481Y60231D01*
X1514814Y62731D01*
X1514147Y60231D01*
X1513564Y62731D01*
G01X1512422Y60523D02*
X1512131Y60314D01*
X1511797Y60231D01*
X1511464Y60314D01*
X1511172Y60564D01*
X1510964Y60939D01*
X1510881Y61314D01*
Y61773D01*
X1510964Y62148D01*
X1511172Y62481D01*
X1511422Y62648D01*
X1511714Y62731D01*
X1512047Y62648D01*
X1512297Y62481D01*
X1512464Y62231D01*
X1512547Y61898D01*
X1512464Y61606D01*
X1512256Y61314D01*
X1512006Y61148D01*
X1511714Y61106D01*
X1511381Y61189D01*
X1511131Y61398D01*
X1510881Y61773D01*
G01X1535476Y73862D02*
Y76362D01*
X1534435D01*
X1534101Y76237D01*
X1533893Y76070D01*
X1533810Y75737D01*
X1533893Y75404D01*
X1534143Y75195D01*
X1534435Y75070D01*
X1535476D01*
G01X1534435D02*
X1533810Y73862D01*
G01X1532460Y74362D02*
X1532210Y74070D01*
X1531876Y73904D01*
X1531501Y73862D01*
X1531168Y73904D01*
X1530835Y74112D01*
X1530626Y74362D01*
X1530585Y74612D01*
X1530668Y74904D01*
X1530960Y75112D01*
X1531251Y75195D01*
X1531626D01*
G01X1531251D02*
X1531001Y75320D01*
X1530793Y75529D01*
X1530710Y75779D01*
X1530793Y76029D01*
X1531001Y76237D01*
X1531376Y76362D01*
X1531751Y76320D01*
X1532126Y76154D01*
G01X1529235Y75945D02*
X1528985Y76195D01*
X1528693Y76320D01*
X1528360Y76362D01*
X1527943Y76279D01*
X1527651Y76070D01*
X1527568Y75820D01*
X1527610Y75570D01*
X1527776Y75362D01*
X1528610Y74945D01*
X1528985Y74654D01*
X1529235Y74237D01*
X1529318Y73862D01*
X1527568D01*
G01X1526593Y76362D02*
X1526010Y73862D01*
X1525343Y76362D01*
X1524676Y73862D01*
X1524093Y76362D01*
G01X1522326Y73862D02*
X1522243Y74404D01*
X1522118Y74862D01*
X1521951Y75279D01*
X1521743Y75737D01*
X1521410Y76362D01*
X1523076D01*
G01X1518076Y45099D02*
Y47599D01*
X1517035D01*
X1516701Y47474D01*
X1516493Y47307D01*
X1516410Y46974D01*
X1516493Y46641D01*
X1516743Y46432D01*
X1517035Y46307D01*
X1518076D01*
G01X1517035D02*
X1516410Y45099D01*
G01X1515060Y45599D02*
X1514810Y45307D01*
X1514476Y45141D01*
X1514101Y45099D01*
X1513768Y45141D01*
X1513435Y45349D01*
X1513226Y45599D01*
X1513185Y45849D01*
X1513268Y46141D01*
X1513560Y46349D01*
X1513851Y46432D01*
X1514226D01*
G01X1513851D02*
X1513601Y46557D01*
X1513393Y46766D01*
X1513310Y47016D01*
X1513393Y47266D01*
X1513601Y47474D01*
X1513976Y47599D01*
X1514351Y47557D01*
X1514726Y47391D01*
G01X1511835Y47182D02*
X1511585Y47432D01*
X1511293Y47557D01*
X1510960Y47599D01*
X1510543Y47516D01*
X1510251Y47307D01*
X1510168Y47057D01*
X1510210Y46807D01*
X1510376Y46599D01*
X1511210Y46182D01*
X1511585Y45891D01*
X1511835Y45474D01*
X1511918Y45099D01*
X1510168D01*
G01X1509193Y47599D02*
X1508610Y45099D01*
X1507943Y47599D01*
X1507276Y45099D01*
X1506693Y47599D01*
G01X1504843Y45099D02*
Y47599D01*
X1505343Y47099D01*
G01Y45099D02*
X1504343D01*
G01X1502535Y47182D02*
X1502285Y47432D01*
X1501993Y47557D01*
X1501660Y47599D01*
X1501243Y47516D01*
X1500951Y47307D01*
X1500868Y47057D01*
X1500910Y46807D01*
X1501076Y46599D01*
X1501910Y46182D01*
X1502285Y45891D01*
X1502535Y45474D01*
X1502618Y45099D01*
X1500868D01*
G01X1509733Y95742D02*
X1509983Y95867D01*
X1510275Y95950D01*
X1510608D01*
X1510983Y95825D01*
X1511275Y95617D01*
X1511483Y95367D01*
X1511650Y94950D01*
X1511692Y94575D01*
X1511608Y94200D01*
X1511483Y93950D01*
X1511233Y93700D01*
X1510942Y93533D01*
X1510650Y93450D01*
X1510358D01*
X1510067Y93533D01*
X1509817Y93658D01*
X1509608Y93825D01*
G01X1508342Y95533D02*
X1508092Y95783D01*
X1507800Y95908D01*
X1507467Y95950D01*
X1507050Y95867D01*
X1506758Y95658D01*
X1506675Y95408D01*
X1506717Y95158D01*
X1506883Y94950D01*
X1507717Y94533D01*
X1508092Y94242D01*
X1508342Y93825D01*
X1508425Y93450D01*
X1506675D01*
G01X1504450Y95950D02*
Y93450D01*
G01X1505408Y95950D02*
X1503492D01*
G01X1502142Y95533D02*
X1501892Y95783D01*
X1501600Y95908D01*
X1501267Y95950D01*
X1500850Y95867D01*
X1500558Y95658D01*
X1500475Y95408D01*
X1500517Y95158D01*
X1500683Y94950D01*
X1501517Y94533D01*
X1501892Y94242D01*
X1502142Y93825D01*
X1502225Y93450D01*
X1500475D01*
G01X1499167Y93950D02*
X1498917Y93658D01*
X1498583Y93492D01*
X1498208Y93450D01*
X1497875Y93492D01*
X1497542Y93700D01*
X1497333Y93950D01*
X1497292Y94200D01*
X1497375Y94492D01*
X1497667Y94700D01*
X1497958Y94783D01*
X1498333D01*
G01X1497958D02*
X1497708Y94908D01*
X1497500Y95117D01*
X1497417Y95367D01*
X1497500Y95617D01*
X1497708Y95825D01*
X1498083Y95950D01*
X1498458Y95908D01*
X1498833Y95742D01*
G01X1506983Y73192D02*
X1507233Y73317D01*
X1507525Y73400D01*
X1507858D01*
X1508233Y73275D01*
X1508525Y73067D01*
X1508733Y72817D01*
X1508900Y72400D01*
X1508942Y72025D01*
X1508858Y71650D01*
X1508733Y71400D01*
X1508483Y71150D01*
X1508192Y70983D01*
X1507900Y70900D01*
X1507608D01*
X1507317Y70983D01*
X1507067Y71108D01*
X1506858Y71275D01*
G01X1505592Y72983D02*
X1505342Y73233D01*
X1505050Y73358D01*
X1504717Y73400D01*
X1504300Y73317D01*
X1504008Y73108D01*
X1503925Y72858D01*
X1503967Y72608D01*
X1504133Y72400D01*
X1504967Y71983D01*
X1505342Y71692D01*
X1505592Y71275D01*
X1505675Y70900D01*
X1503925D01*
G01X1501700Y73400D02*
Y70900D01*
G01X1502658Y73400D02*
X1500742D01*
G01X1498600Y70900D02*
Y73400D01*
X1499100Y72900D01*
G01Y70900D02*
X1498100D01*
G01X1496417Y71275D02*
X1496167Y71067D01*
X1495875Y70942D01*
X1495500Y70900D01*
X1495125Y70983D01*
X1494833Y71150D01*
X1494625Y71442D01*
X1494583Y71775D01*
X1494667Y72108D01*
X1494875Y72317D01*
X1495167Y72483D01*
X1495458Y72525D01*
X1495750Y72483D01*
X1496125Y72317D01*
X1496000Y73400D01*
X1494875D01*
G01X1506583Y65386D02*
X1506833Y65511D01*
X1507125Y65594D01*
X1507458D01*
X1507833Y65469D01*
X1508125Y65261D01*
X1508333Y65011D01*
X1508500Y64594D01*
X1508542Y64219D01*
X1508458Y63844D01*
X1508333Y63594D01*
X1508083Y63344D01*
X1507792Y63177D01*
X1507500Y63094D01*
X1507208D01*
X1506917Y63177D01*
X1506667Y63302D01*
X1506458Y63469D01*
G01X1505192Y65177D02*
X1504942Y65427D01*
X1504650Y65552D01*
X1504317Y65594D01*
X1503900Y65511D01*
X1503608Y65302D01*
X1503525Y65052D01*
X1503567Y64802D01*
X1503733Y64594D01*
X1504567Y64177D01*
X1504942Y63886D01*
X1505192Y63469D01*
X1505275Y63094D01*
X1503525D01*
G01X1501300Y65594D02*
Y63094D01*
G01X1502258Y65594D02*
X1500342D01*
G01X1498992Y65177D02*
X1498742Y65427D01*
X1498450Y65552D01*
X1498117Y65594D01*
X1497700Y65511D01*
X1497408Y65302D01*
X1497325Y65052D01*
X1497367Y64802D01*
X1497533Y64594D01*
X1498367Y64177D01*
X1498742Y63886D01*
X1498992Y63469D01*
X1499075Y63094D01*
X1497325D01*
G01X1495100D02*
Y65594D01*
X1495600Y65094D01*
G01Y63094D02*
X1494600D01*
G01X1506583Y53992D02*
X1506833Y54117D01*
X1507125Y54200D01*
X1507458D01*
X1507833Y54075D01*
X1508125Y53867D01*
X1508333Y53617D01*
X1508500Y53200D01*
X1508542Y52825D01*
X1508458Y52450D01*
X1508333Y52200D01*
X1508083Y51950D01*
X1507792Y51783D01*
X1507500Y51700D01*
X1507208D01*
X1506917Y51783D01*
X1506667Y51908D01*
X1506458Y52075D01*
G01X1505192Y53783D02*
X1504942Y54033D01*
X1504650Y54158D01*
X1504317Y54200D01*
X1503900Y54117D01*
X1503608Y53908D01*
X1503525Y53658D01*
X1503567Y53408D01*
X1503733Y53200D01*
X1504567Y52783D01*
X1504942Y52492D01*
X1505192Y52075D01*
X1505275Y51700D01*
X1503525D01*
G01X1501300Y54200D02*
Y51700D01*
G01X1502258Y54200D02*
X1500342D01*
G01X1498992Y53783D02*
X1498742Y54033D01*
X1498450Y54158D01*
X1498117Y54200D01*
X1497700Y54117D01*
X1497408Y53908D01*
X1497325Y53658D01*
X1497367Y53408D01*
X1497533Y53200D01*
X1498367Y52783D01*
X1498742Y52492D01*
X1498992Y52075D01*
X1499075Y51700D01*
X1497325D01*
G01X1495808Y51992D02*
X1495517Y51783D01*
X1495183Y51700D01*
X1494850Y51783D01*
X1494558Y52033D01*
X1494350Y52408D01*
X1494267Y52783D01*
Y53242D01*
X1494350Y53617D01*
X1494558Y53950D01*
X1494808Y54117D01*
X1495100Y54200D01*
X1495433Y54117D01*
X1495683Y53950D01*
X1495850Y53700D01*
X1495933Y53367D01*
X1495850Y53075D01*
X1495642Y52783D01*
X1495392Y52617D01*
X1495100Y52575D01*
X1494767Y52658D01*
X1494517Y52867D01*
X1494267Y53242D01*
G01X1506583Y57886D02*
X1506833Y58011D01*
X1507125Y58094D01*
X1507458D01*
X1507833Y57969D01*
X1508125Y57761D01*
X1508333Y57511D01*
X1508500Y57094D01*
X1508542Y56719D01*
X1508458Y56344D01*
X1508333Y56094D01*
X1508083Y55844D01*
X1507792Y55677D01*
X1507500Y55594D01*
X1507208D01*
X1506917Y55677D01*
X1506667Y55802D01*
X1506458Y55969D01*
G01X1505192Y57677D02*
X1504942Y57927D01*
X1504650Y58052D01*
X1504317Y58094D01*
X1503900Y58011D01*
X1503608Y57802D01*
X1503525Y57552D01*
X1503567Y57302D01*
X1503733Y57094D01*
X1504567Y56677D01*
X1504942Y56386D01*
X1505192Y55969D01*
X1505275Y55594D01*
X1503525D01*
G01X1501300Y58094D02*
Y55594D01*
G01X1502258Y58094D02*
X1500342D01*
G01X1498992Y57677D02*
X1498742Y57927D01*
X1498450Y58052D01*
X1498117Y58094D01*
X1497700Y58011D01*
X1497408Y57802D01*
X1497325Y57552D01*
X1497367Y57302D01*
X1497533Y57094D01*
X1498367Y56677D01*
X1498742Y56386D01*
X1498992Y55969D01*
X1499075Y55594D01*
X1497325D01*
G01X1495892Y56636D02*
X1495600Y56927D01*
X1495350Y57094D01*
X1495017Y57177D01*
X1494725Y57094D01*
X1494517Y56927D01*
X1494350Y56677D01*
X1494308Y56386D01*
X1494350Y56136D01*
X1494517Y55886D01*
X1494767Y55677D01*
X1495058Y55594D01*
X1495392Y55677D01*
X1495683Y55927D01*
X1495850Y56302D01*
X1495892Y56719D01*
X1495808Y57261D01*
X1495683Y57552D01*
X1495475Y57844D01*
X1495183Y58052D01*
X1494892Y58094D01*
X1494600Y58011D01*
X1494392Y57802D01*
G01X1506583Y61786D02*
X1506833Y61911D01*
X1507125Y61994D01*
X1507458D01*
X1507833Y61869D01*
X1508125Y61661D01*
X1508333Y61411D01*
X1508500Y60994D01*
X1508542Y60619D01*
X1508458Y60244D01*
X1508333Y59994D01*
X1508083Y59744D01*
X1507792Y59577D01*
X1507500Y59494D01*
X1507208D01*
X1506917Y59577D01*
X1506667Y59702D01*
X1506458Y59869D01*
G01X1505192Y61577D02*
X1504942Y61827D01*
X1504650Y61952D01*
X1504317Y61994D01*
X1503900Y61911D01*
X1503608Y61702D01*
X1503525Y61452D01*
X1503567Y61202D01*
X1503733Y60994D01*
X1504567Y60577D01*
X1504942Y60286D01*
X1505192Y59869D01*
X1505275Y59494D01*
X1503525D01*
G01X1501300Y61994D02*
Y59494D01*
G01X1502258Y61994D02*
X1500342D01*
G01X1498992Y61577D02*
X1498742Y61827D01*
X1498450Y61952D01*
X1498117Y61994D01*
X1497700Y61911D01*
X1497408Y61702D01*
X1497325Y61452D01*
X1497367Y61202D01*
X1497533Y60994D01*
X1498367Y60577D01*
X1498742Y60286D01*
X1498992Y59869D01*
X1499075Y59494D01*
X1497325D01*
G01X1494600D02*
Y61994D01*
X1496142Y60202D01*
X1494058D01*
G01X1506683Y69486D02*
X1506933Y69611D01*
X1507225Y69694D01*
X1507558D01*
X1507933Y69569D01*
X1508225Y69361D01*
X1508433Y69111D01*
X1508600Y68694D01*
X1508642Y68319D01*
X1508558Y67944D01*
X1508433Y67694D01*
X1508183Y67444D01*
X1507892Y67277D01*
X1507600Y67194D01*
X1507308D01*
X1507017Y67277D01*
X1506767Y67402D01*
X1506558Y67569D01*
G01X1505292Y69277D02*
X1505042Y69527D01*
X1504750Y69652D01*
X1504417Y69694D01*
X1504000Y69611D01*
X1503708Y69402D01*
X1503625Y69152D01*
X1503667Y68902D01*
X1503833Y68694D01*
X1504667Y68277D01*
X1505042Y67986D01*
X1505292Y67569D01*
X1505375Y67194D01*
X1503625D01*
G01X1501400Y69694D02*
Y67194D01*
G01X1502358Y69694D02*
X1500442D01*
G01X1498300Y67194D02*
Y69694D01*
X1498800Y69194D01*
G01Y67194D02*
X1497800D01*
G01X1495992Y68236D02*
X1495700Y68527D01*
X1495450Y68694D01*
X1495117Y68777D01*
X1494825Y68694D01*
X1494617Y68527D01*
X1494450Y68277D01*
X1494408Y67986D01*
X1494450Y67736D01*
X1494617Y67486D01*
X1494867Y67277D01*
X1495158Y67194D01*
X1495492Y67277D01*
X1495783Y67527D01*
X1495950Y67902D01*
X1495992Y68319D01*
X1495908Y68861D01*
X1495783Y69152D01*
X1495575Y69444D01*
X1495283Y69652D01*
X1494992Y69694D01*
X1494700Y69611D01*
X1494492Y69402D01*
G01X1512633Y77192D02*
X1512883Y77317D01*
X1513175Y77400D01*
X1513508D01*
X1513883Y77275D01*
X1514175Y77067D01*
X1514383Y76817D01*
X1514550Y76400D01*
X1514592Y76025D01*
X1514508Y75650D01*
X1514383Y75400D01*
X1514133Y75150D01*
X1513842Y74983D01*
X1513550Y74900D01*
X1513258D01*
X1512967Y74983D01*
X1512717Y75108D01*
X1512508Y75275D01*
G01X1511408Y74900D02*
Y77400D01*
X1509492Y74900D01*
Y77400D01*
G01X1507350Y74900D02*
X1507058Y74942D01*
X1506725Y75067D01*
X1506517Y75275D01*
X1506433Y75567D01*
X1506517Y75858D01*
X1506767Y76108D01*
X1507142Y76233D01*
X1507558D01*
X1507808Y76317D01*
X1508017Y76525D01*
X1508100Y76817D01*
X1507975Y77108D01*
X1507683Y77317D01*
X1507350Y77400D01*
X1507017Y77317D01*
X1506725Y77108D01*
X1506600Y76817D01*
X1506683Y76525D01*
X1506892Y76317D01*
X1507142Y76233D01*
X1507558D01*
X1507933Y76108D01*
X1508183Y75858D01*
X1508267Y75567D01*
X1508183Y75275D01*
X1507975Y75067D01*
X1507642Y74942D01*
X1507350Y74900D01*
G01X1505042D02*
Y77400D01*
X1503458D01*
G01X1504042Y76192D02*
X1505042D01*
G01X1501942Y76983D02*
X1501692Y77233D01*
X1501400Y77358D01*
X1501067Y77400D01*
X1500650Y77317D01*
X1500358Y77108D01*
X1500275Y76858D01*
X1500317Y76608D01*
X1500483Y76400D01*
X1501317Y75983D01*
X1501692Y75692D01*
X1501942Y75275D01*
X1502025Y74900D01*
X1500275D01*
G01X1512633Y80692D02*
X1512883Y80817D01*
X1513175Y80900D01*
X1513508D01*
X1513883Y80775D01*
X1514175Y80567D01*
X1514383Y80317D01*
X1514550Y79900D01*
X1514592Y79525D01*
X1514508Y79150D01*
X1514383Y78900D01*
X1514133Y78650D01*
X1513842Y78483D01*
X1513550Y78400D01*
X1513258D01*
X1512967Y78483D01*
X1512717Y78608D01*
X1512508Y78775D01*
G01X1511408Y78400D02*
Y80900D01*
X1509492Y78400D01*
Y80900D01*
G01X1507350Y78400D02*
X1507058Y78442D01*
X1506725Y78567D01*
X1506517Y78775D01*
X1506433Y79067D01*
X1506517Y79358D01*
X1506767Y79608D01*
X1507142Y79733D01*
X1507558D01*
X1507808Y79817D01*
X1508017Y80025D01*
X1508100Y80317D01*
X1507975Y80608D01*
X1507683Y80817D01*
X1507350Y80900D01*
X1507017Y80817D01*
X1506725Y80608D01*
X1506600Y80317D01*
X1506683Y80025D01*
X1506892Y79817D01*
X1507142Y79733D01*
X1507558D01*
X1507933Y79608D01*
X1508183Y79358D01*
X1508267Y79067D01*
X1508183Y78775D01*
X1507975Y78567D01*
X1507642Y78442D01*
X1507350Y78400D01*
G01X1505042D02*
Y80900D01*
X1503458D01*
G01X1504042Y79692D02*
X1505042D01*
G01X1501150Y78400D02*
Y80900D01*
X1501650Y80400D01*
G01Y78400D02*
X1500650D01*
G01X1528689Y69217D02*
X1528939Y69342D01*
X1529231Y69425D01*
X1529564D01*
X1529939Y69300D01*
X1530231Y69092D01*
X1530439Y68842D01*
X1530606Y68425D01*
X1530648Y68050D01*
X1530564Y67675D01*
X1530439Y67425D01*
X1530189Y67175D01*
X1529898Y67008D01*
X1529606Y66925D01*
X1529314D01*
X1529023Y67008D01*
X1528773Y67133D01*
X1528564Y67300D01*
G01X1527423Y67425D02*
X1527173Y67133D01*
X1526839Y66967D01*
X1526464Y66925D01*
X1526131Y66967D01*
X1525798Y67175D01*
X1525589Y67425D01*
X1525548Y67675D01*
X1525631Y67967D01*
X1525923Y68175D01*
X1526214Y68258D01*
X1526589D01*
G01X1526214D02*
X1525964Y68383D01*
X1525756Y68592D01*
X1525673Y68842D01*
X1525756Y69092D01*
X1525964Y69300D01*
X1526339Y69425D01*
X1526714Y69383D01*
X1527089Y69217D01*
G01X1524198Y69008D02*
X1523948Y69258D01*
X1523656Y69383D01*
X1523323Y69425D01*
X1522906Y69342D01*
X1522614Y69133D01*
X1522531Y68883D01*
X1522573Y68633D01*
X1522739Y68425D01*
X1523573Y68008D01*
X1523948Y67717D01*
X1524198Y67300D01*
X1524281Y66925D01*
X1522531D01*
G01X1521556Y69425D02*
X1520973Y66925D01*
X1520306Y69425D01*
X1519639Y66925D01*
X1519056Y69425D01*
G01X1517998Y69008D02*
X1517748Y69258D01*
X1517456Y69383D01*
X1517123Y69425D01*
X1516706Y69342D01*
X1516414Y69133D01*
X1516331Y68883D01*
X1516373Y68633D01*
X1516539Y68425D01*
X1517373Y68008D01*
X1517748Y67717D01*
X1517998Y67300D01*
X1518081Y66925D01*
X1516331D01*
G01X1528689Y72717D02*
X1528939Y72842D01*
X1529231Y72925D01*
X1529564D01*
X1529939Y72800D01*
X1530231Y72592D01*
X1530439Y72342D01*
X1530606Y71925D01*
X1530648Y71550D01*
X1530564Y71175D01*
X1530439Y70925D01*
X1530189Y70675D01*
X1529898Y70508D01*
X1529606Y70425D01*
X1529314D01*
X1529023Y70508D01*
X1528773Y70633D01*
X1528564Y70800D01*
G01X1527423Y70925D02*
X1527173Y70633D01*
X1526839Y70467D01*
X1526464Y70425D01*
X1526131Y70467D01*
X1525798Y70675D01*
X1525589Y70925D01*
X1525548Y71175D01*
X1525631Y71467D01*
X1525923Y71675D01*
X1526214Y71758D01*
X1526589D01*
G01X1526214D02*
X1525964Y71883D01*
X1525756Y72092D01*
X1525673Y72342D01*
X1525756Y72592D01*
X1525964Y72800D01*
X1526339Y72925D01*
X1526714Y72883D01*
X1527089Y72717D01*
G01X1524198Y72508D02*
X1523948Y72758D01*
X1523656Y72883D01*
X1523323Y72925D01*
X1522906Y72842D01*
X1522614Y72633D01*
X1522531Y72383D01*
X1522573Y72133D01*
X1522739Y71925D01*
X1523573Y71508D01*
X1523948Y71217D01*
X1524198Y70800D01*
X1524281Y70425D01*
X1522531D01*
G01X1521556Y72925D02*
X1520973Y70425D01*
X1520306Y72925D01*
X1519639Y70425D01*
X1519056Y72925D01*
G01X1516706Y70425D02*
Y72925D01*
X1518248Y71133D01*
X1516164D01*
G01X1524951Y58605D02*
Y56813D01*
X1524784Y56438D01*
X1524451Y56188D01*
X1524034Y56105D01*
X1523617Y56188D01*
X1523284Y56438D01*
X1523117Y56813D01*
Y58605D01*
G01X1521851Y56605D02*
X1521601Y56313D01*
X1521267Y56147D01*
X1520892Y56105D01*
X1520559Y56147D01*
X1520226Y56355D01*
X1520017Y56605D01*
X1519976Y56855D01*
X1520059Y57147D01*
X1520351Y57355D01*
X1520642Y57438D01*
X1521017D01*
G01X1520642D02*
X1520392Y57563D01*
X1520184Y57772D01*
X1520101Y58022D01*
X1520184Y58272D01*
X1520392Y58480D01*
X1520767Y58605D01*
X1521142Y58563D01*
X1521517Y58397D01*
G01X1518626Y58188D02*
X1518376Y58438D01*
X1518084Y58563D01*
X1517751Y58605D01*
X1517334Y58522D01*
X1517042Y58313D01*
X1516959Y58063D01*
X1517001Y57813D01*
X1517167Y57605D01*
X1518001Y57188D01*
X1518376Y56897D01*
X1518626Y56480D01*
X1518709Y56105D01*
X1516959D01*
G01X1515984Y58605D02*
X1515401Y56105D01*
X1514734Y58605D01*
X1514067Y56105D01*
X1513484Y58605D01*
G01X1512426Y58188D02*
X1512176Y58438D01*
X1511884Y58563D01*
X1511551Y58605D01*
X1511134Y58522D01*
X1510842Y58313D01*
X1510759Y58063D01*
X1510801Y57813D01*
X1510967Y57605D01*
X1511801Y57188D01*
X1512176Y56897D01*
X1512426Y56480D01*
X1512509Y56105D01*
X1510759D01*
G01X1526823Y45108D02*
Y53108D01*
X1538773D01*
Y45108D01*
X1526823D01*
G01X1479309Y154877D02*
Y154851D01*
G01X1485200Y109967D02*
X1487700D01*
Y111008D01*
X1487575Y111342D01*
X1487408Y111550D01*
X1487075Y111633D01*
X1486742Y111550D01*
X1486533Y111300D01*
X1486408Y111008D01*
Y109967D01*
G01Y111008D02*
X1485200Y111633D01*
G01Y112942D02*
X1487700D01*
X1485200Y114858D01*
X1487700D01*
G01X1485200Y117000D02*
X1485242Y117292D01*
X1485367Y117625D01*
X1485575Y117833D01*
X1485867Y117917D01*
X1486158Y117833D01*
X1486408Y117583D01*
X1486533Y117208D01*
Y116792D01*
X1486617Y116542D01*
X1486825Y116333D01*
X1487117Y116250D01*
X1487408Y116375D01*
X1487617Y116667D01*
X1487700Y117000D01*
X1487617Y117333D01*
X1487408Y117625D01*
X1487117Y117750D01*
X1486825Y117667D01*
X1486617Y117458D01*
X1486533Y117208D01*
Y116792D01*
X1486408Y116417D01*
X1486158Y116167D01*
X1485867Y116083D01*
X1485575Y116167D01*
X1485367Y116375D01*
X1485242Y116708D01*
X1485200Y117000D01*
G01Y119308D02*
X1487700D01*
Y120892D01*
G01X1486492Y120308D02*
Y119308D01*
G01X1485575Y122283D02*
X1485367Y122533D01*
X1485242Y122825D01*
X1485200Y123200D01*
X1485283Y123575D01*
X1485450Y123867D01*
X1485742Y124075D01*
X1486075Y124117D01*
X1486408Y124033D01*
X1486617Y123825D01*
X1486783Y123533D01*
X1486825Y123242D01*
X1486783Y122950D01*
X1486617Y122575D01*
X1487700Y122700D01*
Y123825D01*
G01X1509317Y154902D02*
Y157402D01*
X1508276D01*
X1507942Y157277D01*
X1507734Y157110D01*
X1507651Y156777D01*
X1507734Y156444D01*
X1507984Y156235D01*
X1508276Y156110D01*
X1509317D01*
G01X1508276D02*
X1507651Y154902D01*
G01X1505467D02*
X1505384Y155444D01*
X1505259Y155902D01*
X1505092Y156319D01*
X1504884Y156777D01*
X1504551Y157402D01*
X1506217D01*
G01X1501451Y154902D02*
X1503117D01*
Y157402D01*
X1501451D01*
G01X1502117Y156194D02*
X1503117D01*
G01X1499267Y154902D02*
X1499184Y155444D01*
X1499059Y155902D01*
X1498892Y156319D01*
X1498684Y156777D01*
X1498351Y157402D01*
X1500017D01*
G01X1503167Y137643D02*
X1505667D01*
Y138684D01*
X1505542Y139018D01*
X1505375Y139226D01*
X1505042Y139309D01*
X1504709Y139226D01*
X1504500Y138976D01*
X1504375Y138684D01*
Y137643D01*
G01Y138684D02*
X1503167Y139309D01*
G01Y141493D02*
X1503709Y141576D01*
X1504167Y141701D01*
X1504584Y141868D01*
X1505042Y142076D01*
X1505667Y142409D01*
Y140743D01*
G01X1503167Y145509D02*
Y143843D01*
X1505667D01*
Y145509D01*
G01X1504459Y144843D02*
Y143843D01*
G01X1503167Y147776D02*
X1505667D01*
X1505167Y147276D01*
G01X1503167D02*
Y148276D01*
G01X1505667Y150876D02*
X1505584Y150543D01*
X1505375Y150293D01*
X1505125Y150126D01*
X1504792Y150001D01*
X1504417Y149959D01*
X1504042Y150001D01*
X1503709Y150126D01*
X1503459Y150293D01*
X1503250Y150543D01*
X1503167Y150876D01*
X1503250Y151209D01*
X1503459Y151459D01*
X1503709Y151626D01*
X1504042Y151751D01*
X1504417Y151793D01*
X1504792Y151751D01*
X1505125Y151626D01*
X1505375Y151459D01*
X1505584Y151209D01*
X1505667Y150876D01*
G01X1526571Y131131D02*
Y133631D01*
X1525530D01*
X1525196Y133506D01*
X1524988Y133339D01*
X1524905Y133006D01*
X1524988Y132673D01*
X1525238Y132464D01*
X1525530Y132339D01*
X1526571D01*
G01X1525530D02*
X1524905Y131131D01*
G01X1522721D02*
X1522638Y131673D01*
X1522513Y132131D01*
X1522346Y132548D01*
X1522138Y133006D01*
X1521805Y133631D01*
X1523471D01*
G01X1520788D02*
X1520205Y131131D01*
X1519538Y133631D01*
X1518871Y131131D01*
X1518288Y133631D01*
G01X1517230Y132173D02*
X1516938Y132464D01*
X1516688Y132631D01*
X1516355Y132714D01*
X1516063Y132631D01*
X1515855Y132464D01*
X1515688Y132214D01*
X1515646Y131923D01*
X1515688Y131673D01*
X1515855Y131423D01*
X1516105Y131214D01*
X1516396Y131131D01*
X1516730Y131214D01*
X1517021Y131464D01*
X1517188Y131839D01*
X1517230Y132256D01*
X1517146Y132798D01*
X1517021Y133089D01*
X1516813Y133381D01*
X1516521Y133589D01*
X1516230Y133631D01*
X1515938Y133548D01*
X1515730Y133339D01*
G01X1497667Y139350D02*
X1497709Y139017D01*
X1497875Y138725D01*
X1498125Y138475D01*
X1498417Y138308D01*
X1498750Y138225D01*
X1499084D01*
X1499417Y138308D01*
X1499709Y138475D01*
X1499959Y138725D01*
X1500125Y139017D01*
X1500167Y139350D01*
X1500125Y139683D01*
X1499959Y139975D01*
X1499709Y140225D01*
X1499417Y140392D01*
X1499084Y140475D01*
X1498750D01*
X1498417Y140392D01*
X1498125Y140225D01*
X1497875Y139975D01*
X1497709Y139683D01*
X1497667Y139350D01*
G01X1498334Y139683D02*
X1497667Y140183D01*
G01Y142367D02*
X1498209Y142450D01*
X1498667Y142575D01*
X1499084Y142742D01*
X1499542Y142950D01*
X1500167Y143283D01*
Y141617D01*
G01X1497667Y146383D02*
Y144717D01*
X1500167D01*
Y146383D01*
G01X1498959Y145717D02*
Y144717D01*
G01X1498042Y147733D02*
X1497834Y147983D01*
X1497709Y148275D01*
X1497667Y148650D01*
X1497750Y149025D01*
X1497917Y149317D01*
X1498209Y149525D01*
X1498542Y149567D01*
X1498875Y149483D01*
X1499084Y149275D01*
X1499250Y148983D01*
X1499292Y148692D01*
X1499250Y148400D01*
X1499084Y148025D01*
X1500167Y148150D01*
Y149275D01*
G01X1494667Y140433D02*
X1492875D01*
X1492500Y140600D01*
X1492250Y140933D01*
X1492167Y141350D01*
X1492250Y141767D01*
X1492500Y142100D01*
X1492875Y142267D01*
X1494667D01*
G01X1492167Y144367D02*
X1492709Y144450D01*
X1493167Y144575D01*
X1493584Y144742D01*
X1494042Y144950D01*
X1494667Y145283D01*
Y143617D01*
G01X1492167Y148383D02*
Y146717D01*
X1494667D01*
Y148383D01*
G01X1493459Y147717D02*
Y146717D01*
G01X1494250Y149858D02*
X1494500Y150108D01*
X1494625Y150400D01*
X1494667Y150733D01*
X1494584Y151150D01*
X1494375Y151442D01*
X1494125Y151525D01*
X1493875Y151483D01*
X1493667Y151317D01*
X1493250Y150483D01*
X1492959Y150108D01*
X1492542Y149858D01*
X1492167Y149775D01*
Y151525D01*
G01X1512433Y101892D02*
X1512683Y102017D01*
X1512975Y102100D01*
X1513308D01*
X1513683Y101975D01*
X1513975Y101767D01*
X1514183Y101517D01*
X1514350Y101100D01*
X1514392Y100725D01*
X1514308Y100350D01*
X1514183Y100100D01*
X1513933Y99850D01*
X1513642Y99683D01*
X1513350Y99600D01*
X1513058D01*
X1512767Y99683D01*
X1512517Y99808D01*
X1512308Y99975D01*
G01X1511042Y101683D02*
X1510792Y101933D01*
X1510500Y102058D01*
X1510167Y102100D01*
X1509750Y102017D01*
X1509458Y101808D01*
X1509375Y101558D01*
X1509417Y101308D01*
X1509583Y101100D01*
X1510417Y100683D01*
X1510792Y100392D01*
X1511042Y99975D01*
X1511125Y99600D01*
X1509375D01*
G01X1507150Y102100D02*
Y99600D01*
G01X1508108Y102100D02*
X1506192D01*
G01X1504842Y101683D02*
X1504592Y101933D01*
X1504300Y102058D01*
X1503967Y102100D01*
X1503550Y102017D01*
X1503258Y101808D01*
X1503175Y101558D01*
X1503217Y101308D01*
X1503383Y101100D01*
X1504217Y100683D01*
X1504592Y100392D01*
X1504842Y99975D01*
X1504925Y99600D01*
X1503175D01*
G01X1500950Y102100D02*
X1501283Y102017D01*
X1501533Y101808D01*
X1501700Y101558D01*
X1501825Y101225D01*
X1501867Y100850D01*
X1501825Y100475D01*
X1501700Y100142D01*
X1501533Y99892D01*
X1501283Y99683D01*
X1500950Y99600D01*
X1500617Y99683D01*
X1500367Y99892D01*
X1500200Y100142D01*
X1500075Y100475D01*
X1500033Y100850D01*
X1500075Y101225D01*
X1500200Y101558D01*
X1500367Y101808D01*
X1500617Y102017D01*
X1500950Y102100D01*
G01X1538183Y113792D02*
X1538433Y113917D01*
X1538725Y114000D01*
X1539058D01*
X1539433Y113875D01*
X1539725Y113667D01*
X1539933Y113417D01*
X1540100Y113000D01*
X1540142Y112625D01*
X1540058Y112250D01*
X1539933Y112000D01*
X1539683Y111750D01*
X1539392Y111583D01*
X1539100Y111500D01*
X1538808D01*
X1538517Y111583D01*
X1538267Y111708D01*
X1538058Y111875D01*
G01X1536000Y111500D02*
X1535708Y111542D01*
X1535375Y111667D01*
X1535167Y111875D01*
X1535083Y112167D01*
X1535167Y112458D01*
X1535417Y112708D01*
X1535792Y112833D01*
X1536208D01*
X1536458Y112917D01*
X1536667Y113125D01*
X1536750Y113417D01*
X1536625Y113708D01*
X1536333Y113917D01*
X1536000Y114000D01*
X1535667Y113917D01*
X1535375Y113708D01*
X1535250Y113417D01*
X1535333Y113125D01*
X1535542Y112917D01*
X1535792Y112833D01*
X1536208D01*
X1536583Y112708D01*
X1536833Y112458D01*
X1536917Y112167D01*
X1536833Y111875D01*
X1536625Y111667D01*
X1536292Y111542D01*
X1536000Y111500D01*
G01X1533692D02*
Y114000D01*
X1532108D01*
G01X1532692Y112792D02*
X1533692D01*
G01X1529800Y111500D02*
Y114000D01*
X1530300Y113500D01*
G01Y111500D02*
X1529300D01*
G01X1527492Y112542D02*
X1527200Y112833D01*
X1526950Y113000D01*
X1526617Y113083D01*
X1526325Y113000D01*
X1526117Y112833D01*
X1525950Y112583D01*
X1525908Y112292D01*
X1525950Y112042D01*
X1526117Y111792D01*
X1526367Y111583D01*
X1526658Y111500D01*
X1526992Y111583D01*
X1527283Y111833D01*
X1527450Y112208D01*
X1527492Y112625D01*
X1527408Y113167D01*
X1527283Y113458D01*
X1527075Y113750D01*
X1526783Y113958D01*
X1526492Y114000D01*
X1526200Y113917D01*
X1525992Y113708D01*
G01X1509483Y107042D02*
X1509733Y107167D01*
X1510025Y107250D01*
X1510358D01*
X1510733Y107125D01*
X1511025Y106917D01*
X1511233Y106667D01*
X1511400Y106250D01*
X1511442Y105875D01*
X1511358Y105500D01*
X1511233Y105250D01*
X1510983Y105000D01*
X1510692Y104833D01*
X1510400Y104750D01*
X1510108D01*
X1509817Y104833D01*
X1509567Y104958D01*
X1509358Y105125D01*
G01X1508092Y106833D02*
X1507842Y107083D01*
X1507550Y107208D01*
X1507217Y107250D01*
X1506800Y107167D01*
X1506508Y106958D01*
X1506425Y106708D01*
X1506467Y106458D01*
X1506633Y106250D01*
X1507467Y105833D01*
X1507842Y105542D01*
X1508092Y105125D01*
X1508175Y104750D01*
X1506425D01*
G01X1504200Y107250D02*
Y104750D01*
G01X1505158Y107250D02*
X1503242D01*
G01X1501100Y104750D02*
Y107250D01*
X1501600Y106750D01*
G01Y104750D02*
X1500600D01*
G01X1497500D02*
Y107250D01*
X1499042Y105458D01*
X1496958D01*
G01X1523283Y112692D02*
X1523533Y112817D01*
X1523825Y112900D01*
X1524158D01*
X1524533Y112775D01*
X1524825Y112567D01*
X1525033Y112317D01*
X1525200Y111900D01*
X1525242Y111525D01*
X1525158Y111150D01*
X1525033Y110900D01*
X1524783Y110650D01*
X1524492Y110483D01*
X1524200Y110400D01*
X1523908D01*
X1523617Y110483D01*
X1523367Y110608D01*
X1523158Y110775D01*
G01X1521892Y112483D02*
X1521642Y112733D01*
X1521350Y112858D01*
X1521017Y112900D01*
X1520600Y112817D01*
X1520308Y112608D01*
X1520225Y112358D01*
X1520267Y112108D01*
X1520433Y111900D01*
X1521267Y111483D01*
X1521642Y111192D01*
X1521892Y110775D01*
X1521975Y110400D01*
X1520225D01*
G01X1518000Y112900D02*
Y110400D01*
G01X1518958Y112900D02*
X1517042D01*
G01X1514900Y110400D02*
Y112900D01*
X1515400Y112400D01*
G01Y110400D02*
X1514400D01*
G01X1512717Y110900D02*
X1512467Y110608D01*
X1512133Y110442D01*
X1511758Y110400D01*
X1511425Y110442D01*
X1511092Y110650D01*
X1510883Y110900D01*
X1510842Y111150D01*
X1510925Y111442D01*
X1511217Y111650D01*
X1511508Y111733D01*
X1511883D01*
G01X1511508D02*
X1511258Y111858D01*
X1511050Y112067D01*
X1510967Y112317D01*
X1511050Y112567D01*
X1511258Y112775D01*
X1511633Y112900D01*
X1512008Y112858D01*
X1512383Y112692D01*
G01X1513296Y124523D02*
X1513546Y124648D01*
X1513838Y124731D01*
X1514171D01*
X1514546Y124606D01*
X1514838Y124398D01*
X1515046Y124148D01*
X1515213Y123731D01*
X1515255Y123356D01*
X1515171Y122981D01*
X1515046Y122731D01*
X1514796Y122481D01*
X1514505Y122314D01*
X1514213Y122231D01*
X1513921D01*
X1513630Y122314D01*
X1513380Y122439D01*
X1513171Y122606D01*
G01X1511905Y124314D02*
X1511655Y124564D01*
X1511363Y124689D01*
X1511030Y124731D01*
X1510613Y124648D01*
X1510321Y124439D01*
X1510238Y124189D01*
X1510280Y123939D01*
X1510446Y123731D01*
X1511280Y123314D01*
X1511655Y123023D01*
X1511905Y122606D01*
X1511988Y122231D01*
X1510238D01*
G01X1508013Y124731D02*
Y122231D01*
G01X1508971Y124731D02*
X1507055D01*
G01X1504913Y122231D02*
Y124731D01*
X1505413Y124231D01*
G01Y122231D02*
X1504413D01*
G01X1501813Y124731D02*
X1502146Y124648D01*
X1502396Y124439D01*
X1502563Y124189D01*
X1502688Y123856D01*
X1502730Y123481D01*
X1502688Y123106D01*
X1502563Y122773D01*
X1502396Y122523D01*
X1502146Y122314D01*
X1501813Y122231D01*
X1501480Y122314D01*
X1501230Y122523D01*
X1501063Y122773D01*
X1500938Y123106D01*
X1500896Y123481D01*
X1500938Y123856D01*
X1501063Y124189D01*
X1501230Y124439D01*
X1501480Y124648D01*
X1501813Y124731D01*
G01X1510821Y118495D02*
X1511071Y118620D01*
X1511363Y118703D01*
X1511696D01*
X1512071Y118578D01*
X1512363Y118370D01*
X1512571Y118120D01*
X1512738Y117703D01*
X1512780Y117328D01*
X1512696Y116953D01*
X1512571Y116703D01*
X1512321Y116453D01*
X1512030Y116286D01*
X1511738Y116203D01*
X1511446D01*
X1511155Y116286D01*
X1510905Y116411D01*
X1510696Y116578D01*
G01X1509430Y118286D02*
X1509180Y118536D01*
X1508888Y118661D01*
X1508555Y118703D01*
X1508138Y118620D01*
X1507846Y118411D01*
X1507763Y118161D01*
X1507805Y117911D01*
X1507971Y117703D01*
X1508805Y117286D01*
X1509180Y116995D01*
X1509430Y116578D01*
X1509513Y116203D01*
X1507763D01*
G01X1505538Y118703D02*
Y116203D01*
G01X1506496Y118703D02*
X1504580D01*
G01X1502438Y116203D02*
Y118703D01*
X1502938Y118203D01*
G01Y116203D02*
X1501938D01*
G01X1499338D02*
Y118703D01*
X1499838Y118203D01*
G01Y116203D02*
X1498838D01*
G01X1529812Y153097D02*
X1530062Y153222D01*
X1530354Y153305D01*
X1530687D01*
X1531062Y153180D01*
X1531354Y152972D01*
X1531562Y152722D01*
X1531729Y152305D01*
X1531771Y151930D01*
X1531687Y151555D01*
X1531562Y151305D01*
X1531312Y151055D01*
X1531021Y150888D01*
X1530729Y150805D01*
X1530437D01*
X1530146Y150888D01*
X1529896Y151013D01*
X1529687Y151180D01*
G01X1528421Y152888D02*
X1528171Y153138D01*
X1527879Y153263D01*
X1527546Y153305D01*
X1527129Y153222D01*
X1526837Y153013D01*
X1526754Y152763D01*
X1526796Y152513D01*
X1526962Y152305D01*
X1527796Y151888D01*
X1528171Y151597D01*
X1528421Y151180D01*
X1528504Y150805D01*
X1526754D01*
G01X1524529Y153305D02*
Y150805D01*
G01X1525487Y153305D02*
X1523571D01*
G01X1520929Y150805D02*
Y153305D01*
X1522471Y151513D01*
X1520387D01*
G01X1524808Y146905D02*
X1525058Y147030D01*
X1525350Y147113D01*
X1525683D01*
X1526058Y146988D01*
X1526350Y146780D01*
X1526558Y146530D01*
X1526725Y146113D01*
X1526767Y145738D01*
X1526683Y145363D01*
X1526558Y145113D01*
X1526308Y144863D01*
X1526017Y144696D01*
X1525725Y144613D01*
X1525433D01*
X1525142Y144696D01*
X1524892Y144821D01*
X1524683Y144988D01*
G01X1523417Y146696D02*
X1523167Y146946D01*
X1522875Y147071D01*
X1522542Y147113D01*
X1522125Y147030D01*
X1521833Y146821D01*
X1521750Y146571D01*
X1521792Y146321D01*
X1521958Y146113D01*
X1522792Y145696D01*
X1523167Y145405D01*
X1523417Y144988D01*
X1523500Y144613D01*
X1521750D01*
G01X1519525Y147113D02*
Y144613D01*
G01X1520483Y147113D02*
X1518567D01*
G01X1517342Y144988D02*
X1517092Y144780D01*
X1516800Y144655D01*
X1516425Y144613D01*
X1516050Y144696D01*
X1515758Y144863D01*
X1515550Y145155D01*
X1515508Y145488D01*
X1515592Y145821D01*
X1515800Y146030D01*
X1516092Y146196D01*
X1516383Y146238D01*
X1516675Y146196D01*
X1517050Y146030D01*
X1516925Y147113D01*
X1515800D01*
G01X1517003Y152557D02*
X1517045Y152224D01*
X1517211Y151932D01*
X1517461Y151682D01*
X1517753Y151515D01*
X1518086Y151432D01*
X1518420D01*
X1518753Y151515D01*
X1519045Y151682D01*
X1519295Y151932D01*
X1519461Y152224D01*
X1519503Y152557D01*
X1519461Y152890D01*
X1519295Y153182D01*
X1519045Y153432D01*
X1518753Y153599D01*
X1518420Y153682D01*
X1518086D01*
X1517753Y153599D01*
X1517461Y153432D01*
X1517211Y153182D01*
X1517045Y152890D01*
X1517003Y152557D01*
G01X1517670Y152890D02*
X1517003Y153390D01*
G01Y155574D02*
X1517545Y155657D01*
X1518003Y155782D01*
X1518420Y155949D01*
X1518878Y156157D01*
X1519503Y156490D01*
Y154824D01*
G01X1517003Y159590D02*
Y157924D01*
X1519503D01*
Y159590D01*
G01X1518295Y158924D02*
Y157924D01*
G01X1517003Y162357D02*
X1519503D01*
X1517711Y160815D01*
Y162899D01*
G01X1493544Y180251D02*
X1495765D01*
Y192004D01*
X1488923D01*
Y196043D01*
X1478749D01*
Y205527D01*
X1477044D01*
Y217500D01*
X1480525D01*
Y248741D01*
X1472970D01*
G01X1477044Y216680D02*
Y217500D01*
G01X1518499Y201605D02*
X1520999D01*
Y202646D01*
X1520874Y202980D01*
X1520707Y203188D01*
X1520374Y203271D01*
X1520041Y203188D01*
X1519832Y202938D01*
X1519707Y202646D01*
Y201605D01*
G01Y202646D02*
X1518499Y203271D01*
G01X1518999Y204621D02*
X1518707Y204871D01*
X1518541Y205205D01*
X1518499Y205580D01*
X1518541Y205913D01*
X1518749Y206246D01*
X1518999Y206455D01*
X1519249Y206496D01*
X1519541Y206413D01*
X1519749Y206121D01*
X1519832Y205830D01*
Y205455D01*
G01Y205830D02*
X1519957Y206080D01*
X1520166Y206288D01*
X1520416Y206371D01*
X1520666Y206288D01*
X1520874Y206080D01*
X1520999Y205705D01*
X1520957Y205330D01*
X1520791Y204955D01*
G01X1520999Y207721D02*
X1519207D01*
X1518832Y207888D01*
X1518582Y208221D01*
X1518499Y208638D01*
X1518582Y209055D01*
X1518832Y209388D01*
X1519207Y209555D01*
X1520999D01*
G01X1518499Y211738D02*
X1520999D01*
X1520499Y211238D01*
G01X1518499D02*
Y212238D01*
G01X1513348Y193800D02*
X1515848D01*
Y194841D01*
X1515723Y195175D01*
X1515556Y195383D01*
X1515223Y195466D01*
X1514890Y195383D01*
X1514681Y195133D01*
X1514556Y194841D01*
Y193800D01*
G01Y194841D02*
X1513348Y195466D01*
G01X1513848Y196816D02*
X1513556Y197066D01*
X1513390Y197400D01*
X1513348Y197775D01*
X1513390Y198108D01*
X1513598Y198441D01*
X1513848Y198650D01*
X1514098Y198691D01*
X1514390Y198608D01*
X1514598Y198316D01*
X1514681Y198025D01*
Y197650D01*
G01Y198025D02*
X1514806Y198275D01*
X1515015Y198483D01*
X1515265Y198566D01*
X1515515Y198483D01*
X1515723Y198275D01*
X1515848Y197900D01*
X1515806Y197525D01*
X1515640Y197150D01*
G01X1515848Y200833D02*
X1513348D01*
G01X1515848Y199875D02*
Y201791D01*
G01X1513348Y203933D02*
X1515848D01*
X1515348Y203433D01*
G01X1513348D02*
Y204433D01*
G01X1515431Y206241D02*
X1515681Y206491D01*
X1515806Y206783D01*
X1515848Y207116D01*
X1515765Y207533D01*
X1515556Y207825D01*
X1515306Y207908D01*
X1515056Y207866D01*
X1514848Y207700D01*
X1514431Y206866D01*
X1514140Y206491D01*
X1513723Y206241D01*
X1513348Y206158D01*
Y207908D01*
G01X1509109Y183289D02*
X1511609D01*
Y184330D01*
X1511484Y184664D01*
X1511317Y184872D01*
X1510984Y184955D01*
X1510651Y184872D01*
X1510442Y184622D01*
X1510317Y184330D01*
Y183289D01*
G01Y184330D02*
X1509109Y184955D01*
G01X1509609Y186305D02*
X1509317Y186555D01*
X1509151Y186889D01*
X1509109Y187264D01*
X1509151Y187597D01*
X1509359Y187930D01*
X1509609Y188139D01*
X1509859Y188180D01*
X1510151Y188097D01*
X1510359Y187805D01*
X1510442Y187514D01*
Y187139D01*
G01Y187514D02*
X1510567Y187764D01*
X1510776Y187972D01*
X1511026Y188055D01*
X1511276Y187972D01*
X1511484Y187764D01*
X1511609Y187389D01*
X1511567Y187014D01*
X1511401Y186639D01*
G01X1511609Y190322D02*
X1509109D01*
G01X1511609Y189364D02*
Y191280D01*
G01X1509401Y192714D02*
X1509192Y193005D01*
X1509109Y193339D01*
X1509192Y193672D01*
X1509442Y193964D01*
X1509817Y194172D01*
X1510192Y194255D01*
X1510651D01*
X1511026Y194172D01*
X1511359Y193964D01*
X1511526Y193714D01*
X1511609Y193422D01*
X1511526Y193089D01*
X1511359Y192839D01*
X1511109Y192672D01*
X1510776Y192589D01*
X1510484Y192672D01*
X1510192Y192880D01*
X1510026Y193130D01*
X1509984Y193422D01*
X1510067Y193755D01*
X1510276Y194005D01*
X1510651Y194255D01*
G01X1521850Y163927D02*
X1524350D01*
Y164968D01*
X1524225Y165302D01*
X1524058Y165510D01*
X1523725Y165593D01*
X1523392Y165510D01*
X1523183Y165260D01*
X1523058Y164968D01*
Y163927D01*
G01Y164968D02*
X1521850Y165593D01*
G01Y167777D02*
X1522392Y167860D01*
X1522850Y167985D01*
X1523267Y168152D01*
X1523725Y168360D01*
X1524350Y168693D01*
Y167027D01*
G01X1521850Y171793D02*
Y170127D01*
X1524350D01*
Y171793D01*
G01X1523142Y171127D02*
Y170127D01*
G01X1522142Y173352D02*
X1521933Y173643D01*
X1521850Y173977D01*
X1521933Y174310D01*
X1522183Y174602D01*
X1522558Y174810D01*
X1522933Y174893D01*
X1523392D01*
X1523767Y174810D01*
X1524100Y174602D01*
X1524267Y174352D01*
X1524350Y174060D01*
X1524267Y173727D01*
X1524100Y173477D01*
X1523850Y173310D01*
X1523517Y173227D01*
X1523225Y173310D01*
X1522933Y173518D01*
X1522767Y173768D01*
X1522725Y174060D01*
X1522808Y174393D01*
X1523017Y174643D01*
X1523392Y174893D01*
G01X1507117Y193356D02*
Y195856D01*
X1506076D01*
X1505742Y195731D01*
X1505534Y195564D01*
X1505451Y195231D01*
X1505534Y194898D01*
X1505784Y194689D01*
X1506076Y194564D01*
X1507117D01*
G01X1506076D02*
X1505451Y193356D01*
G01X1504101Y193856D02*
X1503851Y193564D01*
X1503517Y193398D01*
X1503142Y193356D01*
X1502809Y193398D01*
X1502476Y193606D01*
X1502267Y193856D01*
X1502226Y194106D01*
X1502309Y194398D01*
X1502601Y194606D01*
X1502892Y194689D01*
X1503267D01*
G01X1502892D02*
X1502642Y194814D01*
X1502434Y195023D01*
X1502351Y195273D01*
X1502434Y195523D01*
X1502642Y195731D01*
X1503017Y195856D01*
X1503392Y195814D01*
X1503767Y195648D01*
G01X1500084Y195856D02*
Y193356D01*
G01X1501042Y195856D02*
X1499126D01*
G01X1497776Y195439D02*
X1497526Y195689D01*
X1497234Y195814D01*
X1496901Y195856D01*
X1496484Y195773D01*
X1496192Y195564D01*
X1496109Y195314D01*
X1496151Y195064D01*
X1496317Y194856D01*
X1497151Y194439D01*
X1497526Y194148D01*
X1497776Y193731D01*
X1497859Y193356D01*
X1496109D01*
G01X1511541Y158860D02*
Y161360D01*
X1510500D01*
X1510166Y161235D01*
X1509958Y161068D01*
X1509875Y160735D01*
X1509958Y160402D01*
X1510208Y160193D01*
X1510500Y160068D01*
X1511541D01*
G01X1510500D02*
X1509875Y158860D01*
G01X1507691D02*
X1507608Y159402D01*
X1507483Y159860D01*
X1507316Y160277D01*
X1507108Y160735D01*
X1506775Y161360D01*
X1508441D01*
G01X1503675Y158860D02*
X1505341D01*
Y161360D01*
X1503675D01*
G01X1504341Y160152D02*
X1505341D01*
G01X1501408Y158860D02*
Y161360D01*
X1501908Y160860D01*
G01Y158860D02*
X1500908D01*
G01X1498308D02*
Y161360D01*
X1498808Y160860D01*
G01Y158860D02*
X1497808D01*
G01X1537026Y165560D02*
X1537359Y165602D01*
X1537651Y165768D01*
X1537901Y166018D01*
X1538068Y166310D01*
X1538151Y166643D01*
Y166977D01*
X1538068Y167310D01*
X1537901Y167602D01*
X1537651Y167852D01*
X1537359Y168018D01*
X1537026Y168060D01*
X1536693Y168018D01*
X1536401Y167852D01*
X1536151Y167602D01*
X1535984Y167310D01*
X1535901Y166977D01*
Y166643D01*
X1535984Y166310D01*
X1536151Y166018D01*
X1536401Y165768D01*
X1536693Y165602D01*
X1537026Y165560D01*
G01X1536693Y166227D02*
X1536193Y165560D01*
G01X1534718Y167643D02*
X1534468Y167893D01*
X1534176Y168018D01*
X1533843Y168060D01*
X1533426Y167977D01*
X1533134Y167768D01*
X1533051Y167518D01*
X1533093Y167268D01*
X1533259Y167060D01*
X1534093Y166643D01*
X1534468Y166352D01*
X1534718Y165935D01*
X1534801Y165560D01*
X1533051D01*
G01X1531743Y168060D02*
Y166268D01*
X1531576Y165893D01*
X1531243Y165643D01*
X1530826Y165560D01*
X1530409Y165643D01*
X1530076Y165893D01*
X1529909Y166268D01*
Y168060D01*
G01X1527726Y165560D02*
Y168060D01*
X1528226Y167560D01*
G01Y165560D02*
X1527226D01*
G01X1507146Y189117D02*
X1507479Y189159D01*
X1507771Y189325D01*
X1508021Y189575D01*
X1508188Y189867D01*
X1508271Y190200D01*
Y190534D01*
X1508188Y190867D01*
X1508021Y191159D01*
X1507771Y191409D01*
X1507479Y191575D01*
X1507146Y191617D01*
X1506813Y191575D01*
X1506521Y191409D01*
X1506271Y191159D01*
X1506104Y190867D01*
X1506021Y190534D01*
Y190200D01*
X1506104Y189867D01*
X1506271Y189575D01*
X1506521Y189325D01*
X1506813Y189159D01*
X1507146Y189117D01*
G01X1506813Y189784D02*
X1506313Y189117D01*
G01X1504129D02*
X1504046Y189659D01*
X1503921Y190117D01*
X1503754Y190534D01*
X1503546Y190992D01*
X1503213Y191617D01*
X1504879D01*
G01X1500113Y189117D02*
X1501779D01*
Y191617D01*
X1500113D01*
G01X1500779Y190409D02*
X1501779D01*
G01X1498638Y190159D02*
X1498346Y190450D01*
X1498096Y190617D01*
X1497763Y190700D01*
X1497471Y190617D01*
X1497263Y190450D01*
X1497096Y190200D01*
X1497054Y189909D01*
X1497096Y189659D01*
X1497263Y189409D01*
X1497513Y189200D01*
X1497804Y189117D01*
X1498138Y189200D01*
X1498429Y189450D01*
X1498596Y189825D01*
X1498638Y190242D01*
X1498554Y190784D01*
X1498429Y191075D01*
X1498221Y191367D01*
X1497929Y191575D01*
X1497638Y191617D01*
X1497346Y191534D01*
X1497138Y191325D01*
G01X1494517Y220690D02*
Y218898D01*
X1494350Y218523D01*
X1494017Y218273D01*
X1493600Y218190D01*
X1493183Y218273D01*
X1492850Y218523D01*
X1492683Y218898D01*
Y220690D01*
G01X1490500Y218190D02*
X1490208Y218232D01*
X1489875Y218357D01*
X1489667Y218565D01*
X1489583Y218857D01*
X1489667Y219148D01*
X1489917Y219398D01*
X1490292Y219523D01*
X1490708D01*
X1490958Y219607D01*
X1491167Y219815D01*
X1491250Y220107D01*
X1491125Y220398D01*
X1490833Y220607D01*
X1490500Y220690D01*
X1490167Y220607D01*
X1489875Y220398D01*
X1489750Y220107D01*
X1489833Y219815D01*
X1490042Y219607D01*
X1490292Y219523D01*
X1490708D01*
X1491083Y219398D01*
X1491333Y219148D01*
X1491417Y218857D01*
X1491333Y218565D01*
X1491125Y218357D01*
X1490792Y218232D01*
X1490500Y218190D01*
G01X1488192D02*
Y220690D01*
X1486608D01*
G01X1487192Y219482D02*
X1488192D01*
G01X1484300Y218190D02*
Y220690D01*
X1484800Y220190D01*
G01Y218190D02*
X1483800D01*
G01X1496950Y216850D02*
X1493950D01*
Y212850D01*
X1496950D01*
Y216850D01*
G01X1500200D02*
X1490800D01*
Y197150D01*
X1500200D01*
Y216850D01*
G01X1483664Y161312D02*
X1483706Y160979D01*
X1483872Y160687D01*
X1484122Y160437D01*
X1484414Y160270D01*
X1484747Y160187D01*
X1485081D01*
X1485414Y160270D01*
X1485706Y160437D01*
X1485956Y160687D01*
X1486122Y160979D01*
X1486164Y161312D01*
X1486122Y161645D01*
X1485956Y161937D01*
X1485706Y162187D01*
X1485414Y162354D01*
X1485081Y162437D01*
X1484747D01*
X1484414Y162354D01*
X1484122Y162187D01*
X1483872Y161937D01*
X1483706Y161645D01*
X1483664Y161312D01*
G01X1484331Y161645D02*
X1483664Y162145D01*
G01Y164329D02*
X1484206Y164412D01*
X1484664Y164537D01*
X1485081Y164704D01*
X1485539Y164912D01*
X1486164Y165245D01*
Y163579D01*
G01X1483664Y168345D02*
Y166679D01*
X1486164D01*
Y168345D01*
G01X1484956Y167679D02*
Y166679D01*
G01X1483664Y170612D02*
X1483706Y170904D01*
X1483831Y171237D01*
X1484039Y171445D01*
X1484331Y171529D01*
X1484622Y171445D01*
X1484872Y171195D01*
X1484997Y170820D01*
Y170404D01*
X1485081Y170154D01*
X1485289Y169945D01*
X1485581Y169862D01*
X1485872Y169987D01*
X1486081Y170279D01*
X1486164Y170612D01*
X1486081Y170945D01*
X1485872Y171237D01*
X1485581Y171362D01*
X1485289Y171279D01*
X1485081Y171070D01*
X1484997Y170820D01*
Y170404D01*
X1484872Y170029D01*
X1484622Y169779D01*
X1484331Y169695D01*
X1484039Y169779D01*
X1483831Y169987D01*
X1483706Y170320D01*
X1483664Y170612D01*
G01X1493850Y162500D02*
X1490600D01*
Y166000D01*
G01X1493850Y174500D02*
X1490600D01*
Y171000D01*
G01X1496100Y169750D02*
Y167250D01*
G01X1517298Y171578D02*
Y169078D01*
G01X1515048Y176328D02*
X1511798D01*
Y172828D01*
G01X1515048Y164328D02*
X1511798D01*
Y167828D01*
G01X1466500Y174700D02*
Y178700D01*
X1473900D01*
G01X1466400Y268607D02*
X1468023D01*
Y265308D01*
X1484695D01*
G01X1497537Y262800D02*
Y260199D01*
X1500303D01*
Y251899D01*
G01X1486550Y268926D02*
X1497537D01*
Y267800D01*
G01X1497300Y250692D02*
X1486469D01*
Y248741D01*
X1480525D01*
G01X1536083Y235900D02*
Y238400D01*
X1535042D01*
X1534708Y238275D01*
X1534500Y238108D01*
X1534417Y237775D01*
X1534500Y237442D01*
X1534750Y237233D01*
X1535042Y237108D01*
X1536083D01*
G01X1535042D02*
X1534417Y235900D01*
G01X1532942Y237983D02*
X1532692Y238233D01*
X1532400Y238358D01*
X1532067Y238400D01*
X1531650Y238317D01*
X1531358Y238108D01*
X1531275Y237858D01*
X1531317Y237608D01*
X1531483Y237400D01*
X1532317Y236983D01*
X1532692Y236692D01*
X1532942Y236275D01*
X1533025Y235900D01*
X1531275D01*
G01X1529050Y238400D02*
Y235900D01*
G01X1530008Y238400D02*
X1528092D01*
G01X1526742Y237983D02*
X1526492Y238233D01*
X1526200Y238358D01*
X1525867Y238400D01*
X1525450Y238317D01*
X1525158Y238108D01*
X1525075Y237858D01*
X1525117Y237608D01*
X1525283Y237400D01*
X1526117Y236983D01*
X1526492Y236692D01*
X1526742Y236275D01*
X1526825Y235900D01*
X1525075D01*
G01X1513510Y220397D02*
Y222897D01*
X1512469D01*
X1512135Y222772D01*
X1511927Y222605D01*
X1511844Y222272D01*
X1511927Y221939D01*
X1512177Y221730D01*
X1512469Y221605D01*
X1513510D01*
G01X1512469D02*
X1511844Y220397D01*
G01X1509577D02*
Y222897D01*
X1510077Y222397D01*
G01Y220397D02*
X1509077D01*
G01X1507394Y222897D02*
Y221105D01*
X1507227Y220730D01*
X1506894Y220480D01*
X1506477Y220397D01*
X1506060Y220480D01*
X1505727Y220730D01*
X1505560Y221105D01*
Y222897D01*
G01X1504169Y221439D02*
X1503877Y221730D01*
X1503627Y221897D01*
X1503294Y221980D01*
X1503002Y221897D01*
X1502794Y221730D01*
X1502627Y221480D01*
X1502585Y221189D01*
X1502627Y220939D01*
X1502794Y220689D01*
X1503044Y220480D01*
X1503335Y220397D01*
X1503669Y220480D01*
X1503960Y220730D01*
X1504127Y221105D01*
X1504169Y221522D01*
X1504085Y222064D01*
X1503960Y222355D01*
X1503752Y222647D01*
X1503460Y222855D01*
X1503169Y222897D01*
X1502877Y222814D01*
X1502669Y222605D01*
G01X1526633Y243200D02*
Y245700D01*
X1525592D01*
X1525258Y245575D01*
X1525050Y245408D01*
X1524967Y245075D01*
X1525050Y244742D01*
X1525300Y244533D01*
X1525592Y244408D01*
X1526633D01*
G01X1525592D02*
X1524967Y243200D01*
G01X1523492Y245283D02*
X1523242Y245533D01*
X1522950Y245658D01*
X1522617Y245700D01*
X1522200Y245617D01*
X1521908Y245408D01*
X1521825Y245158D01*
X1521867Y244908D01*
X1522033Y244700D01*
X1522867Y244283D01*
X1523242Y243992D01*
X1523492Y243575D01*
X1523575Y243200D01*
X1521825D01*
G01X1520433D02*
Y245700D01*
X1519392D01*
X1519058Y245575D01*
X1518850Y245408D01*
X1518767Y245075D01*
X1518850Y244742D01*
X1519100Y244533D01*
X1519392Y244408D01*
X1520433D01*
G01X1519392D02*
X1518767Y243200D01*
G01X1516500D02*
Y245700D01*
X1517000Y245200D01*
G01Y243200D02*
X1516000D01*
G01X1514192Y245283D02*
X1513942Y245533D01*
X1513650Y245658D01*
X1513317Y245700D01*
X1512900Y245617D01*
X1512608Y245408D01*
X1512525Y245158D01*
X1512567Y244908D01*
X1512733Y244700D01*
X1513567Y244283D01*
X1513942Y243992D01*
X1514192Y243575D01*
X1514275Y243200D01*
X1512525D01*
G01X1533357Y265493D02*
Y267993D01*
X1532316D01*
X1531982Y267868D01*
X1531774Y267701D01*
X1531691Y267368D01*
X1531774Y267035D01*
X1532024Y266826D01*
X1532316Y266701D01*
X1533357D01*
G01X1532316D02*
X1531691Y265493D01*
G01X1530216Y267576D02*
X1529966Y267826D01*
X1529674Y267951D01*
X1529341Y267993D01*
X1528924Y267910D01*
X1528632Y267701D01*
X1528549Y267451D01*
X1528591Y267201D01*
X1528757Y266993D01*
X1529591Y266576D01*
X1529966Y266285D01*
X1530216Y265868D01*
X1530299Y265493D01*
X1528549D01*
G01X1526324Y267993D02*
Y265493D01*
G01X1527282Y267993D02*
X1525366D01*
G01X1524016Y266535D02*
X1523724Y266826D01*
X1523474Y266993D01*
X1523141Y267076D01*
X1522849Y266993D01*
X1522641Y266826D01*
X1522474Y266576D01*
X1522432Y266285D01*
X1522474Y266035D01*
X1522641Y265785D01*
X1522891Y265576D01*
X1523182Y265493D01*
X1523516Y265576D01*
X1523807Y265826D01*
X1523974Y266201D01*
X1524016Y266618D01*
X1523932Y267160D01*
X1523807Y267451D01*
X1523599Y267743D01*
X1523307Y267951D01*
X1523016Y267993D01*
X1522724Y267910D01*
X1522516Y267701D01*
G01X1518479Y276094D02*
Y278594D01*
X1517438D01*
X1517104Y278469D01*
X1516896Y278302D01*
X1516813Y277969D01*
X1516896Y277636D01*
X1517146Y277427D01*
X1517438Y277302D01*
X1518479D01*
G01X1517438D02*
X1516813Y276094D01*
G01X1514629D02*
X1514546Y276636D01*
X1514421Y277094D01*
X1514254Y277511D01*
X1514046Y277969D01*
X1513713Y278594D01*
X1515379D01*
G01X1510613Y276094D02*
X1512279D01*
Y278594D01*
X1510613D01*
G01X1511279Y277386D02*
X1512279D01*
G01X1509138Y278177D02*
X1508888Y278427D01*
X1508596Y278552D01*
X1508263Y278594D01*
X1507846Y278511D01*
X1507554Y278302D01*
X1507471Y278052D01*
X1507513Y277802D01*
X1507679Y277594D01*
X1508513Y277177D01*
X1508888Y276886D01*
X1509138Y276469D01*
X1509221Y276094D01*
X1507471D01*
G01X1505246Y278594D02*
X1505579Y278511D01*
X1505829Y278302D01*
X1505996Y278052D01*
X1506121Y277719D01*
X1506163Y277344D01*
X1506121Y276969D01*
X1505996Y276636D01*
X1505829Y276386D01*
X1505579Y276177D01*
X1505246Y276094D01*
X1504913Y276177D01*
X1504663Y276386D01*
X1504496Y276636D01*
X1504371Y276969D01*
X1504329Y277344D01*
X1504371Y277719D01*
X1504496Y278052D01*
X1504663Y278302D01*
X1504913Y278511D01*
X1505246Y278594D01*
G01X1529757Y261192D02*
Y263692D01*
X1528716D01*
X1528382Y263567D01*
X1528174Y263400D01*
X1528091Y263067D01*
X1528174Y262734D01*
X1528424Y262525D01*
X1528716Y262400D01*
X1529757D01*
G01X1528716D02*
X1528091Y261192D01*
G01X1526616Y263275D02*
X1526366Y263525D01*
X1526074Y263650D01*
X1525741Y263692D01*
X1525324Y263609D01*
X1525032Y263400D01*
X1524949Y263150D01*
X1524991Y262900D01*
X1525157Y262692D01*
X1525991Y262275D01*
X1526366Y261984D01*
X1526616Y261567D01*
X1526699Y261192D01*
X1524949D01*
G01X1522724Y263692D02*
Y261192D01*
G01X1523682Y263692D02*
X1521766D01*
G01X1519624Y261192D02*
X1519332Y261234D01*
X1518999Y261359D01*
X1518791Y261567D01*
X1518707Y261859D01*
X1518791Y262150D01*
X1519041Y262400D01*
X1519416Y262525D01*
X1519832D01*
X1520082Y262609D01*
X1520291Y262817D01*
X1520374Y263109D01*
X1520249Y263400D01*
X1519957Y263609D01*
X1519624Y263692D01*
X1519291Y263609D01*
X1518999Y263400D01*
X1518874Y263109D01*
X1518957Y262817D01*
X1519166Y262609D01*
X1519416Y262525D01*
X1519832D01*
X1520207Y262400D01*
X1520457Y262150D01*
X1520541Y261859D01*
X1520457Y261567D01*
X1520249Y261359D01*
X1519916Y261234D01*
X1519624Y261192D01*
G01X1501746Y248213D02*
Y246421D01*
X1501579Y246046D01*
X1501246Y245796D01*
X1500829Y245713D01*
X1500412Y245796D01*
X1500079Y246046D01*
X1499912Y246421D01*
Y248213D01*
G01X1498521Y247796D02*
X1498271Y248046D01*
X1497979Y248171D01*
X1497646Y248213D01*
X1497229Y248130D01*
X1496937Y247921D01*
X1496854Y247671D01*
X1496896Y247421D01*
X1497062Y247213D01*
X1497896Y246796D01*
X1498271Y246505D01*
X1498521Y246088D01*
X1498604Y245713D01*
X1496854D01*
G01X1494629Y248213D02*
Y245713D01*
G01X1495587Y248213D02*
X1493671D01*
G01X1491529Y245713D02*
Y248213D01*
X1492029Y247713D01*
G01Y245713D02*
X1491029D01*
G01X1500900Y243350D02*
X1491500D01*
Y223650D01*
X1500900D01*
Y243350D01*
G01X1497650D02*
X1494650D01*
Y239350D01*
X1497650D01*
Y243350D01*
G01X1472315Y270880D02*
X1472440Y270630D01*
X1472523Y270338D01*
Y270005D01*
X1472398Y269630D01*
X1472190Y269338D01*
X1471940Y269130D01*
X1471523Y268963D01*
X1471148Y268921D01*
X1470773Y269005D01*
X1470523Y269130D01*
X1470273Y269380D01*
X1470106Y269671D01*
X1470023Y269963D01*
Y270255D01*
X1470106Y270546D01*
X1470231Y270796D01*
X1470398Y271005D01*
G01X1470523Y272146D02*
X1470231Y272396D01*
X1470065Y272730D01*
X1470023Y273105D01*
X1470065Y273438D01*
X1470273Y273771D01*
X1470523Y273980D01*
X1470773Y274021D01*
X1471065Y273938D01*
X1471273Y273646D01*
X1471356Y273355D01*
Y272980D01*
G01Y273355D02*
X1471481Y273605D01*
X1471690Y273813D01*
X1471940Y273896D01*
X1472190Y273813D01*
X1472398Y273605D01*
X1472523Y273230D01*
X1472481Y272855D01*
X1472315Y272480D01*
G01X1470023Y275330D02*
X1472523D01*
Y276330D01*
X1472398Y276663D01*
X1472106Y276913D01*
X1471773Y276996D01*
X1471440Y276913D01*
X1471190Y276705D01*
X1471065Y276330D01*
Y275330D01*
G01X1470398Y278346D02*
X1470190Y278596D01*
X1470065Y278888D01*
X1470023Y279263D01*
X1470106Y279638D01*
X1470273Y279930D01*
X1470565Y280138D01*
X1470898Y280180D01*
X1471231Y280096D01*
X1471440Y279888D01*
X1471606Y279596D01*
X1471648Y279305D01*
X1471606Y279013D01*
X1471440Y278638D01*
X1472523Y278763D01*
Y279888D01*
G01X1470023Y282363D02*
X1472523D01*
X1472023Y281863D01*
G01X1470023D02*
Y282863D01*
G01X1476140Y272966D02*
X1476265Y272716D01*
X1476348Y272424D01*
Y272091D01*
X1476223Y271716D01*
X1476015Y271424D01*
X1475765Y271216D01*
X1475348Y271049D01*
X1474973Y271007D01*
X1474598Y271091D01*
X1474348Y271216D01*
X1474098Y271466D01*
X1473931Y271757D01*
X1473848Y272049D01*
Y272341D01*
X1473931Y272632D01*
X1474056Y272882D01*
X1474223Y273091D01*
G01X1475931Y274357D02*
X1476181Y274607D01*
X1476306Y274899D01*
X1476348Y275232D01*
X1476265Y275649D01*
X1476056Y275941D01*
X1475806Y276024D01*
X1475556Y275982D01*
X1475348Y275816D01*
X1474931Y274982D01*
X1474640Y274607D01*
X1474223Y274357D01*
X1473848Y274274D01*
Y276024D01*
G01Y277416D02*
X1476348D01*
Y278457D01*
X1476223Y278791D01*
X1476056Y278999D01*
X1475723Y279082D01*
X1475390Y278999D01*
X1475181Y278749D01*
X1475056Y278457D01*
Y277416D01*
G01Y278457D02*
X1473848Y279082D01*
G01X1474223Y280432D02*
X1474015Y280682D01*
X1473890Y280974D01*
X1473848Y281349D01*
X1473931Y281724D01*
X1474098Y282016D01*
X1474390Y282224D01*
X1474723Y282266D01*
X1475056Y282182D01*
X1475265Y281974D01*
X1475431Y281682D01*
X1475473Y281391D01*
X1475431Y281099D01*
X1475265Y280724D01*
X1476348Y280849D01*
Y281974D01*
G01X1479857Y279445D02*
X1479982Y279195D01*
X1480065Y278903D01*
Y278570D01*
X1479940Y278195D01*
X1479732Y277903D01*
X1479482Y277695D01*
X1479065Y277528D01*
X1478690Y277486D01*
X1478315Y277570D01*
X1478065Y277695D01*
X1477815Y277945D01*
X1477648Y278236D01*
X1477565Y278528D01*
Y278820D01*
X1477648Y279111D01*
X1477773Y279361D01*
X1477940Y279570D01*
G01X1479648Y280836D02*
X1479898Y281086D01*
X1480023Y281378D01*
X1480065Y281711D01*
X1479982Y282128D01*
X1479773Y282420D01*
X1479523Y282503D01*
X1479273Y282461D01*
X1479065Y282295D01*
X1478648Y281461D01*
X1478357Y281086D01*
X1477940Y280836D01*
X1477565Y280753D01*
Y282503D01*
G01Y283895D02*
X1480065D01*
Y284895D01*
X1479940Y285228D01*
X1479648Y285478D01*
X1479315Y285561D01*
X1478982Y285478D01*
X1478732Y285270D01*
X1478607Y284895D01*
Y283895D01*
G01X1477940Y286911D02*
X1477732Y287161D01*
X1477607Y287453D01*
X1477565Y287828D01*
X1477648Y288203D01*
X1477815Y288495D01*
X1478107Y288703D01*
X1478440Y288745D01*
X1478773Y288661D01*
X1478982Y288453D01*
X1479148Y288161D01*
X1479190Y287870D01*
X1479148Y287578D01*
X1478982Y287203D01*
X1480065Y287328D01*
Y288453D01*
G01X1490166Y280952D02*
X1490291Y280702D01*
X1490374Y280410D01*
Y280077D01*
X1490249Y279702D01*
X1490041Y279410D01*
X1489791Y279202D01*
X1489374Y279035D01*
X1488999Y278993D01*
X1488624Y279077D01*
X1488374Y279202D01*
X1488124Y279452D01*
X1487957Y279743D01*
X1487874Y280035D01*
Y280327D01*
X1487957Y280618D01*
X1488082Y280868D01*
X1488249Y281077D01*
G01X1489957Y282343D02*
X1490207Y282593D01*
X1490332Y282885D01*
X1490374Y283218D01*
X1490291Y283635D01*
X1490082Y283927D01*
X1489832Y284010D01*
X1489582Y283968D01*
X1489374Y283802D01*
X1488957Y282968D01*
X1488666Y282593D01*
X1488249Y282343D01*
X1487874Y282260D01*
Y284010D01*
G01Y285402D02*
X1490374D01*
Y286402D01*
X1490249Y286735D01*
X1489957Y286985D01*
X1489624Y287068D01*
X1489291Y286985D01*
X1489041Y286777D01*
X1488916Y286402D01*
Y285402D01*
G01X1487874Y289335D02*
X1487916Y289627D01*
X1488041Y289960D01*
X1488249Y290168D01*
X1488541Y290252D01*
X1488832Y290168D01*
X1489082Y289918D01*
X1489207Y289543D01*
Y289127D01*
X1489291Y288877D01*
X1489499Y288668D01*
X1489791Y288585D01*
X1490082Y288710D01*
X1490291Y289002D01*
X1490374Y289335D01*
X1490291Y289668D01*
X1490082Y289960D01*
X1489791Y290085D01*
X1489499Y290002D01*
X1489291Y289793D01*
X1489207Y289543D01*
Y289127D01*
X1489082Y288752D01*
X1488832Y288502D01*
X1488541Y288418D01*
X1488249Y288502D01*
X1488041Y288710D01*
X1487916Y289043D01*
X1487874Y289335D01*
G01X1498075Y274391D02*
X1498325Y274516D01*
X1498617Y274599D01*
X1498950D01*
X1499325Y274474D01*
X1499617Y274266D01*
X1499825Y274016D01*
X1499992Y273599D01*
X1500034Y273224D01*
X1499950Y272849D01*
X1499825Y272599D01*
X1499575Y272349D01*
X1499284Y272182D01*
X1498992Y272099D01*
X1498700D01*
X1498409Y272182D01*
X1498159Y272307D01*
X1497950Y272474D01*
G01X1496684Y274182D02*
X1496434Y274432D01*
X1496142Y274557D01*
X1495809Y274599D01*
X1495392Y274516D01*
X1495100Y274307D01*
X1495017Y274057D01*
X1495059Y273807D01*
X1495225Y273599D01*
X1496059Y273182D01*
X1496434Y272891D01*
X1496684Y272474D01*
X1496767Y272099D01*
X1495017D01*
G01X1493625D02*
Y274599D01*
X1492625D01*
X1492292Y274474D01*
X1492042Y274182D01*
X1491959Y273849D01*
X1492042Y273516D01*
X1492250Y273266D01*
X1492625Y273141D01*
X1493625D01*
G01X1490609Y272599D02*
X1490359Y272307D01*
X1490025Y272141D01*
X1489650Y272099D01*
X1489317Y272141D01*
X1488984Y272349D01*
X1488775Y272599D01*
X1488734Y272849D01*
X1488817Y273141D01*
X1489109Y273349D01*
X1489400Y273432D01*
X1489775D01*
G01X1489400D02*
X1489150Y273557D01*
X1488942Y273766D01*
X1488859Y274016D01*
X1488942Y274266D01*
X1489150Y274474D01*
X1489525Y274599D01*
X1489900Y274557D01*
X1490275Y274391D01*
G01X1510167Y256350D02*
X1510209Y256017D01*
X1510375Y255725D01*
X1510625Y255475D01*
X1510917Y255308D01*
X1511250Y255225D01*
X1511584D01*
X1511917Y255308D01*
X1512209Y255475D01*
X1512459Y255725D01*
X1512625Y256017D01*
X1512667Y256350D01*
X1512625Y256683D01*
X1512459Y256975D01*
X1512209Y257225D01*
X1511917Y257392D01*
X1511584Y257475D01*
X1511250D01*
X1510917Y257392D01*
X1510625Y257225D01*
X1510375Y256975D01*
X1510209Y256683D01*
X1510167Y256350D01*
G01X1510834Y256683D02*
X1510167Y257183D01*
G01Y259450D02*
X1510209Y259742D01*
X1510334Y260075D01*
X1510542Y260283D01*
X1510834Y260367D01*
X1511125Y260283D01*
X1511375Y260033D01*
X1511500Y259658D01*
Y259242D01*
X1511584Y258992D01*
X1511792Y258783D01*
X1512084Y258700D01*
X1512375Y258825D01*
X1512584Y259117D01*
X1512667Y259450D01*
X1512584Y259783D01*
X1512375Y260075D01*
X1512084Y260200D01*
X1511792Y260117D01*
X1511584Y259908D01*
X1511500Y259658D01*
Y259242D01*
X1511375Y258867D01*
X1511125Y258617D01*
X1510834Y258533D01*
X1510542Y258617D01*
X1510334Y258825D01*
X1510209Y259158D01*
X1510167Y259450D01*
G01Y261758D02*
X1512667D01*
Y263342D01*
G01X1511459Y262758D02*
Y261758D01*
G01X1510167Y265650D02*
X1512667D01*
X1512167Y265150D01*
G01X1510167D02*
Y266150D01*
G01X1521900Y255700D02*
X1524400D01*
G01X1517150Y253450D02*
Y250200D01*
X1520650D01*
G01X1529150Y253450D02*
Y250200D01*
X1525650D01*
G01X1472100Y239800D02*
X1476100D01*
Y232400D01*
G01X1485442Y341273D02*
Y342398D01*
X1490951D01*
Y348915D01*
X1494713D01*
G01X1485351Y337718D02*
X1485323D01*
Y320273D01*
X1492550D01*
Y317600D01*
X1507900D01*
Y323600D01*
X1509700D01*
Y330800D01*
X1532700D01*
Y339000D01*
X1532000D01*
G01X1526100Y298467D02*
X1528600D01*
Y299508D01*
X1528475Y299842D01*
X1528308Y300050D01*
X1527975Y300133D01*
X1527642Y300050D01*
X1527433Y299800D01*
X1527308Y299508D01*
Y298467D01*
G01Y299508D02*
X1526100Y300133D01*
G01X1526600Y301483D02*
X1526308Y301733D01*
X1526142Y302067D01*
X1526100Y302442D01*
X1526142Y302775D01*
X1526350Y303108D01*
X1526600Y303317D01*
X1526850Y303358D01*
X1527142Y303275D01*
X1527350Y302983D01*
X1527433Y302692D01*
Y302317D01*
G01Y302692D02*
X1527558Y302942D01*
X1527767Y303150D01*
X1528017Y303233D01*
X1528267Y303150D01*
X1528475Y302942D01*
X1528600Y302567D01*
X1528558Y302192D01*
X1528392Y301817D01*
G01X1526100Y304667D02*
X1528600D01*
Y305667D01*
X1528475Y306000D01*
X1528183Y306250D01*
X1527850Y306333D01*
X1527517Y306250D01*
X1527267Y306042D01*
X1527142Y305667D01*
Y304667D01*
G01Y307808D02*
X1527433Y308100D01*
X1527600Y308350D01*
X1527683Y308683D01*
X1527600Y308975D01*
X1527433Y309183D01*
X1527183Y309350D01*
X1526892Y309392D01*
X1526642Y309350D01*
X1526392Y309183D01*
X1526183Y308933D01*
X1526100Y308642D01*
X1526183Y308308D01*
X1526433Y308017D01*
X1526808Y307850D01*
X1527225Y307808D01*
X1527767Y307892D01*
X1528058Y308017D01*
X1528350Y308225D01*
X1528558Y308517D01*
X1528600Y308808D01*
X1528517Y309100D01*
X1528308Y309308D01*
G01X1526600Y310783D02*
X1526308Y311033D01*
X1526142Y311367D01*
X1526100Y311742D01*
X1526142Y312075D01*
X1526350Y312408D01*
X1526600Y312617D01*
X1526850Y312658D01*
X1527142Y312575D01*
X1527350Y312283D01*
X1527433Y311992D01*
Y311617D01*
G01Y311992D02*
X1527558Y312242D01*
X1527767Y312450D01*
X1528017Y312533D01*
X1528267Y312450D01*
X1528475Y312242D01*
X1528600Y311867D01*
X1528558Y311492D01*
X1528392Y311117D01*
G01X1499100Y294367D02*
X1501600D01*
Y295408D01*
X1501475Y295742D01*
X1501308Y295950D01*
X1500975Y296033D01*
X1500642Y295950D01*
X1500433Y295700D01*
X1500308Y295408D01*
Y294367D01*
G01Y295408D02*
X1499100Y296033D01*
G01X1499392Y297592D02*
X1499183Y297883D01*
X1499100Y298217D01*
X1499183Y298550D01*
X1499433Y298842D01*
X1499808Y299050D01*
X1500183Y299133D01*
X1500642D01*
X1501017Y299050D01*
X1501350Y298842D01*
X1501517Y298592D01*
X1501600Y298300D01*
X1501517Y297967D01*
X1501350Y297717D01*
X1501100Y297550D01*
X1500767Y297467D01*
X1500475Y297550D01*
X1500183Y297758D01*
X1500017Y298008D01*
X1499975Y298300D01*
X1500058Y298633D01*
X1500267Y298883D01*
X1500642Y299133D01*
G01X1499100Y300608D02*
X1501600D01*
Y302192D01*
G01X1500392Y301608D02*
Y300608D01*
G01X1499475Y303583D02*
X1499267Y303833D01*
X1499142Y304125D01*
X1499100Y304500D01*
X1499183Y304875D01*
X1499350Y305167D01*
X1499642Y305375D01*
X1499975Y305417D01*
X1500308Y305333D01*
X1500517Y305125D01*
X1500683Y304833D01*
X1500725Y304542D01*
X1500683Y304250D01*
X1500517Y303875D01*
X1501600Y304000D01*
Y305125D01*
G01X1499475Y306683D02*
X1499267Y306933D01*
X1499142Y307225D01*
X1499100Y307600D01*
X1499183Y307975D01*
X1499350Y308267D01*
X1499642Y308475D01*
X1499975Y308517D01*
X1500308Y308433D01*
X1500517Y308225D01*
X1500683Y307933D01*
X1500725Y307642D01*
X1500683Y307350D01*
X1500517Y306975D01*
X1501600Y307100D01*
Y308225D01*
G01X1516033Y313400D02*
Y315900D01*
X1514992D01*
X1514658Y315775D01*
X1514450Y315608D01*
X1514367Y315275D01*
X1514450Y314942D01*
X1514700Y314733D01*
X1514992Y314608D01*
X1516033D01*
G01X1514992D02*
X1514367Y313400D01*
G01X1512183D02*
X1512100Y313942D01*
X1511975Y314400D01*
X1511808Y314817D01*
X1511600Y315275D01*
X1511267Y315900D01*
X1512933D01*
G01X1509917Y313400D02*
Y315900D01*
X1509083D01*
X1508750Y315775D01*
X1508500Y315608D01*
X1508292Y315358D01*
X1508125Y315067D01*
X1508083Y314650D01*
X1508125Y314233D01*
X1508292Y313942D01*
X1508500Y313692D01*
X1508750Y313525D01*
X1509083Y313400D01*
X1509917D01*
G01X1505900D02*
Y315900D01*
X1506400Y315400D01*
G01Y313400D02*
X1505400D01*
G01X1503717Y313775D02*
X1503467Y313567D01*
X1503175Y313442D01*
X1502800Y313400D01*
X1502425Y313483D01*
X1502133Y313650D01*
X1501925Y313942D01*
X1501883Y314275D01*
X1501967Y314608D01*
X1502175Y314817D01*
X1502467Y314983D01*
X1502758Y315025D01*
X1503050Y314983D01*
X1503425Y314817D01*
X1503300Y315900D01*
X1502175D01*
G01X1514802Y289394D02*
Y291894D01*
X1513761D01*
X1513427Y291769D01*
X1513219Y291602D01*
X1513136Y291269D01*
X1513219Y290936D01*
X1513469Y290727D01*
X1513761Y290602D01*
X1514802D01*
G01X1513761D02*
X1513136Y289394D01*
G01X1510952D02*
X1510869Y289936D01*
X1510744Y290394D01*
X1510577Y290811D01*
X1510369Y291269D01*
X1510036Y291894D01*
X1511702D01*
G01X1506936Y289394D02*
X1508602D01*
Y291894D01*
X1506936D01*
G01X1507602Y290686D02*
X1508602D01*
G01X1504669Y289394D02*
Y291894D01*
X1505169Y291394D01*
G01Y289394D02*
X1504169D01*
G01X1502277Y289686D02*
X1501986Y289477D01*
X1501652Y289394D01*
X1501319Y289477D01*
X1501027Y289727D01*
X1500819Y290102D01*
X1500736Y290477D01*
Y290936D01*
X1500819Y291311D01*
X1501027Y291644D01*
X1501277Y291811D01*
X1501569Y291894D01*
X1501902Y291811D01*
X1502152Y291644D01*
X1502319Y291394D01*
X1502402Y291061D01*
X1502319Y290769D01*
X1502111Y290477D01*
X1501861Y290311D01*
X1501569Y290269D01*
X1501236Y290352D01*
X1500986Y290561D01*
X1500736Y290936D01*
G01X1521192Y307817D02*
X1521317Y307567D01*
X1521400Y307275D01*
Y306942D01*
X1521275Y306567D01*
X1521067Y306275D01*
X1520817Y306067D01*
X1520400Y305900D01*
X1520025Y305858D01*
X1519650Y305942D01*
X1519400Y306067D01*
X1519150Y306317D01*
X1518983Y306608D01*
X1518900Y306900D01*
Y307192D01*
X1518983Y307483D01*
X1519108Y307733D01*
X1519275Y307942D01*
G01X1518900Y310000D02*
X1521400D01*
X1520900Y309500D01*
G01X1518900D02*
Y310500D01*
G01Y313600D02*
X1521400D01*
X1519608Y312058D01*
Y314142D01*
G01X1521400Y314950D02*
X1518900Y315533D01*
X1521400Y316200D01*
X1518900Y316867D01*
X1521400Y317450D01*
G01X1518900Y319300D02*
X1521400D01*
X1520900Y318800D01*
G01X1518900D02*
Y319800D01*
G01X1487364Y304542D02*
X1487489Y304292D01*
X1487572Y304000D01*
Y303667D01*
X1487447Y303292D01*
X1487239Y303000D01*
X1486989Y302792D01*
X1486572Y302625D01*
X1486197Y302583D01*
X1485822Y302667D01*
X1485572Y302792D01*
X1485322Y303042D01*
X1485155Y303333D01*
X1485072Y303625D01*
Y303917D01*
X1485155Y304208D01*
X1485280Y304458D01*
X1485447Y304667D01*
G01X1487155Y305933D02*
X1487405Y306183D01*
X1487530Y306475D01*
X1487572Y306808D01*
X1487489Y307225D01*
X1487280Y307517D01*
X1487030Y307600D01*
X1486780Y307558D01*
X1486572Y307392D01*
X1486155Y306558D01*
X1485864Y306183D01*
X1485447Y305933D01*
X1485072Y305850D01*
Y307600D01*
G01Y308992D02*
X1487572D01*
Y309992D01*
X1487447Y310325D01*
X1487155Y310575D01*
X1486822Y310658D01*
X1486489Y310575D01*
X1486239Y310367D01*
X1486114Y309992D01*
Y308992D01*
G01X1487155Y312133D02*
X1487405Y312383D01*
X1487530Y312675D01*
X1487572Y313008D01*
X1487489Y313425D01*
X1487280Y313717D01*
X1487030Y313800D01*
X1486780Y313758D01*
X1486572Y313592D01*
X1486155Y312758D01*
X1485864Y312383D01*
X1485447Y312133D01*
X1485072Y312050D01*
Y313800D01*
G01X1476369Y304433D02*
X1476494Y304183D01*
X1476577Y303891D01*
Y303558D01*
X1476452Y303183D01*
X1476244Y302891D01*
X1475994Y302683D01*
X1475577Y302516D01*
X1475202Y302474D01*
X1474827Y302558D01*
X1474577Y302683D01*
X1474327Y302933D01*
X1474160Y303224D01*
X1474077Y303516D01*
Y303808D01*
X1474160Y304099D01*
X1474285Y304349D01*
X1474452Y304558D01*
G01X1474577Y305699D02*
X1474285Y305949D01*
X1474119Y306283D01*
X1474077Y306658D01*
X1474119Y306991D01*
X1474327Y307324D01*
X1474577Y307533D01*
X1474827Y307574D01*
X1475119Y307491D01*
X1475327Y307199D01*
X1475410Y306908D01*
Y306533D01*
G01Y306908D02*
X1475535Y307158D01*
X1475744Y307366D01*
X1475994Y307449D01*
X1476244Y307366D01*
X1476452Y307158D01*
X1476577Y306783D01*
X1476535Y306408D01*
X1476369Y306033D01*
G01X1474077Y308883D02*
X1476577D01*
Y309924D01*
X1476452Y310258D01*
X1476285Y310466D01*
X1475952Y310549D01*
X1475619Y310466D01*
X1475410Y310216D01*
X1475285Y309924D01*
Y308883D01*
G01Y309924D02*
X1474077Y310549D01*
G01Y312816D02*
X1476577D01*
X1476077Y312316D01*
G01X1474077D02*
Y313316D01*
G01X1472860Y301360D02*
X1472985Y301110D01*
X1473068Y300818D01*
Y300485D01*
X1472943Y300110D01*
X1472735Y299818D01*
X1472485Y299610D01*
X1472068Y299443D01*
X1471693Y299401D01*
X1471318Y299485D01*
X1471068Y299610D01*
X1470818Y299860D01*
X1470651Y300151D01*
X1470568Y300443D01*
Y300735D01*
X1470651Y301026D01*
X1470776Y301276D01*
X1470943Y301485D01*
G01X1471068Y302626D02*
X1470776Y302876D01*
X1470610Y303210D01*
X1470568Y303585D01*
X1470610Y303918D01*
X1470818Y304251D01*
X1471068Y304460D01*
X1471318Y304501D01*
X1471610Y304418D01*
X1471818Y304126D01*
X1471901Y303835D01*
Y303460D01*
G01Y303835D02*
X1472026Y304085D01*
X1472235Y304293D01*
X1472485Y304376D01*
X1472735Y304293D01*
X1472943Y304085D01*
X1473068Y303710D01*
X1473026Y303335D01*
X1472860Y302960D01*
G01X1470568Y305810D02*
X1473068D01*
Y306851D01*
X1472943Y307185D01*
X1472776Y307393D01*
X1472443Y307476D01*
X1472110Y307393D01*
X1471901Y307143D01*
X1471776Y306851D01*
Y305810D01*
G01Y306851D02*
X1470568Y307476D01*
G01X1471068Y308826D02*
X1470776Y309076D01*
X1470610Y309410D01*
X1470568Y309785D01*
X1470610Y310118D01*
X1470818Y310451D01*
X1471068Y310660D01*
X1471318Y310701D01*
X1471610Y310618D01*
X1471818Y310326D01*
X1471901Y310035D01*
Y309660D01*
G01Y310035D02*
X1472026Y310285D01*
X1472235Y310493D01*
X1472485Y310576D01*
X1472735Y310493D01*
X1472943Y310285D01*
X1473068Y309910D01*
X1473026Y309535D01*
X1472860Y309160D01*
G01X1486387Y282482D02*
X1486512Y282232D01*
X1486595Y281940D01*
Y281607D01*
X1486470Y281232D01*
X1486262Y280940D01*
X1486012Y280732D01*
X1485595Y280565D01*
X1485220Y280523D01*
X1484845Y280607D01*
X1484595Y280732D01*
X1484345Y280982D01*
X1484178Y281273D01*
X1484095Y281565D01*
Y281857D01*
X1484178Y282148D01*
X1484303Y282398D01*
X1484470Y282607D01*
G01X1486178Y283873D02*
X1486428Y284123D01*
X1486553Y284415D01*
X1486595Y284748D01*
X1486512Y285165D01*
X1486303Y285457D01*
X1486053Y285540D01*
X1485803Y285498D01*
X1485595Y285332D01*
X1485178Y284498D01*
X1484887Y284123D01*
X1484470Y283873D01*
X1484095Y283790D01*
Y285540D01*
G01Y286932D02*
X1486595D01*
Y287932D01*
X1486470Y288265D01*
X1486178Y288515D01*
X1485845Y288598D01*
X1485512Y288515D01*
X1485262Y288307D01*
X1485137Y287932D01*
Y286932D01*
G01Y290073D02*
X1485428Y290365D01*
X1485595Y290615D01*
X1485678Y290948D01*
X1485595Y291240D01*
X1485428Y291448D01*
X1485178Y291615D01*
X1484887Y291657D01*
X1484637Y291615D01*
X1484387Y291448D01*
X1484178Y291198D01*
X1484095Y290907D01*
X1484178Y290573D01*
X1484428Y290282D01*
X1484803Y290115D01*
X1485220Y290073D01*
X1485762Y290157D01*
X1486053Y290282D01*
X1486345Y290490D01*
X1486553Y290782D01*
X1486595Y291073D01*
X1486512Y291365D01*
X1486303Y291573D01*
G01X1492459Y304419D02*
X1492584Y304169D01*
X1492667Y303877D01*
Y303544D01*
X1492542Y303169D01*
X1492334Y302877D01*
X1492084Y302669D01*
X1491667Y302502D01*
X1491292Y302460D01*
X1490917Y302544D01*
X1490667Y302669D01*
X1490417Y302919D01*
X1490250Y303210D01*
X1490167Y303502D01*
Y303794D01*
X1490250Y304085D01*
X1490375Y304335D01*
X1490542Y304544D01*
G01X1490667Y305685D02*
X1490375Y305935D01*
X1490209Y306269D01*
X1490167Y306644D01*
X1490209Y306977D01*
X1490417Y307310D01*
X1490667Y307519D01*
X1490917Y307560D01*
X1491209Y307477D01*
X1491417Y307185D01*
X1491500Y306894D01*
Y306519D01*
G01Y306894D02*
X1491625Y307144D01*
X1491834Y307352D01*
X1492084Y307435D01*
X1492334Y307352D01*
X1492542Y307144D01*
X1492667Y306769D01*
X1492625Y306394D01*
X1492459Y306019D01*
G01X1490167Y308869D02*
X1492667D01*
Y309869D01*
X1492542Y310202D01*
X1492250Y310452D01*
X1491917Y310535D01*
X1491584Y310452D01*
X1491334Y310244D01*
X1491209Y309869D01*
Y308869D01*
G01X1490542Y311885D02*
X1490334Y312135D01*
X1490209Y312427D01*
X1490167Y312802D01*
X1490250Y313177D01*
X1490417Y313469D01*
X1490709Y313677D01*
X1491042Y313719D01*
X1491375Y313635D01*
X1491584Y313427D01*
X1491750Y313135D01*
X1491792Y312844D01*
X1491750Y312552D01*
X1491584Y312177D01*
X1492667Y312302D01*
Y313427D01*
G01X1492250Y315110D02*
X1492500Y315360D01*
X1492625Y315652D01*
X1492667Y315985D01*
X1492584Y316402D01*
X1492375Y316694D01*
X1492125Y316777D01*
X1491875Y316735D01*
X1491667Y316569D01*
X1491250Y315735D01*
X1490959Y315360D01*
X1490542Y315110D01*
X1490167Y315027D01*
Y316777D01*
G01X1477781Y331695D02*
X1475281D01*
G01X1482531Y333945D02*
Y337195D01*
X1479031D01*
G01X1470531Y333945D02*
Y337195D01*
X1474031D01*
G01X1507200Y330200D02*
Y318800D01*
G01X1493800Y330200D02*
X1507200D01*
G01X1493800Y318800D02*
Y330200D01*
G01X1507200Y318800D02*
X1493800D01*
G01X1581700Y387900D02*
X1577100D01*
Y380541D01*
X1572924D01*
Y374674D01*
X1524300D01*
Y368700D01*
X1520700D01*
Y349100D01*
G01X1497438Y349093D02*
X1515625D01*
G01X1503775Y458720D02*
X1550048D01*
Y455503D01*
X1551668D01*
Y452119D01*
X1553336D01*
Y448617D01*
X1551882D01*
Y445281D01*
X1549802D01*
Y441907D01*
X1551637D01*
Y438595D01*
X1557641D01*
Y434069D01*
X1559501D01*
Y429988D01*
X1553829D01*
Y419939D01*
X1555401D01*
Y416318D01*
X1553590D01*
Y413053D01*
X1551899D01*
Y409550D01*
X1548182D01*
Y402869D01*
X1522622D01*
Y399461D01*
X1507200D01*
Y402737D01*
X1505032D01*
Y406120D01*
X1495382D01*
Y409408D01*
X1497073D01*
Y413112D01*
X1495429D01*
Y416341D01*
X1493308D01*
Y419748D01*
X1495310D01*
Y423132D01*
X1493380D01*
Y426468D01*
X1495477D01*
Y431318D01*
X1499297D01*
Y438515D01*
X1497335D01*
Y441931D01*
X1499170D01*
Y445338D01*
X1500981D01*
Y448770D01*
X1499456D01*
Y452129D01*
X1501028D01*
Y455394D01*
X1503101D01*
Y458720D01*
X1503775D01*
G01X1520700Y349100D02*
Y349200D01*
X1518600Y351300D01*
X1523000D01*
X1520900Y349200D01*
X1520700D01*
G01X1481421Y403639D02*
Y406139D01*
X1480380D01*
X1480046Y406014D01*
X1479838Y405847D01*
X1479755Y405514D01*
X1479838Y405181D01*
X1480088Y404972D01*
X1480380Y404847D01*
X1481421D01*
G01X1480380D02*
X1479755Y403639D01*
G01X1478405Y404139D02*
X1478155Y403847D01*
X1477821Y403681D01*
X1477446Y403639D01*
X1477113Y403681D01*
X1476780Y403889D01*
X1476571Y404139D01*
X1476530Y404389D01*
X1476613Y404681D01*
X1476905Y404889D01*
X1477196Y404972D01*
X1477571D01*
G01X1477196D02*
X1476946Y405097D01*
X1476738Y405306D01*
X1476655Y405556D01*
X1476738Y405806D01*
X1476946Y406014D01*
X1477321Y406139D01*
X1477696Y406097D01*
X1478071Y405931D01*
G01X1475346Y403639D02*
Y406139D01*
X1473430Y403639D01*
Y406139D01*
G01X1472205Y404139D02*
X1471955Y403847D01*
X1471621Y403681D01*
X1471246Y403639D01*
X1470913Y403681D01*
X1470580Y403889D01*
X1470371Y404139D01*
X1470330Y404389D01*
X1470413Y404681D01*
X1470705Y404889D01*
X1470996Y404972D01*
X1471371D01*
G01X1470996D02*
X1470746Y405097D01*
X1470538Y405306D01*
X1470455Y405556D01*
X1470538Y405806D01*
X1470746Y406014D01*
X1471121Y406139D01*
X1471496Y406097D01*
X1471871Y405931D01*
G01X1489300Y350367D02*
X1491800D01*
Y351408D01*
X1491675Y351742D01*
X1491508Y351950D01*
X1491175Y352033D01*
X1490842Y351950D01*
X1490633Y351700D01*
X1490508Y351408D01*
Y350367D01*
G01Y351408D02*
X1489300Y352033D01*
G01Y354217D02*
X1489842Y354300D01*
X1490300Y354425D01*
X1490717Y354592D01*
X1491175Y354800D01*
X1491800Y355133D01*
Y353467D01*
G01X1491592Y358317D02*
X1491717Y358067D01*
X1491800Y357775D01*
Y357442D01*
X1491675Y357067D01*
X1491467Y356775D01*
X1491217Y356567D01*
X1490800Y356400D01*
X1490425Y356358D01*
X1490050Y356442D01*
X1489800Y356567D01*
X1489550Y356817D01*
X1489383Y357108D01*
X1489300Y357400D01*
Y357692D01*
X1489383Y357983D01*
X1489508Y358233D01*
X1489675Y358442D01*
G01X1491383Y359708D02*
X1491633Y359958D01*
X1491758Y360250D01*
X1491800Y360583D01*
X1491717Y361000D01*
X1491508Y361292D01*
X1491258Y361375D01*
X1491008Y361333D01*
X1490800Y361167D01*
X1490383Y360333D01*
X1490092Y359958D01*
X1489675Y359708D01*
X1489300Y359625D01*
Y361375D01*
G01X1490342Y362808D02*
X1490633Y363100D01*
X1490800Y363350D01*
X1490883Y363683D01*
X1490800Y363975D01*
X1490633Y364183D01*
X1490383Y364350D01*
X1490092Y364392D01*
X1489842Y364350D01*
X1489592Y364183D01*
X1489383Y363933D01*
X1489300Y363642D01*
X1489383Y363308D01*
X1489633Y363017D01*
X1490008Y362850D01*
X1490425Y362808D01*
X1490967Y362892D01*
X1491258Y363017D01*
X1491550Y363225D01*
X1491758Y363517D01*
X1491800Y363808D01*
X1491717Y364100D01*
X1491508Y364308D01*
G01X1471300Y364667D02*
X1473800D01*
Y365708D01*
X1473675Y366042D01*
X1473508Y366250D01*
X1473175Y366333D01*
X1472842Y366250D01*
X1472633Y366000D01*
X1472508Y365708D01*
Y364667D01*
G01Y365708D02*
X1471300Y366333D01*
G01Y368517D02*
X1471842Y368600D01*
X1472300Y368725D01*
X1472717Y368892D01*
X1473175Y369100D01*
X1473800Y369433D01*
Y367767D01*
G01X1473592Y372617D02*
X1473717Y372367D01*
X1473800Y372075D01*
Y371742D01*
X1473675Y371367D01*
X1473467Y371075D01*
X1473217Y370867D01*
X1472800Y370700D01*
X1472425Y370658D01*
X1472050Y370742D01*
X1471800Y370867D01*
X1471550Y371117D01*
X1471383Y371408D01*
X1471300Y371700D01*
Y371992D01*
X1471383Y372283D01*
X1471508Y372533D01*
X1471675Y372742D01*
G01X1471300Y374800D02*
X1473800D01*
X1473300Y374300D01*
G01X1471300D02*
Y375300D01*
G01X1473800Y377900D02*
X1473717Y377567D01*
X1473508Y377317D01*
X1473258Y377150D01*
X1472925Y377025D01*
X1472550Y376983D01*
X1472175Y377025D01*
X1471842Y377150D01*
X1471592Y377317D01*
X1471383Y377567D01*
X1471300Y377900D01*
X1471383Y378233D01*
X1471592Y378483D01*
X1471842Y378650D01*
X1472175Y378775D01*
X1472550Y378817D01*
X1472925Y378775D01*
X1473258Y378650D01*
X1473508Y378483D01*
X1473717Y378233D01*
X1473800Y377900D01*
G01X1484400Y355767D02*
X1486900D01*
Y356808D01*
X1486775Y357142D01*
X1486608Y357350D01*
X1486275Y357433D01*
X1485942Y357350D01*
X1485733Y357100D01*
X1485608Y356808D01*
Y355767D01*
G01Y356808D02*
X1484400Y357433D01*
G01Y359700D02*
X1486900D01*
X1486400Y359200D01*
G01X1484400D02*
Y360200D01*
G01X1486900Y361550D02*
X1484400Y362133D01*
X1486900Y362800D01*
X1484400Y363467D01*
X1486900Y364050D01*
G01X1486483Y365108D02*
X1486733Y365358D01*
X1486858Y365650D01*
X1486900Y365983D01*
X1486817Y366400D01*
X1486608Y366692D01*
X1486358Y366775D01*
X1486108Y366733D01*
X1485900Y366567D01*
X1485483Y365733D01*
X1485192Y365358D01*
X1484775Y365108D01*
X1484400Y365025D01*
Y366775D01*
G01Y368917D02*
X1484942Y369000D01*
X1485400Y369125D01*
X1485817Y369292D01*
X1486275Y369500D01*
X1486900Y369833D01*
Y368167D01*
G01X1509600Y352317D02*
X1512100D01*
Y353358D01*
X1511975Y353692D01*
X1511808Y353900D01*
X1511475Y353983D01*
X1511142Y353900D01*
X1510933Y353650D01*
X1510808Y353358D01*
Y352317D01*
G01Y353358D02*
X1509600Y353983D01*
G01Y356167D02*
X1510142Y356250D01*
X1510600Y356375D01*
X1511017Y356542D01*
X1511475Y356750D01*
X1512100Y357083D01*
Y355417D01*
G01Y358100D02*
X1509600Y358683D01*
X1512100Y359350D01*
X1509600Y360017D01*
X1512100Y360600D01*
G01X1509600Y362450D02*
X1512100D01*
X1511600Y361950D01*
G01X1509600D02*
Y362950D01*
G01X1510100Y364633D02*
X1509808Y364883D01*
X1509642Y365217D01*
X1509600Y365592D01*
X1509642Y365925D01*
X1509850Y366258D01*
X1510100Y366467D01*
X1510350Y366508D01*
X1510642Y366425D01*
X1510850Y366133D01*
X1510933Y365842D01*
Y365467D01*
G01Y365842D02*
X1511058Y366092D01*
X1511267Y366300D01*
X1511517Y366383D01*
X1511767Y366300D01*
X1511975Y366092D01*
X1512100Y365717D01*
X1512058Y365342D01*
X1511892Y364967D01*
G01X1487883Y379300D02*
Y381800D01*
X1486842D01*
X1486508Y381675D01*
X1486300Y381508D01*
X1486217Y381175D01*
X1486300Y380842D01*
X1486550Y380633D01*
X1486842Y380508D01*
X1487883D01*
G01X1486842D02*
X1486217Y379300D01*
G01X1484033D02*
X1483950Y379842D01*
X1483825Y380300D01*
X1483658Y380717D01*
X1483450Y381175D01*
X1483117Y381800D01*
X1484783D01*
G01X1482100D02*
X1481517Y379300D01*
X1480850Y381800D01*
X1480183Y379300D01*
X1479600Y381800D01*
G01X1477750Y379300D02*
Y381800D01*
X1478250Y381300D01*
G01Y379300D02*
X1477250D01*
G01X1475358Y379592D02*
X1475067Y379383D01*
X1474733Y379300D01*
X1474400Y379383D01*
X1474108Y379633D01*
X1473900Y380008D01*
X1473817Y380383D01*
Y380842D01*
X1473900Y381217D01*
X1474108Y381550D01*
X1474358Y381717D01*
X1474650Y381800D01*
X1474983Y381717D01*
X1475233Y381550D01*
X1475400Y381300D01*
X1475483Y380967D01*
X1475400Y380675D01*
X1475192Y380383D01*
X1474942Y380217D01*
X1474650Y380175D01*
X1474317Y380258D01*
X1474067Y380467D01*
X1473817Y380842D01*
G01X1514183Y446350D02*
X1510850Y453350D01*
X1507517Y446350D01*
G01X1508717Y448800D02*
X1512983D01*
G01X1478273Y437391D02*
X1480773D01*
Y438432D01*
X1480648Y438766D01*
X1480481Y438974D01*
X1480148Y439057D01*
X1479815Y438974D01*
X1479606Y438724D01*
X1479481Y438432D01*
Y437391D01*
G01Y438432D02*
X1478273Y439057D01*
G01X1478773Y440407D02*
X1478481Y440657D01*
X1478315Y440991D01*
X1478273Y441366D01*
X1478315Y441699D01*
X1478523Y442032D01*
X1478773Y442241D01*
X1479023Y442282D01*
X1479315Y442199D01*
X1479523Y441907D01*
X1479606Y441616D01*
Y441241D01*
G01Y441616D02*
X1479731Y441866D01*
X1479940Y442074D01*
X1480190Y442157D01*
X1480440Y442074D01*
X1480648Y441866D01*
X1480773Y441491D01*
X1480731Y441116D01*
X1480565Y440741D01*
G01X1478273Y443466D02*
X1480773D01*
X1478273Y445382D01*
X1480773D01*
G01X1478273Y447524D02*
X1480773D01*
X1480273Y447024D01*
G01X1478273D02*
Y448024D01*
G01X1480283Y410459D02*
X1480533Y410584D01*
X1480825Y410667D01*
X1481158D01*
X1481533Y410542D01*
X1481825Y410334D01*
X1482033Y410084D01*
X1482200Y409667D01*
X1482242Y409292D01*
X1482158Y408917D01*
X1482033Y408667D01*
X1481783Y408417D01*
X1481492Y408250D01*
X1481200Y408167D01*
X1480908D01*
X1480617Y408250D01*
X1480367Y408375D01*
X1480158Y408542D01*
G01X1479017Y408667D02*
X1478767Y408375D01*
X1478433Y408209D01*
X1478058Y408167D01*
X1477725Y408209D01*
X1477392Y408417D01*
X1477183Y408667D01*
X1477142Y408917D01*
X1477225Y409209D01*
X1477517Y409417D01*
X1477808Y409500D01*
X1478183D01*
G01X1477808D02*
X1477558Y409625D01*
X1477350Y409834D01*
X1477267Y410084D01*
X1477350Y410334D01*
X1477558Y410542D01*
X1477933Y410667D01*
X1478308Y410625D01*
X1478683Y410459D01*
G01X1475958Y408167D02*
Y410667D01*
X1474042Y408167D01*
Y410667D01*
G01X1472817Y408667D02*
X1472567Y408375D01*
X1472233Y408209D01*
X1471858Y408167D01*
X1471525Y408209D01*
X1471192Y408417D01*
X1470983Y408667D01*
X1470942Y408917D01*
X1471025Y409209D01*
X1471317Y409417D01*
X1471608Y409500D01*
X1471983D01*
G01X1471608D02*
X1471358Y409625D01*
X1471150Y409834D01*
X1471067Y410084D01*
X1471150Y410334D01*
X1471358Y410542D01*
X1471733Y410667D01*
X1472108Y410625D01*
X1472483Y410459D01*
G01X1468800Y410667D02*
X1469133Y410584D01*
X1469383Y410375D01*
X1469550Y410125D01*
X1469675Y409792D01*
X1469717Y409417D01*
X1469675Y409042D01*
X1469550Y408709D01*
X1469383Y408459D01*
X1469133Y408250D01*
X1468800Y408167D01*
X1468467Y408250D01*
X1468217Y408459D01*
X1468050Y408709D01*
X1467925Y409042D01*
X1467883Y409417D01*
X1467925Y409792D01*
X1468050Y410125D01*
X1468217Y410375D01*
X1468467Y410584D01*
X1468800Y410667D01*
G01X1478783Y415459D02*
X1479033Y415584D01*
X1479325Y415667D01*
X1479658D01*
X1480033Y415542D01*
X1480325Y415334D01*
X1480533Y415084D01*
X1480700Y414667D01*
X1480742Y414292D01*
X1480658Y413917D01*
X1480533Y413667D01*
X1480283Y413417D01*
X1479992Y413250D01*
X1479700Y413167D01*
X1479408D01*
X1479117Y413250D01*
X1478867Y413375D01*
X1478658Y413542D01*
G01X1477517Y413667D02*
X1477267Y413375D01*
X1476933Y413209D01*
X1476558Y413167D01*
X1476225Y413209D01*
X1475892Y413417D01*
X1475683Y413667D01*
X1475642Y413917D01*
X1475725Y414209D01*
X1476017Y414417D01*
X1476308Y414500D01*
X1476683D01*
G01X1476308D02*
X1476058Y414625D01*
X1475850Y414834D01*
X1475767Y415084D01*
X1475850Y415334D01*
X1476058Y415542D01*
X1476433Y415667D01*
X1476808Y415625D01*
X1477183Y415459D01*
G01X1474458Y413167D02*
Y415667D01*
X1472542Y413167D01*
Y415667D01*
G01X1471192Y415250D02*
X1470942Y415500D01*
X1470650Y415625D01*
X1470317Y415667D01*
X1469900Y415584D01*
X1469608Y415375D01*
X1469525Y415125D01*
X1469567Y414875D01*
X1469733Y414667D01*
X1470567Y414250D01*
X1470942Y413959D01*
X1471192Y413542D01*
X1471275Y413167D01*
X1469525D01*
G01X1467383D02*
X1467300Y413709D01*
X1467175Y414167D01*
X1467008Y414584D01*
X1466800Y415042D01*
X1466467Y415667D01*
X1468133D01*
G01X1477020Y426167D02*
X1477145Y425917D01*
X1477228Y425625D01*
Y425292D01*
X1477103Y424917D01*
X1476895Y424625D01*
X1476645Y424417D01*
X1476228Y424250D01*
X1475853Y424208D01*
X1475478Y424292D01*
X1475228Y424417D01*
X1474978Y424667D01*
X1474811Y424958D01*
X1474728Y425250D01*
Y425542D01*
X1474811Y425833D01*
X1474936Y426083D01*
X1475103Y426292D01*
G01X1475228Y427433D02*
X1474936Y427683D01*
X1474770Y428017D01*
X1474728Y428392D01*
X1474770Y428725D01*
X1474978Y429058D01*
X1475228Y429267D01*
X1475478Y429308D01*
X1475770Y429225D01*
X1475978Y428933D01*
X1476061Y428642D01*
Y428267D01*
G01Y428642D02*
X1476186Y428892D01*
X1476395Y429100D01*
X1476645Y429183D01*
X1476895Y429100D01*
X1477103Y428892D01*
X1477228Y428517D01*
X1477186Y428142D01*
X1477020Y427767D01*
G01X1477228Y430200D02*
X1474728Y430783D01*
X1477228Y431450D01*
X1474728Y432117D01*
X1477228Y432700D01*
G01X1474728Y434550D02*
X1477228D01*
X1476728Y434050D01*
G01X1474728D02*
Y435050D01*
G01X1521883Y489600D02*
Y492100D01*
X1520842D01*
X1520508Y491975D01*
X1520300Y491808D01*
X1520217Y491475D01*
X1520300Y491142D01*
X1520550Y490933D01*
X1520842Y490808D01*
X1521883D01*
G01X1520842D02*
X1520217Y489600D01*
G01X1518867Y490100D02*
X1518617Y489808D01*
X1518283Y489642D01*
X1517908Y489600D01*
X1517575Y489642D01*
X1517242Y489850D01*
X1517033Y490100D01*
X1516992Y490350D01*
X1517075Y490642D01*
X1517367Y490850D01*
X1517658Y490933D01*
X1518033D01*
G01X1517658D02*
X1517408Y491058D01*
X1517200Y491267D01*
X1517117Y491517D01*
X1517200Y491767D01*
X1517408Y491975D01*
X1517783Y492100D01*
X1518158Y492058D01*
X1518533Y491892D01*
G01X1515933Y489600D02*
Y492100D01*
X1514850Y490017D01*
X1513767Y492100D01*
Y489600D01*
G01X1511750D02*
Y492100D01*
X1512250Y491600D01*
G01Y489600D02*
X1511250D01*
G01X1509442Y491683D02*
X1509192Y491933D01*
X1508900Y492058D01*
X1508567Y492100D01*
X1508150Y492017D01*
X1507858Y491808D01*
X1507775Y491558D01*
X1507817Y491308D01*
X1507983Y491100D01*
X1508817Y490683D01*
X1509192Y490392D01*
X1509442Y489975D01*
X1509525Y489600D01*
X1507775D01*
G01X1516000Y494917D02*
X1518500D01*
Y495958D01*
X1518375Y496292D01*
X1518208Y496500D01*
X1517875Y496583D01*
X1517542Y496500D01*
X1517333Y496250D01*
X1517208Y495958D01*
Y494917D01*
G01Y495958D02*
X1516000Y496583D01*
G01X1516500Y497933D02*
X1516208Y498183D01*
X1516042Y498517D01*
X1516000Y498892D01*
X1516042Y499225D01*
X1516250Y499558D01*
X1516500Y499767D01*
X1516750Y499808D01*
X1517042Y499725D01*
X1517250Y499433D01*
X1517333Y499142D01*
Y498767D01*
G01Y499142D02*
X1517458Y499392D01*
X1517667Y499600D01*
X1517917Y499683D01*
X1518167Y499600D01*
X1518375Y499392D01*
X1518500Y499017D01*
X1518458Y498642D01*
X1518292Y498267D01*
G01X1516000Y500867D02*
X1518500D01*
X1516417Y501950D01*
X1518500Y503033D01*
X1516000D01*
G01Y505050D02*
X1518500D01*
X1518000Y504550D01*
G01X1516000D02*
Y505550D01*
G01X1518500Y508150D02*
X1518417Y507817D01*
X1518208Y507567D01*
X1517958Y507400D01*
X1517625Y507275D01*
X1517250Y507233D01*
X1516875Y507275D01*
X1516542Y507400D01*
X1516292Y507567D01*
X1516083Y507817D01*
X1516000Y508150D01*
X1516083Y508483D01*
X1516292Y508733D01*
X1516542Y508900D01*
X1516875Y509025D01*
X1517250Y509067D01*
X1517625Y509025D01*
X1517958Y508900D01*
X1518208Y508733D01*
X1518417Y508483D01*
X1518500Y508150D01*
G01X1494441Y503904D02*
X1494566Y503654D01*
X1494649Y503362D01*
Y503029D01*
X1494524Y502654D01*
X1494316Y502362D01*
X1494066Y502154D01*
X1493649Y501987D01*
X1493274Y501945D01*
X1492899Y502029D01*
X1492649Y502154D01*
X1492399Y502404D01*
X1492232Y502695D01*
X1492149Y502987D01*
Y503279D01*
X1492232Y503570D01*
X1492357Y503820D01*
X1492524Y504029D01*
G01X1492649Y505170D02*
X1492357Y505420D01*
X1492191Y505754D01*
X1492149Y506129D01*
X1492191Y506462D01*
X1492399Y506795D01*
X1492649Y507004D01*
X1492899Y507045D01*
X1493191Y506962D01*
X1493399Y506670D01*
X1493482Y506379D01*
Y506004D01*
G01Y506379D02*
X1493607Y506629D01*
X1493816Y506837D01*
X1494066Y506920D01*
X1494316Y506837D01*
X1494524Y506629D01*
X1494649Y506254D01*
X1494607Y505879D01*
X1494441Y505504D01*
G01X1492149Y508104D02*
X1494649D01*
X1492566Y509187D01*
X1494649Y510270D01*
X1492149D01*
G01X1492649Y511370D02*
X1492357Y511620D01*
X1492191Y511954D01*
X1492149Y512329D01*
X1492191Y512662D01*
X1492399Y512995D01*
X1492649Y513204D01*
X1492899Y513245D01*
X1493191Y513162D01*
X1493399Y512870D01*
X1493482Y512579D01*
Y512204D01*
G01Y512579D02*
X1493607Y512829D01*
X1493816Y513037D01*
X1494066Y513120D01*
X1494316Y513037D01*
X1494524Y512829D01*
X1494649Y512454D01*
X1494607Y512079D01*
X1494441Y511704D01*
G01X1494649Y515387D02*
X1494566Y515054D01*
X1494357Y514804D01*
X1494107Y514637D01*
X1493774Y514512D01*
X1493399Y514470D01*
X1493024Y514512D01*
X1492691Y514637D01*
X1492441Y514804D01*
X1492232Y515054D01*
X1492149Y515387D01*
X1492232Y515720D01*
X1492441Y515970D01*
X1492691Y516137D01*
X1493024Y516262D01*
X1493399Y516304D01*
X1493774Y516262D01*
X1494107Y516137D01*
X1494357Y515970D01*
X1494566Y515720D01*
X1494649Y515387D01*
G01X1475884Y503529D02*
X1476009Y503279D01*
X1476092Y502987D01*
Y502654D01*
X1475967Y502279D01*
X1475759Y501987D01*
X1475509Y501779D01*
X1475092Y501612D01*
X1474717Y501570D01*
X1474342Y501654D01*
X1474092Y501779D01*
X1473842Y502029D01*
X1473675Y502320D01*
X1473592Y502612D01*
Y502904D01*
X1473675Y503195D01*
X1473800Y503445D01*
X1473967Y503654D01*
G01X1474092Y504795D02*
X1473800Y505045D01*
X1473634Y505379D01*
X1473592Y505754D01*
X1473634Y506087D01*
X1473842Y506420D01*
X1474092Y506629D01*
X1474342Y506670D01*
X1474634Y506587D01*
X1474842Y506295D01*
X1474925Y506004D01*
Y505629D01*
G01Y506004D02*
X1475050Y506254D01*
X1475259Y506462D01*
X1475509Y506545D01*
X1475759Y506462D01*
X1475967Y506254D01*
X1476092Y505879D01*
X1476050Y505504D01*
X1475884Y505129D01*
G01X1473592Y507729D02*
X1476092D01*
X1474009Y508812D01*
X1476092Y509895D01*
X1473592D01*
G01X1475675Y511120D02*
X1475925Y511370D01*
X1476050Y511662D01*
X1476092Y511995D01*
X1476009Y512412D01*
X1475800Y512704D01*
X1475550Y512787D01*
X1475300Y512745D01*
X1475092Y512579D01*
X1474675Y511745D01*
X1474384Y511370D01*
X1473967Y511120D01*
X1473592Y511037D01*
Y512787D01*
G01X1473884Y514304D02*
X1473675Y514595D01*
X1473592Y514929D01*
X1473675Y515262D01*
X1473925Y515554D01*
X1474300Y515762D01*
X1474675Y515845D01*
X1475134D01*
X1475509Y515762D01*
X1475842Y515554D01*
X1476009Y515304D01*
X1476092Y515012D01*
X1476009Y514679D01*
X1475842Y514429D01*
X1475592Y514262D01*
X1475259Y514179D01*
X1474967Y514262D01*
X1474675Y514470D01*
X1474509Y514720D01*
X1474467Y515012D01*
X1474550Y515345D01*
X1474759Y515595D01*
X1475134Y515845D01*
G01X1519459Y514517D02*
X1519584Y514267D01*
X1519667Y513975D01*
Y513642D01*
X1519542Y513267D01*
X1519334Y512975D01*
X1519084Y512767D01*
X1518667Y512600D01*
X1518292Y512558D01*
X1517917Y512642D01*
X1517667Y512767D01*
X1517417Y513017D01*
X1517250Y513308D01*
X1517167Y513600D01*
Y513892D01*
X1517250Y514183D01*
X1517375Y514433D01*
X1517542Y514642D01*
G01X1517667Y515783D02*
X1517375Y516033D01*
X1517209Y516367D01*
X1517167Y516742D01*
X1517209Y517075D01*
X1517417Y517408D01*
X1517667Y517617D01*
X1517917Y517658D01*
X1518209Y517575D01*
X1518417Y517283D01*
X1518500Y516992D01*
Y516617D01*
G01Y516992D02*
X1518625Y517242D01*
X1518834Y517450D01*
X1519084Y517533D01*
X1519334Y517450D01*
X1519542Y517242D01*
X1519667Y516867D01*
X1519625Y516492D01*
X1519459Y516117D01*
G01X1517167Y518717D02*
X1519667D01*
X1517584Y519800D01*
X1519667Y520883D01*
X1517167D01*
G01X1519250Y522108D02*
X1519500Y522358D01*
X1519625Y522650D01*
X1519667Y522983D01*
X1519584Y523400D01*
X1519375Y523692D01*
X1519125Y523775D01*
X1518875Y523733D01*
X1518667Y523567D01*
X1518250Y522733D01*
X1517959Y522358D01*
X1517542Y522108D01*
X1517167Y522025D01*
Y523775D01*
G01X1519667Y526000D02*
X1519584Y525667D01*
X1519375Y525417D01*
X1519125Y525250D01*
X1518792Y525125D01*
X1518417Y525083D01*
X1518042Y525125D01*
X1517709Y525250D01*
X1517459Y525417D01*
X1517250Y525667D01*
X1517167Y526000D01*
X1517250Y526333D01*
X1517459Y526583D01*
X1517709Y526750D01*
X1518042Y526875D01*
X1518417Y526917D01*
X1518792Y526875D01*
X1519125Y526750D01*
X1519375Y526583D01*
X1519584Y526333D01*
X1519667Y526000D01*
G01X1523759Y518217D02*
X1523884Y517967D01*
X1523967Y517675D01*
Y517342D01*
X1523842Y516967D01*
X1523634Y516675D01*
X1523384Y516467D01*
X1522967Y516300D01*
X1522592Y516258D01*
X1522217Y516342D01*
X1521967Y516467D01*
X1521717Y516717D01*
X1521550Y517008D01*
X1521467Y517300D01*
Y517592D01*
X1521550Y517883D01*
X1521675Y518133D01*
X1521842Y518342D01*
G01X1521967Y519483D02*
X1521675Y519733D01*
X1521509Y520067D01*
X1521467Y520442D01*
X1521509Y520775D01*
X1521717Y521108D01*
X1521967Y521317D01*
X1522217Y521358D01*
X1522509Y521275D01*
X1522717Y520983D01*
X1522800Y520692D01*
Y520317D01*
G01Y520692D02*
X1522925Y520942D01*
X1523134Y521150D01*
X1523384Y521233D01*
X1523634Y521150D01*
X1523842Y520942D01*
X1523967Y520567D01*
X1523925Y520192D01*
X1523759Y519817D01*
G01X1521467Y522417D02*
X1523967D01*
X1521884Y523500D01*
X1523967Y524583D01*
X1521467D01*
G01X1523550Y525808D02*
X1523800Y526058D01*
X1523925Y526350D01*
X1523967Y526683D01*
X1523884Y527100D01*
X1523675Y527392D01*
X1523425Y527475D01*
X1523175Y527433D01*
X1522967Y527267D01*
X1522550Y526433D01*
X1522259Y526058D01*
X1521842Y525808D01*
X1521467Y525725D01*
Y527475D01*
G01Y529700D02*
X1523967D01*
X1523467Y529200D01*
G01X1521467D02*
Y530200D01*
G01X1525567Y517708D02*
X1528067D01*
Y519292D01*
G01X1526859Y518708D02*
Y517708D01*
G01X1526900Y521933D02*
X1527025Y522100D01*
X1527234Y522225D01*
X1527525Y522308D01*
X1527775Y522225D01*
X1527942Y522058D01*
X1528067Y521767D01*
Y520642D01*
X1525567D01*
Y522017D01*
X1525734Y522308D01*
X1525984Y522475D01*
X1526275Y522558D01*
X1526567Y522475D01*
X1526817Y522225D01*
X1526900Y521933D01*
Y520642D01*
G01X1526067Y523783D02*
X1525775Y524033D01*
X1525609Y524367D01*
X1525567Y524742D01*
X1525609Y525075D01*
X1525817Y525408D01*
X1526067Y525617D01*
X1526317Y525658D01*
X1526609Y525575D01*
X1526817Y525283D01*
X1526900Y524992D01*
Y524617D01*
G01Y524992D02*
X1527025Y525242D01*
X1527234Y525450D01*
X1527484Y525533D01*
X1527734Y525450D01*
X1527942Y525242D01*
X1528067Y524867D01*
X1528025Y524492D01*
X1527859Y524117D01*
G01X1525567Y526717D02*
X1528067D01*
X1525984Y527800D01*
X1528067Y528883D01*
X1525567D01*
G01Y530900D02*
X1528067D01*
X1527567Y530400D01*
G01X1525567D02*
Y531400D01*
G01X1527559Y586167D02*
X1527684Y585917D01*
X1527767Y585625D01*
Y585292D01*
X1527642Y584917D01*
X1527434Y584625D01*
X1527184Y584417D01*
X1526767Y584250D01*
X1526392Y584208D01*
X1526017Y584292D01*
X1525767Y584417D01*
X1525517Y584667D01*
X1525350Y584958D01*
X1525267Y585250D01*
Y585542D01*
X1525350Y585833D01*
X1525475Y586083D01*
X1525642Y586292D01*
G01X1525767Y587433D02*
X1525475Y587683D01*
X1525309Y588017D01*
X1525267Y588392D01*
X1525309Y588725D01*
X1525517Y589058D01*
X1525767Y589267D01*
X1526017Y589308D01*
X1526309Y589225D01*
X1526517Y588933D01*
X1526600Y588642D01*
Y588267D01*
G01Y588642D02*
X1526725Y588892D01*
X1526934Y589100D01*
X1527184Y589183D01*
X1527434Y589100D01*
X1527642Y588892D01*
X1527767Y588517D01*
X1527725Y588142D01*
X1527559Y587767D01*
G01X1527767Y590617D02*
X1525267D01*
Y592283D01*
G01X1525559Y593842D02*
X1525350Y594133D01*
X1525267Y594467D01*
X1525350Y594800D01*
X1525600Y595092D01*
X1525975Y595300D01*
X1526350Y595383D01*
X1526809D01*
X1527184Y595300D01*
X1527517Y595092D01*
X1527684Y594842D01*
X1527767Y594550D01*
X1527684Y594217D01*
X1527517Y593967D01*
X1527267Y593800D01*
X1526934Y593717D01*
X1526642Y593800D01*
X1526350Y594008D01*
X1526184Y594258D01*
X1526142Y594550D01*
X1526225Y594883D01*
X1526434Y595133D01*
X1526809Y595383D01*
G01X1512994Y586993D02*
X1513119Y586743D01*
X1513202Y586451D01*
Y586118D01*
X1513077Y585743D01*
X1512869Y585451D01*
X1512619Y585243D01*
X1512202Y585076D01*
X1511827Y585034D01*
X1511452Y585118D01*
X1511202Y585243D01*
X1510952Y585493D01*
X1510785Y585784D01*
X1510702Y586076D01*
Y586368D01*
X1510785Y586659D01*
X1510910Y586909D01*
X1511077Y587118D01*
G01X1511202Y588259D02*
X1510910Y588509D01*
X1510744Y588843D01*
X1510702Y589218D01*
X1510744Y589551D01*
X1510952Y589884D01*
X1511202Y590093D01*
X1511452Y590134D01*
X1511744Y590051D01*
X1511952Y589759D01*
X1512035Y589468D01*
Y589093D01*
G01Y589468D02*
X1512160Y589718D01*
X1512369Y589926D01*
X1512619Y590009D01*
X1512869Y589926D01*
X1513077Y589718D01*
X1513202Y589343D01*
X1513160Y588968D01*
X1512994Y588593D01*
G01X1513202Y591443D02*
X1510702D01*
Y593109D01*
G01Y595293D02*
X1511244Y595376D01*
X1511702Y595501D01*
X1512119Y595668D01*
X1512577Y595876D01*
X1513202Y596209D01*
Y594543D01*
G01X1520759Y533817D02*
X1520884Y533567D01*
X1520967Y533275D01*
Y532942D01*
X1520842Y532567D01*
X1520634Y532275D01*
X1520384Y532067D01*
X1519967Y531900D01*
X1519592Y531858D01*
X1519217Y531942D01*
X1518967Y532067D01*
X1518717Y532317D01*
X1518550Y532608D01*
X1518467Y532900D01*
Y533192D01*
X1518550Y533483D01*
X1518675Y533733D01*
X1518842Y533942D01*
G01X1518967Y535083D02*
X1518675Y535333D01*
X1518509Y535667D01*
X1518467Y536042D01*
X1518509Y536375D01*
X1518717Y536708D01*
X1518967Y536917D01*
X1519217Y536958D01*
X1519509Y536875D01*
X1519717Y536583D01*
X1519800Y536292D01*
Y535917D01*
G01Y536292D02*
X1519925Y536542D01*
X1520134Y536750D01*
X1520384Y536833D01*
X1520634Y536750D01*
X1520842Y536542D01*
X1520967Y536167D01*
X1520925Y535792D01*
X1520759Y535417D01*
G01X1520967Y538267D02*
X1518467D01*
Y539933D01*
G01X1520550Y541408D02*
X1520800Y541658D01*
X1520925Y541950D01*
X1520967Y542283D01*
X1520884Y542700D01*
X1520675Y542992D01*
X1520425Y543075D01*
X1520175Y543033D01*
X1519967Y542867D01*
X1519550Y542033D01*
X1519259Y541658D01*
X1518842Y541408D01*
X1518467Y541325D01*
Y543075D01*
G01X1518967Y544383D02*
X1518675Y544633D01*
X1518509Y544967D01*
X1518467Y545342D01*
X1518509Y545675D01*
X1518717Y546008D01*
X1518967Y546217D01*
X1519217Y546258D01*
X1519509Y546175D01*
X1519717Y545883D01*
X1519800Y545592D01*
Y545217D01*
G01Y545592D02*
X1519925Y545842D01*
X1520134Y546050D01*
X1520384Y546133D01*
X1520634Y546050D01*
X1520842Y545842D01*
X1520967Y545467D01*
X1520925Y545092D01*
X1520759Y544717D01*
G01X1524559Y533517D02*
X1524684Y533267D01*
X1524767Y532975D01*
Y532642D01*
X1524642Y532267D01*
X1524434Y531975D01*
X1524184Y531767D01*
X1523767Y531600D01*
X1523392Y531558D01*
X1523017Y531642D01*
X1522767Y531767D01*
X1522517Y532017D01*
X1522350Y532308D01*
X1522267Y532600D01*
Y532892D01*
X1522350Y533183D01*
X1522475Y533433D01*
X1522642Y533642D01*
G01X1522767Y534783D02*
X1522475Y535033D01*
X1522309Y535367D01*
X1522267Y535742D01*
X1522309Y536075D01*
X1522517Y536408D01*
X1522767Y536617D01*
X1523017Y536658D01*
X1523309Y536575D01*
X1523517Y536283D01*
X1523600Y535992D01*
Y535617D01*
G01Y535992D02*
X1523725Y536242D01*
X1523934Y536450D01*
X1524184Y536533D01*
X1524434Y536450D01*
X1524642Y536242D01*
X1524767Y535867D01*
X1524725Y535492D01*
X1524559Y535117D01*
G01X1524767Y537967D02*
X1522267D01*
Y539633D01*
G01X1524350Y541108D02*
X1524600Y541358D01*
X1524725Y541650D01*
X1524767Y541983D01*
X1524684Y542400D01*
X1524475Y542692D01*
X1524225Y542775D01*
X1523975Y542733D01*
X1523767Y542567D01*
X1523350Y541733D01*
X1523059Y541358D01*
X1522642Y541108D01*
X1522267Y541025D01*
Y542775D01*
G01X1524350Y544208D02*
X1524600Y544458D01*
X1524725Y544750D01*
X1524767Y545083D01*
X1524684Y545500D01*
X1524475Y545792D01*
X1524225Y545875D01*
X1523975Y545833D01*
X1523767Y545667D01*
X1523350Y544833D01*
X1523059Y544458D01*
X1522642Y544208D01*
X1522267Y544125D01*
Y545875D01*
G01X1481800Y547136D02*
X1485362D01*
Y559932D01*
X1481800D01*
G01X1484500Y582500D02*
X1481802D01*
G01X1466500D02*
X1469195D01*
G01X1466500D02*
Y559928D01*
G01X1484500Y582500D02*
Y559925D01*
G01X1489700Y547136D02*
X1485909D01*
Y559932D01*
X1489700D01*
G01X1502300Y547136D02*
X1505862D01*
Y559932D01*
X1502300D01*
G01X1505000Y582500D02*
X1502302D01*
G01X1487000D02*
X1489695D01*
G01X1487000D02*
Y559928D01*
G01X1505000Y582500D02*
Y559925D01*
G01X1508612Y570977D02*
X1508737Y570727D01*
X1508820Y570435D01*
Y570102D01*
X1508695Y569727D01*
X1508487Y569435D01*
X1508237Y569227D01*
X1507820Y569060D01*
X1507445Y569018D01*
X1507070Y569102D01*
X1506820Y569227D01*
X1506570Y569477D01*
X1506403Y569768D01*
X1506320Y570060D01*
Y570352D01*
X1506403Y570643D01*
X1506528Y570893D01*
X1506695Y571102D01*
G01X1506820Y572243D02*
X1506528Y572493D01*
X1506362Y572827D01*
X1506320Y573202D01*
X1506362Y573535D01*
X1506570Y573868D01*
X1506820Y574077D01*
X1507070Y574118D01*
X1507362Y574035D01*
X1507570Y573743D01*
X1507653Y573452D01*
Y573077D01*
G01Y573452D02*
X1507778Y573702D01*
X1507987Y573910D01*
X1508237Y573993D01*
X1508487Y573910D01*
X1508695Y573702D01*
X1508820Y573327D01*
X1508778Y572952D01*
X1508612Y572577D01*
G01X1508820Y575427D02*
X1506320D01*
Y577093D01*
G01Y579360D02*
X1508820D01*
X1508320Y578860D01*
G01X1506320D02*
Y579860D01*
G01X1506612Y581752D02*
X1506403Y582043D01*
X1506320Y582377D01*
X1506403Y582710D01*
X1506653Y583002D01*
X1507028Y583210D01*
X1507403Y583293D01*
X1507862D01*
X1508237Y583210D01*
X1508570Y583002D01*
X1508737Y582752D01*
X1508820Y582460D01*
X1508737Y582127D01*
X1508570Y581877D01*
X1508320Y581710D01*
X1507987Y581627D01*
X1507695Y581710D01*
X1507403Y581918D01*
X1507237Y582168D01*
X1507195Y582460D01*
X1507278Y582793D01*
X1507487Y583043D01*
X1507862Y583293D01*
G01X1512700Y547136D02*
X1508909D01*
Y559932D01*
X1512700D01*
G01X1525300Y547136D02*
X1528862D01*
Y559932D01*
X1525300D01*
G01X1528000Y582500D02*
X1525302D01*
G01X1510000D02*
X1512695D01*
G01X1510000D02*
Y559928D01*
G01X1496488Y612531D02*
X1496613Y612281D01*
X1496696Y611989D01*
Y611656D01*
X1496571Y611281D01*
X1496363Y610989D01*
X1496113Y610781D01*
X1495696Y610614D01*
X1495321Y610572D01*
X1494946Y610656D01*
X1494696Y610781D01*
X1494446Y611031D01*
X1494279Y611322D01*
X1494196Y611614D01*
Y611906D01*
X1494279Y612197D01*
X1494404Y612447D01*
X1494571Y612656D01*
G01X1494696Y613797D02*
X1494404Y614047D01*
X1494238Y614381D01*
X1494196Y614756D01*
X1494238Y615089D01*
X1494446Y615422D01*
X1494696Y615631D01*
X1494946Y615672D01*
X1495238Y615589D01*
X1495446Y615297D01*
X1495529Y615006D01*
Y614631D01*
G01Y615006D02*
X1495654Y615256D01*
X1495863Y615464D01*
X1496113Y615547D01*
X1496363Y615464D01*
X1496571Y615256D01*
X1496696Y614881D01*
X1496654Y614506D01*
X1496488Y614131D01*
G01X1496696Y616981D02*
X1494196D01*
Y618647D01*
G01Y620914D02*
X1496696D01*
X1496196Y620414D01*
G01X1494196D02*
Y621414D01*
G01X1496279Y623222D02*
X1496529Y623472D01*
X1496654Y623764D01*
X1496696Y624097D01*
X1496613Y624514D01*
X1496404Y624806D01*
X1496154Y624889D01*
X1495904Y624847D01*
X1495696Y624681D01*
X1495279Y623847D01*
X1494988Y623472D01*
X1494571Y623222D01*
X1494196Y623139D01*
Y624889D01*
G01X1500392Y612917D02*
X1500517Y612667D01*
X1500600Y612375D01*
Y612042D01*
X1500475Y611667D01*
X1500267Y611375D01*
X1500017Y611167D01*
X1499600Y611000D01*
X1499225Y610958D01*
X1498850Y611042D01*
X1498600Y611167D01*
X1498350Y611417D01*
X1498183Y611708D01*
X1498100Y612000D01*
Y612292D01*
X1498183Y612583D01*
X1498308Y612833D01*
X1498475Y613042D01*
G01X1498600Y614183D02*
X1498308Y614433D01*
X1498142Y614767D01*
X1498100Y615142D01*
X1498142Y615475D01*
X1498350Y615808D01*
X1498600Y616017D01*
X1498850Y616058D01*
X1499142Y615975D01*
X1499350Y615683D01*
X1499433Y615392D01*
Y615017D01*
G01Y615392D02*
X1499558Y615642D01*
X1499767Y615850D01*
X1500017Y615933D01*
X1500267Y615850D01*
X1500475Y615642D01*
X1500600Y615267D01*
X1500558Y614892D01*
X1500392Y614517D01*
G01X1500600Y617367D02*
X1498100D01*
Y619033D01*
G01Y621300D02*
X1500600D01*
X1500100Y620800D01*
G01X1498100D02*
Y621800D01*
G01Y624400D02*
X1500600D01*
X1500100Y623900D01*
G01X1498100D02*
Y624900D01*
G01X1503592Y613917D02*
X1503717Y613667D01*
X1503800Y613375D01*
Y613042D01*
X1503675Y612667D01*
X1503467Y612375D01*
X1503217Y612167D01*
X1502800Y612000D01*
X1502425Y611958D01*
X1502050Y612042D01*
X1501800Y612167D01*
X1501550Y612417D01*
X1501383Y612708D01*
X1501300Y613000D01*
Y613292D01*
X1501383Y613583D01*
X1501508Y613833D01*
X1501675Y614042D01*
G01X1501800Y615183D02*
X1501508Y615433D01*
X1501342Y615767D01*
X1501300Y616142D01*
X1501342Y616475D01*
X1501550Y616808D01*
X1501800Y617017D01*
X1502050Y617058D01*
X1502342Y616975D01*
X1502550Y616683D01*
X1502633Y616392D01*
Y616017D01*
G01Y616392D02*
X1502758Y616642D01*
X1502967Y616850D01*
X1503217Y616933D01*
X1503467Y616850D01*
X1503675Y616642D01*
X1503800Y616267D01*
X1503758Y615892D01*
X1503592Y615517D01*
G01X1503800Y618367D02*
X1501300D01*
Y620033D01*
G01Y622300D02*
X1501342Y622592D01*
X1501467Y622925D01*
X1501675Y623133D01*
X1501967Y623217D01*
X1502258Y623133D01*
X1502508Y622883D01*
X1502633Y622508D01*
Y622092D01*
X1502717Y621842D01*
X1502925Y621633D01*
X1503217Y621550D01*
X1503508Y621675D01*
X1503717Y621967D01*
X1503800Y622300D01*
X1503717Y622633D01*
X1503508Y622925D01*
X1503217Y623050D01*
X1502925Y622967D01*
X1502717Y622758D01*
X1502633Y622508D01*
Y622092D01*
X1502508Y621717D01*
X1502258Y621467D01*
X1501967Y621383D01*
X1501675Y621467D01*
X1501467Y621675D01*
X1501342Y622008D01*
X1501300Y622300D01*
G01X1468732Y615262D02*
X1471232D01*
Y616303D01*
X1471107Y616637D01*
X1470940Y616845D01*
X1470607Y616928D01*
X1470274Y616845D01*
X1470065Y616595D01*
X1469940Y616303D01*
Y615262D01*
G01Y616303D02*
X1468732Y616928D01*
G01X1469232Y618278D02*
X1468940Y618528D01*
X1468774Y618862D01*
X1468732Y619237D01*
X1468774Y619570D01*
X1468982Y619903D01*
X1469232Y620112D01*
X1469482Y620153D01*
X1469774Y620070D01*
X1469982Y619778D01*
X1470065Y619487D01*
Y619112D01*
G01Y619487D02*
X1470190Y619737D01*
X1470399Y619945D01*
X1470649Y620028D01*
X1470899Y619945D01*
X1471107Y619737D01*
X1471232Y619362D01*
X1471190Y618987D01*
X1471024Y618612D01*
G01X1471232Y621462D02*
X1468732D01*
Y623128D01*
G01Y625395D02*
X1471232D01*
X1470732Y624895D01*
G01X1468732D02*
Y625895D01*
G01X1486446Y621027D02*
Y623527D01*
X1485405D01*
X1485071Y623402D01*
X1484863Y623235D01*
X1484780Y622902D01*
X1484863Y622569D01*
X1485113Y622360D01*
X1485405Y622235D01*
X1486446D01*
G01X1485405D02*
X1484780Y621027D01*
G01X1483430Y621527D02*
X1483180Y621235D01*
X1482846Y621069D01*
X1482471Y621027D01*
X1482138Y621069D01*
X1481805Y621277D01*
X1481596Y621527D01*
X1481555Y621777D01*
X1481638Y622069D01*
X1481930Y622277D01*
X1482221Y622360D01*
X1482596D01*
G01X1482221D02*
X1481971Y622485D01*
X1481763Y622694D01*
X1481680Y622944D01*
X1481763Y623194D01*
X1481971Y623402D01*
X1482346Y623527D01*
X1482721Y623485D01*
X1483096Y623319D01*
G01X1480246Y623527D02*
Y621027D01*
X1478580D01*
G01X1476313D02*
Y623527D01*
X1476813Y623027D01*
G01Y621027D02*
X1475813D01*
G01X1474130Y621402D02*
X1473880Y621194D01*
X1473588Y621069D01*
X1473213Y621027D01*
X1472838Y621110D01*
X1472546Y621277D01*
X1472338Y621569D01*
X1472296Y621902D01*
X1472380Y622235D01*
X1472588Y622444D01*
X1472880Y622610D01*
X1473171Y622652D01*
X1473463Y622610D01*
X1473838Y622444D01*
X1473713Y623527D01*
X1472588D01*
G01X1531483Y615167D02*
Y617667D01*
X1530442D01*
X1530108Y617542D01*
X1529900Y617375D01*
X1529817Y617042D01*
X1529900Y616709D01*
X1530150Y616500D01*
X1530442Y616375D01*
X1531483D01*
G01X1530442D02*
X1529817Y615167D01*
G01X1528467Y615667D02*
X1528217Y615375D01*
X1527883Y615209D01*
X1527508Y615167D01*
X1527175Y615209D01*
X1526842Y615417D01*
X1526633Y615667D01*
X1526592Y615917D01*
X1526675Y616209D01*
X1526967Y616417D01*
X1527258Y616500D01*
X1527633D01*
G01X1527258D02*
X1527008Y616625D01*
X1526800Y616834D01*
X1526717Y617084D01*
X1526800Y617334D01*
X1527008Y617542D01*
X1527383Y617667D01*
X1527758Y617625D01*
X1528133Y617459D01*
G01X1525283Y617667D02*
Y615167D01*
X1523617D01*
G01X1520850D02*
Y617667D01*
X1522392Y615875D01*
X1520308D01*
G01X1535133Y618667D02*
Y621167D01*
X1534092D01*
X1533758Y621042D01*
X1533550Y620875D01*
X1533467Y620542D01*
X1533550Y620209D01*
X1533800Y620000D01*
X1534092Y619875D01*
X1535133D01*
G01X1534092D02*
X1533467Y618667D01*
G01X1532117Y619167D02*
X1531867Y618875D01*
X1531533Y618709D01*
X1531158Y618667D01*
X1530825Y618709D01*
X1530492Y618917D01*
X1530283Y619167D01*
X1530242Y619417D01*
X1530325Y619709D01*
X1530617Y619917D01*
X1530908Y620000D01*
X1531283D01*
G01X1530908D02*
X1530658Y620125D01*
X1530450Y620334D01*
X1530367Y620584D01*
X1530450Y620834D01*
X1530658Y621042D01*
X1531033Y621167D01*
X1531408Y621125D01*
X1531783Y620959D01*
G01X1528933Y621167D02*
Y618667D01*
X1527267D01*
G01X1525000D02*
Y621167D01*
X1525500Y620667D01*
G01Y618667D02*
X1524500D01*
G01X1521400D02*
Y621167D01*
X1522942Y619375D01*
X1520858D01*
G01X1530333Y624559D02*
X1530583Y624684D01*
X1530875Y624767D01*
X1531208D01*
X1531583Y624642D01*
X1531875Y624434D01*
X1532083Y624184D01*
X1532250Y623767D01*
X1532292Y623392D01*
X1532208Y623017D01*
X1532083Y622767D01*
X1531833Y622517D01*
X1531542Y622350D01*
X1531250Y622267D01*
X1530958D01*
X1530667Y622350D01*
X1530417Y622475D01*
X1530208Y622642D01*
G01X1528150Y624767D02*
Y622267D01*
G01X1529108Y624767D02*
X1527192D01*
G01X1525842Y623309D02*
X1525550Y623600D01*
X1525300Y623767D01*
X1524967Y623850D01*
X1524675Y623767D01*
X1524467Y623600D01*
X1524300Y623350D01*
X1524258Y623059D01*
X1524300Y622809D01*
X1524467Y622559D01*
X1524717Y622350D01*
X1525008Y622267D01*
X1525342Y622350D01*
X1525633Y622600D01*
X1525800Y622975D01*
X1525842Y623392D01*
X1525758Y623934D01*
X1525633Y624225D01*
X1525425Y624517D01*
X1525133Y624725D01*
X1524842Y624767D01*
X1524550Y624684D01*
X1524342Y624475D01*
G01X1522658Y622559D02*
X1522367Y622350D01*
X1522033Y622267D01*
X1521700Y622350D01*
X1521408Y622600D01*
X1521200Y622975D01*
X1521117Y623350D01*
Y623809D01*
X1521200Y624184D01*
X1521408Y624517D01*
X1521658Y624684D01*
X1521950Y624767D01*
X1522283Y624684D01*
X1522533Y624517D01*
X1522700Y624267D01*
X1522783Y623934D01*
X1522700Y623642D01*
X1522492Y623350D01*
X1522242Y623184D01*
X1521950Y623142D01*
X1521617Y623225D01*
X1521367Y623434D01*
X1521117Y623809D01*
G01X1491223Y591812D02*
X1491473Y591937D01*
X1491765Y592020D01*
X1492098D01*
X1492473Y591895D01*
X1492765Y591687D01*
X1492973Y591437D01*
X1493140Y591020D01*
X1493182Y590645D01*
X1493098Y590270D01*
X1492973Y590020D01*
X1492723Y589770D01*
X1492432Y589603D01*
X1492140Y589520D01*
X1491848D01*
X1491557Y589603D01*
X1491307Y589728D01*
X1491098Y589895D01*
G01X1489957Y590020D02*
X1489707Y589728D01*
X1489373Y589562D01*
X1488998Y589520D01*
X1488665Y589562D01*
X1488332Y589770D01*
X1488123Y590020D01*
X1488082Y590270D01*
X1488165Y590562D01*
X1488457Y590770D01*
X1488748Y590853D01*
X1489123D01*
G01X1488748D02*
X1488498Y590978D01*
X1488290Y591187D01*
X1488207Y591437D01*
X1488290Y591687D01*
X1488498Y591895D01*
X1488873Y592020D01*
X1489248Y591978D01*
X1489623Y591812D01*
G01X1486773Y592020D02*
Y589520D01*
X1485107D01*
G01X1483632Y591603D02*
X1483382Y591853D01*
X1483090Y591978D01*
X1482757Y592020D01*
X1482340Y591937D01*
X1482048Y591728D01*
X1481965Y591478D01*
X1482007Y591228D01*
X1482173Y591020D01*
X1483007Y590603D01*
X1483382Y590312D01*
X1483632Y589895D01*
X1483715Y589520D01*
X1481965D01*
G01X1479740Y592020D02*
X1480073Y591937D01*
X1480323Y591728D01*
X1480490Y591478D01*
X1480615Y591145D01*
X1480657Y590770D01*
X1480615Y590395D01*
X1480490Y590062D01*
X1480323Y589812D01*
X1480073Y589603D01*
X1479740Y589520D01*
X1479407Y589603D01*
X1479157Y589812D01*
X1478990Y590062D01*
X1478865Y590395D01*
X1478823Y590770D01*
X1478865Y591145D01*
X1478990Y591478D01*
X1479157Y591728D01*
X1479407Y591937D01*
X1479740Y592020D01*
G01X1502179Y596280D02*
X1502304Y596030D01*
X1502387Y595738D01*
Y595405D01*
X1502262Y595030D01*
X1502054Y594738D01*
X1501804Y594530D01*
X1501387Y594363D01*
X1501012Y594321D01*
X1500637Y594405D01*
X1500387Y594530D01*
X1500137Y594780D01*
X1499970Y595071D01*
X1499887Y595363D01*
Y595655D01*
X1499970Y595946D01*
X1500095Y596196D01*
X1500262Y596405D01*
G01X1500387Y597546D02*
X1500095Y597796D01*
X1499929Y598130D01*
X1499887Y598505D01*
X1499929Y598838D01*
X1500137Y599171D01*
X1500387Y599380D01*
X1500637Y599421D01*
X1500929Y599338D01*
X1501137Y599046D01*
X1501220Y598755D01*
Y598380D01*
G01Y598755D02*
X1501345Y599005D01*
X1501554Y599213D01*
X1501804Y599296D01*
X1502054Y599213D01*
X1502262Y599005D01*
X1502387Y598630D01*
X1502345Y598255D01*
X1502179Y597880D01*
G01X1502387Y600730D02*
X1499887D01*
Y602396D01*
G01X1501970Y603871D02*
X1502220Y604121D01*
X1502345Y604413D01*
X1502387Y604746D01*
X1502304Y605163D01*
X1502095Y605455D01*
X1501845Y605538D01*
X1501595Y605496D01*
X1501387Y605330D01*
X1500970Y604496D01*
X1500679Y604121D01*
X1500262Y603871D01*
X1499887Y603788D01*
Y605538D01*
G01X1500179Y607055D02*
X1499970Y607346D01*
X1499887Y607680D01*
X1499970Y608013D01*
X1500220Y608305D01*
X1500595Y608513D01*
X1500970Y608596D01*
X1501429D01*
X1501804Y608513D01*
X1502137Y608305D01*
X1502304Y608055D01*
X1502387Y607763D01*
X1502304Y607430D01*
X1502137Y607180D01*
X1501887Y607013D01*
X1501554Y606930D01*
X1501262Y607013D01*
X1500970Y607221D01*
X1500804Y607471D01*
X1500762Y607763D01*
X1500845Y608096D01*
X1501054Y608346D01*
X1501429Y608596D01*
G01X1543239Y658678D02*
X1510539D01*
Y639978D01*
X1543239D01*
Y658678D01*
G01X1590684Y-5288D02*
Y-2788D01*
X1589643D01*
X1589309Y-2913D01*
X1589101Y-3080D01*
X1589018Y-3413D01*
X1589101Y-3746D01*
X1589351Y-3955D01*
X1589643Y-4080D01*
X1590684D01*
G01X1589643D02*
X1589018Y-5288D01*
G01X1587543Y-3205D02*
X1587293Y-2955D01*
X1587001Y-2830D01*
X1586668Y-2788D01*
X1586251Y-2871D01*
X1585959Y-3080D01*
X1585876Y-3330D01*
X1585918Y-3580D01*
X1586084Y-3788D01*
X1586918Y-4205D01*
X1587293Y-4496D01*
X1587543Y-4913D01*
X1587626Y-5288D01*
X1585876D01*
G01X1584568Y-2788D02*
Y-4580D01*
X1584401Y-4955D01*
X1584068Y-5205D01*
X1583651Y-5288D01*
X1583234Y-5205D01*
X1582901Y-4955D01*
X1582734Y-4580D01*
Y-2788D01*
G01X1580051Y-5288D02*
Y-2788D01*
X1581593Y-4580D01*
X1579509D01*
G01X1576951Y-5288D02*
Y-2788D01*
X1578493Y-4580D01*
X1576409D01*
G01X1590085Y31484D02*
Y33984D01*
X1589044D01*
X1588710Y33859D01*
X1588502Y33692D01*
X1588419Y33359D01*
X1588502Y33026D01*
X1588752Y32817D01*
X1589044Y32692D01*
X1590085D01*
G01X1589044D02*
X1588419Y31484D01*
G01X1586152D02*
X1585860Y31526D01*
X1585527Y31651D01*
X1585319Y31859D01*
X1585235Y32151D01*
X1585319Y32442D01*
X1585569Y32692D01*
X1585944Y32817D01*
X1586360D01*
X1586610Y32901D01*
X1586819Y33109D01*
X1586902Y33401D01*
X1586777Y33692D01*
X1586485Y33901D01*
X1586152Y33984D01*
X1585819Y33901D01*
X1585527Y33692D01*
X1585402Y33401D01*
X1585485Y33109D01*
X1585694Y32901D01*
X1585944Y32817D01*
X1586360D01*
X1586735Y32692D01*
X1586985Y32442D01*
X1587069Y32151D01*
X1586985Y31859D01*
X1586777Y31651D01*
X1586444Y31526D01*
X1586152Y31484D01*
G01X1583969D02*
Y33984D01*
X1583135D01*
X1582802Y33859D01*
X1582552Y33692D01*
X1582344Y33442D01*
X1582177Y33151D01*
X1582135Y32734D01*
X1582177Y32317D01*
X1582344Y32026D01*
X1582552Y31776D01*
X1582802Y31609D01*
X1583135Y31484D01*
X1583969D01*
G01X1579452D02*
Y33984D01*
X1580994Y32192D01*
X1578910D01*
G01X1576852Y33984D02*
X1577185Y33901D01*
X1577435Y33692D01*
X1577602Y33442D01*
X1577727Y33109D01*
X1577769Y32734D01*
X1577727Y32359D01*
X1577602Y32026D01*
X1577435Y31776D01*
X1577185Y31567D01*
X1576852Y31484D01*
X1576519Y31567D01*
X1576269Y31776D01*
X1576102Y32026D01*
X1575977Y32359D01*
X1575935Y32734D01*
X1575977Y33109D01*
X1576102Y33442D01*
X1576269Y33692D01*
X1576519Y33901D01*
X1576852Y33984D01*
G01X1572008Y21808D02*
X1574508D01*
Y22849D01*
X1574383Y23183D01*
X1574216Y23391D01*
X1573883Y23474D01*
X1573550Y23391D01*
X1573341Y23141D01*
X1573216Y22849D01*
Y21808D01*
G01Y22849D02*
X1572008Y23474D01*
G01Y25741D02*
X1572050Y26033D01*
X1572175Y26366D01*
X1572383Y26574D01*
X1572675Y26658D01*
X1572966Y26574D01*
X1573216Y26324D01*
X1573341Y25949D01*
Y25533D01*
X1573425Y25283D01*
X1573633Y25074D01*
X1573925Y24991D01*
X1574216Y25116D01*
X1574425Y25408D01*
X1574508Y25741D01*
X1574425Y26074D01*
X1574216Y26366D01*
X1573925Y26491D01*
X1573633Y26408D01*
X1573425Y26199D01*
X1573341Y25949D01*
Y25533D01*
X1573216Y25158D01*
X1572966Y24908D01*
X1572675Y24824D01*
X1572383Y24908D01*
X1572175Y25116D01*
X1572050Y25449D01*
X1572008Y25741D01*
G01Y27924D02*
X1574508D01*
Y28758D01*
X1574383Y29091D01*
X1574216Y29341D01*
X1573966Y29549D01*
X1573675Y29716D01*
X1573258Y29758D01*
X1572841Y29716D01*
X1572550Y29549D01*
X1572300Y29341D01*
X1572133Y29091D01*
X1572008Y28758D01*
Y27924D01*
G01X1572508Y31024D02*
X1572216Y31274D01*
X1572050Y31608D01*
X1572008Y31983D01*
X1572050Y32316D01*
X1572258Y32649D01*
X1572508Y32858D01*
X1572758Y32899D01*
X1573050Y32816D01*
X1573258Y32524D01*
X1573341Y32233D01*
Y31858D01*
G01Y32233D02*
X1573466Y32483D01*
X1573675Y32691D01*
X1573925Y32774D01*
X1574175Y32691D01*
X1574383Y32483D01*
X1574508Y32108D01*
X1574466Y31733D01*
X1574300Y31358D01*
G01X1572008Y35041D02*
X1572050Y35333D01*
X1572175Y35666D01*
X1572383Y35874D01*
X1572675Y35958D01*
X1572966Y35874D01*
X1573216Y35624D01*
X1573341Y35249D01*
Y34833D01*
X1573425Y34583D01*
X1573633Y34374D01*
X1573925Y34291D01*
X1574216Y34416D01*
X1574425Y34708D01*
X1574508Y35041D01*
X1574425Y35374D01*
X1574216Y35666D01*
X1573925Y35791D01*
X1573633Y35708D01*
X1573425Y35499D01*
X1573341Y35249D01*
Y34833D01*
X1573216Y34458D01*
X1572966Y34208D01*
X1572675Y34124D01*
X1572383Y34208D01*
X1572175Y34416D01*
X1572050Y34749D01*
X1572008Y35041D01*
G01X1567778Y15690D02*
X1570278D01*
Y16731D01*
X1570153Y17065D01*
X1569986Y17273D01*
X1569653Y17356D01*
X1569320Y17273D01*
X1569111Y17023D01*
X1568986Y16731D01*
Y15690D01*
G01Y16731D02*
X1567778Y17356D01*
G01Y19623D02*
X1567820Y19915D01*
X1567945Y20248D01*
X1568153Y20456D01*
X1568445Y20540D01*
X1568736Y20456D01*
X1568986Y20206D01*
X1569111Y19831D01*
Y19415D01*
X1569195Y19165D01*
X1569403Y18956D01*
X1569695Y18873D01*
X1569986Y18998D01*
X1570195Y19290D01*
X1570278Y19623D01*
X1570195Y19956D01*
X1569986Y20248D01*
X1569695Y20373D01*
X1569403Y20290D01*
X1569195Y20081D01*
X1569111Y19831D01*
Y19415D01*
X1568986Y19040D01*
X1568736Y18790D01*
X1568445Y18706D01*
X1568153Y18790D01*
X1567945Y18998D01*
X1567820Y19331D01*
X1567778Y19623D01*
G01Y21806D02*
X1570278D01*
Y22640D01*
X1570153Y22973D01*
X1569986Y23223D01*
X1569736Y23431D01*
X1569445Y23598D01*
X1569028Y23640D01*
X1568611Y23598D01*
X1568320Y23431D01*
X1568070Y23223D01*
X1567903Y22973D01*
X1567778Y22640D01*
Y21806D01*
G01X1568278Y24906D02*
X1567986Y25156D01*
X1567820Y25490D01*
X1567778Y25865D01*
X1567820Y26198D01*
X1568028Y26531D01*
X1568278Y26740D01*
X1568528Y26781D01*
X1568820Y26698D01*
X1569028Y26406D01*
X1569111Y26115D01*
Y25740D01*
G01Y26115D02*
X1569236Y26365D01*
X1569445Y26573D01*
X1569695Y26656D01*
X1569945Y26573D01*
X1570153Y26365D01*
X1570278Y25990D01*
X1570236Y25615D01*
X1570070Y25240D01*
G01X1568070Y28215D02*
X1567861Y28506D01*
X1567778Y28840D01*
X1567861Y29173D01*
X1568111Y29465D01*
X1568486Y29673D01*
X1568861Y29756D01*
X1569320D01*
X1569695Y29673D01*
X1570028Y29465D01*
X1570195Y29215D01*
X1570278Y28923D01*
X1570195Y28590D01*
X1570028Y28340D01*
X1569778Y28173D01*
X1569445Y28090D01*
X1569153Y28173D01*
X1568861Y28381D01*
X1568695Y28631D01*
X1568653Y28923D01*
X1568736Y29256D01*
X1568945Y29506D01*
X1569320Y29756D01*
G01X1586354Y18145D02*
Y20645D01*
X1585313D01*
X1584979Y20520D01*
X1584771Y20353D01*
X1584688Y20020D01*
X1584771Y19687D01*
X1585021Y19478D01*
X1585313Y19353D01*
X1586354D01*
G01X1585313D02*
X1584688Y18145D01*
G01X1582421D02*
X1582129Y18187D01*
X1581796Y18312D01*
X1581588Y18520D01*
X1581504Y18812D01*
X1581588Y19103D01*
X1581838Y19353D01*
X1582213Y19478D01*
X1582629D01*
X1582879Y19562D01*
X1583088Y19770D01*
X1583171Y20062D01*
X1583046Y20353D01*
X1582754Y20562D01*
X1582421Y20645D01*
X1582088Y20562D01*
X1581796Y20353D01*
X1581671Y20062D01*
X1581754Y19770D01*
X1581963Y19562D01*
X1582213Y19478D01*
X1582629D01*
X1583004Y19353D01*
X1583254Y19103D01*
X1583338Y18812D01*
X1583254Y18520D01*
X1583046Y18312D01*
X1582713Y18187D01*
X1582421Y18145D01*
G01X1580238D02*
Y20645D01*
X1579404D01*
X1579071Y20520D01*
X1578821Y20353D01*
X1578613Y20103D01*
X1578446Y19812D01*
X1578404Y19395D01*
X1578446Y18978D01*
X1578613Y18687D01*
X1578821Y18437D01*
X1579071Y18270D01*
X1579404Y18145D01*
X1580238D01*
G01X1577138Y18645D02*
X1576888Y18353D01*
X1576554Y18187D01*
X1576179Y18145D01*
X1575846Y18187D01*
X1575513Y18395D01*
X1575304Y18645D01*
X1575263Y18895D01*
X1575346Y19187D01*
X1575638Y19395D01*
X1575929Y19478D01*
X1576304D01*
G01X1575929D02*
X1575679Y19603D01*
X1575471Y19812D01*
X1575388Y20062D01*
X1575471Y20312D01*
X1575679Y20520D01*
X1576054Y20645D01*
X1576429Y20603D01*
X1576804Y20437D01*
G01X1573204Y18145D02*
X1573121Y18687D01*
X1572996Y19145D01*
X1572829Y19562D01*
X1572621Y20020D01*
X1572288Y20645D01*
X1573954D01*
G01X1550303Y19854D02*
X1552803D01*
Y20895D01*
X1552678Y21229D01*
X1552511Y21437D01*
X1552178Y21520D01*
X1551845Y21437D01*
X1551636Y21187D01*
X1551511Y20895D01*
Y19854D01*
G01Y20895D02*
X1550303Y21520D01*
G01X1550803Y22870D02*
X1550511Y23120D01*
X1550345Y23454D01*
X1550303Y23829D01*
X1550345Y24162D01*
X1550553Y24495D01*
X1550803Y24704D01*
X1551053Y24745D01*
X1551345Y24662D01*
X1551553Y24370D01*
X1551636Y24079D01*
Y23704D01*
G01Y24079D02*
X1551761Y24329D01*
X1551970Y24537D01*
X1552220Y24620D01*
X1552470Y24537D01*
X1552678Y24329D01*
X1552803Y23954D01*
X1552761Y23579D01*
X1552595Y23204D01*
G01X1552386Y26095D02*
X1552636Y26345D01*
X1552761Y26637D01*
X1552803Y26970D01*
X1552720Y27387D01*
X1552511Y27679D01*
X1552261Y27762D01*
X1552011Y27720D01*
X1551803Y27554D01*
X1551386Y26720D01*
X1551095Y26345D01*
X1550678Y26095D01*
X1550303Y26012D01*
Y27762D01*
G01X1552803Y28737D02*
X1550303Y29320D01*
X1552803Y29987D01*
X1550303Y30654D01*
X1552803Y31237D01*
G01X1550303Y33087D02*
X1552803D01*
X1552303Y32587D01*
G01X1550303D02*
Y33587D01*
G01X1552803Y36187D02*
X1552720Y35854D01*
X1552511Y35604D01*
X1552261Y35437D01*
X1551928Y35312D01*
X1551553Y35270D01*
X1551178Y35312D01*
X1550845Y35437D01*
X1550595Y35604D01*
X1550386Y35854D01*
X1550303Y36187D01*
X1550386Y36520D01*
X1550595Y36770D01*
X1550845Y36937D01*
X1551178Y37062D01*
X1551553Y37104D01*
X1551928Y37062D01*
X1552261Y36937D01*
X1552511Y36770D01*
X1552720Y36520D01*
X1552803Y36187D01*
G01X1546512Y20079D02*
X1549012D01*
Y21120D01*
X1548887Y21454D01*
X1548720Y21662D01*
X1548387Y21745D01*
X1548054Y21662D01*
X1547845Y21412D01*
X1547720Y21120D01*
Y20079D01*
G01Y21120D02*
X1546512Y21745D01*
G01X1547012Y23095D02*
X1546720Y23345D01*
X1546554Y23679D01*
X1546512Y24054D01*
X1546554Y24387D01*
X1546762Y24720D01*
X1547012Y24929D01*
X1547262Y24970D01*
X1547554Y24887D01*
X1547762Y24595D01*
X1547845Y24304D01*
Y23929D01*
G01Y24304D02*
X1547970Y24554D01*
X1548179Y24762D01*
X1548429Y24845D01*
X1548679Y24762D01*
X1548887Y24554D01*
X1549012Y24179D01*
X1548970Y23804D01*
X1548804Y23429D01*
G01X1548595Y26320D02*
X1548845Y26570D01*
X1548970Y26862D01*
X1549012Y27195D01*
X1548929Y27612D01*
X1548720Y27904D01*
X1548470Y27987D01*
X1548220Y27945D01*
X1548012Y27779D01*
X1547595Y26945D01*
X1547304Y26570D01*
X1546887Y26320D01*
X1546512Y26237D01*
Y27987D01*
G01X1549012Y28962D02*
X1546512Y29545D01*
X1549012Y30212D01*
X1546512Y30879D01*
X1549012Y31462D01*
G01X1546512Y33312D02*
X1549012D01*
X1548512Y32812D01*
G01X1546512D02*
Y33812D01*
G01Y36412D02*
X1549012D01*
X1548512Y35912D01*
G01X1546512D02*
Y36912D01*
G01X1585645Y334D02*
X1585895Y459D01*
X1586187Y542D01*
X1586520D01*
X1586895Y417D01*
X1587187Y209D01*
X1587395Y-41D01*
X1587562Y-458D01*
X1587604Y-833D01*
X1587520Y-1208D01*
X1587395Y-1458D01*
X1587145Y-1708D01*
X1586854Y-1875D01*
X1586562Y-1958D01*
X1586270D01*
X1585979Y-1875D01*
X1585729Y-1750D01*
X1585520Y-1583D01*
G01X1584254Y125D02*
X1584004Y375D01*
X1583712Y500D01*
X1583379Y542D01*
X1582962Y459D01*
X1582670Y250D01*
X1582587Y0D01*
X1582629Y-250D01*
X1582795Y-458D01*
X1583629Y-875D01*
X1584004Y-1166D01*
X1584254Y-1583D01*
X1584337Y-1958D01*
X1582587D01*
G01X1581279Y542D02*
Y-1250D01*
X1581112Y-1625D01*
X1580779Y-1875D01*
X1580362Y-1958D01*
X1579945Y-1875D01*
X1579612Y-1625D01*
X1579445Y-1250D01*
Y542D01*
G01X1578054Y125D02*
X1577804Y375D01*
X1577512Y500D01*
X1577179Y542D01*
X1576762Y459D01*
X1576470Y250D01*
X1576387Y0D01*
X1576429Y-250D01*
X1576595Y-458D01*
X1577429Y-875D01*
X1577804Y-1166D01*
X1578054Y-1583D01*
X1578137Y-1958D01*
X1576387D01*
G01X1574162D02*
X1573870Y-1916D01*
X1573537Y-1791D01*
X1573329Y-1583D01*
X1573245Y-1291D01*
X1573329Y-1000D01*
X1573579Y-750D01*
X1573954Y-625D01*
X1574370D01*
X1574620Y-541D01*
X1574829Y-333D01*
X1574912Y-41D01*
X1574787Y250D01*
X1574495Y459D01*
X1574162Y542D01*
X1573829Y459D01*
X1573537Y250D01*
X1573412Y-41D01*
X1573495Y-333D01*
X1573704Y-541D01*
X1573954Y-625D01*
X1574370D01*
X1574745Y-750D01*
X1574995Y-1000D01*
X1575079Y-1291D01*
X1574995Y-1583D01*
X1574787Y-1791D01*
X1574454Y-1916D01*
X1574162Y-1958D01*
G01X1588129Y17054D02*
X1588379Y17179D01*
X1588671Y17262D01*
X1589004D01*
X1589379Y17137D01*
X1589671Y16929D01*
X1589879Y16679D01*
X1590046Y16262D01*
X1590088Y15887D01*
X1590004Y15512D01*
X1589879Y15262D01*
X1589629Y15012D01*
X1589338Y14845D01*
X1589046Y14762D01*
X1588754D01*
X1588463Y14845D01*
X1588213Y14970D01*
X1588004Y15137D01*
G01X1585946Y14762D02*
X1585654Y14804D01*
X1585321Y14929D01*
X1585113Y15137D01*
X1585029Y15429D01*
X1585113Y15720D01*
X1585363Y15970D01*
X1585738Y16095D01*
X1586154D01*
X1586404Y16179D01*
X1586613Y16387D01*
X1586696Y16679D01*
X1586571Y16970D01*
X1586279Y17179D01*
X1585946Y17262D01*
X1585613Y17179D01*
X1585321Y16970D01*
X1585196Y16679D01*
X1585279Y16387D01*
X1585488Y16179D01*
X1585738Y16095D01*
X1586154D01*
X1586529Y15970D01*
X1586779Y15720D01*
X1586863Y15429D01*
X1586779Y15137D01*
X1586571Y14929D01*
X1586238Y14804D01*
X1585946Y14762D01*
G01X1583763D02*
Y17262D01*
X1582929D01*
X1582596Y17137D01*
X1582346Y16970D01*
X1582138Y16720D01*
X1581971Y16429D01*
X1581929Y16012D01*
X1581971Y15595D01*
X1582138Y15304D01*
X1582346Y15054D01*
X1582596Y14887D01*
X1582929Y14762D01*
X1583763D01*
G01X1579246D02*
Y17262D01*
X1580788Y15470D01*
X1578704D01*
G01X1585513Y9491D02*
X1585763Y9616D01*
X1586055Y9699D01*
X1586388D01*
X1586763Y9574D01*
X1587055Y9366D01*
X1587263Y9116D01*
X1587430Y8699D01*
X1587472Y8324D01*
X1587388Y7949D01*
X1587263Y7699D01*
X1587013Y7449D01*
X1586722Y7282D01*
X1586430Y7199D01*
X1586138D01*
X1585847Y7282D01*
X1585597Y7407D01*
X1585388Y7574D01*
G01X1583330Y7199D02*
Y9699D01*
X1583830Y9199D01*
G01Y7199D02*
X1582830D01*
G01X1581063Y9699D02*
Y7199D01*
X1579397D01*
G01X1577130D02*
Y9699D01*
X1577630Y9199D01*
G01Y7199D02*
X1576630D01*
G01X1574030D02*
Y9699D01*
X1574530Y9199D01*
G01Y7199D02*
X1573530D01*
G01X1571638Y7491D02*
X1571347Y7282D01*
X1571013Y7199D01*
X1570680Y7282D01*
X1570388Y7532D01*
X1570180Y7907D01*
X1570097Y8282D01*
Y8741D01*
X1570180Y9116D01*
X1570388Y9449D01*
X1570638Y9616D01*
X1570930Y9699D01*
X1571263Y9616D01*
X1571513Y9449D01*
X1571680Y9199D01*
X1571763Y8866D01*
X1571680Y8574D01*
X1571472Y8282D01*
X1571222Y8116D01*
X1570930Y8074D01*
X1570597Y8157D01*
X1570347Y8366D01*
X1570097Y8741D01*
G01X1588024Y25809D02*
Y24017D01*
X1587857Y23642D01*
X1587524Y23392D01*
X1587107Y23309D01*
X1586690Y23392D01*
X1586357Y23642D01*
X1586190Y24017D01*
Y25809D01*
G01X1584007Y23309D02*
X1583715Y23351D01*
X1583382Y23476D01*
X1583174Y23684D01*
X1583090Y23976D01*
X1583174Y24267D01*
X1583424Y24517D01*
X1583799Y24642D01*
X1584215D01*
X1584465Y24726D01*
X1584674Y24934D01*
X1584757Y25226D01*
X1584632Y25517D01*
X1584340Y25726D01*
X1584007Y25809D01*
X1583674Y25726D01*
X1583382Y25517D01*
X1583257Y25226D01*
X1583340Y24934D01*
X1583549Y24726D01*
X1583799Y24642D01*
X1584215D01*
X1584590Y24517D01*
X1584840Y24267D01*
X1584924Y23976D01*
X1584840Y23684D01*
X1584632Y23476D01*
X1584299Y23351D01*
X1584007Y23309D01*
G01X1581824D02*
Y25809D01*
X1580990D01*
X1580657Y25684D01*
X1580407Y25517D01*
X1580199Y25267D01*
X1580032Y24976D01*
X1579990Y24559D01*
X1580032Y24142D01*
X1580199Y23851D01*
X1580407Y23601D01*
X1580657Y23434D01*
X1580990Y23309D01*
X1581824D01*
G01X1577807D02*
X1577515Y23351D01*
X1577182Y23476D01*
X1576974Y23684D01*
X1576890Y23976D01*
X1576974Y24267D01*
X1577224Y24517D01*
X1577599Y24642D01*
X1578015D01*
X1578265Y24726D01*
X1578474Y24934D01*
X1578557Y25226D01*
X1578432Y25517D01*
X1578140Y25726D01*
X1577807Y25809D01*
X1577474Y25726D01*
X1577182Y25517D01*
X1577057Y25226D01*
X1577140Y24934D01*
X1577349Y24726D01*
X1577599Y24642D01*
X1578015D01*
X1578390Y24517D01*
X1578640Y24267D01*
X1578724Y23976D01*
X1578640Y23684D01*
X1578432Y23476D01*
X1578099Y23351D01*
X1577807Y23309D01*
G01X1576700Y-7800D02*
X1576648Y-7532D01*
X1576493Y-7225D01*
X1576235Y-7033D01*
X1575873Y-6957D01*
X1575512Y-7033D01*
X1575202Y-7263D01*
X1575047Y-7608D01*
Y-7992D01*
X1574943Y-8222D01*
X1574685Y-8413D01*
X1574323Y-8490D01*
X1573962Y-8375D01*
X1573703Y-8107D01*
X1573600Y-7800D01*
X1573703Y-7493D01*
X1573962Y-7225D01*
X1574323Y-7110D01*
X1574685Y-7187D01*
X1574943Y-7378D01*
X1575047Y-7608D01*
Y-7992D01*
X1575202Y-8337D01*
X1575512Y-8567D01*
X1575873Y-8643D01*
X1576235Y-8567D01*
X1576493Y-8375D01*
X1576648Y-8068D01*
X1576700Y-7800D01*
G01X1587990Y93200D02*
X1590100D01*
G01X1584272D02*
X1574500D01*
Y97848D01*
X1578790D01*
Y102348D01*
G01X1604437Y73417D02*
Y75917D01*
X1603396D01*
X1603062Y75792D01*
X1602854Y75625D01*
X1602771Y75292D01*
X1602854Y74959D01*
X1603104Y74750D01*
X1603396Y74625D01*
X1604437D01*
G01X1603396D02*
X1602771Y73417D01*
G01X1601296Y75500D02*
X1601046Y75750D01*
X1600754Y75875D01*
X1600421Y75917D01*
X1600004Y75834D01*
X1599712Y75625D01*
X1599629Y75375D01*
X1599671Y75125D01*
X1599837Y74917D01*
X1600671Y74500D01*
X1601046Y74209D01*
X1601296Y73792D01*
X1601379Y73417D01*
X1599629D01*
G01X1598321Y73792D02*
X1598071Y73584D01*
X1597779Y73459D01*
X1597404Y73417D01*
X1597029Y73500D01*
X1596737Y73667D01*
X1596529Y73959D01*
X1596487Y74292D01*
X1596571Y74625D01*
X1596779Y74834D01*
X1597071Y75000D01*
X1597362Y75042D01*
X1597654Y75000D01*
X1598029Y74834D01*
X1597904Y75917D01*
X1596779D01*
G01X1595554D02*
X1594971Y73417D01*
X1594304Y75917D01*
X1593637Y73417D01*
X1593054Y75917D01*
G01X1591204Y73417D02*
Y75917D01*
X1591704Y75417D01*
G01Y73417D02*
X1590704D01*
G01X1588104D02*
Y75917D01*
X1588604Y75417D01*
G01Y73417D02*
X1587604D01*
G01X1585004D02*
Y75917D01*
X1585504Y75417D01*
G01Y73417D02*
X1584504D01*
G01X1597683Y58300D02*
Y60800D01*
X1596642D01*
X1596308Y60675D01*
X1596100Y60508D01*
X1596017Y60175D01*
X1596100Y59842D01*
X1596350Y59633D01*
X1596642Y59508D01*
X1597683D01*
G01X1596642D02*
X1596017Y58300D01*
G01X1594542Y60383D02*
X1594292Y60633D01*
X1594000Y60758D01*
X1593667Y60800D01*
X1593250Y60717D01*
X1592958Y60508D01*
X1592875Y60258D01*
X1592917Y60008D01*
X1593083Y59800D01*
X1593917Y59383D01*
X1594292Y59092D01*
X1594542Y58675D01*
X1594625Y58300D01*
X1592875D01*
G01X1591483D02*
Y60800D01*
X1590442D01*
X1590108Y60675D01*
X1589900Y60508D01*
X1589817Y60175D01*
X1589900Y59842D01*
X1590150Y59633D01*
X1590442Y59508D01*
X1591483D01*
G01X1590442D02*
X1589817Y58300D01*
G01X1587550D02*
Y60800D01*
X1588050Y60300D01*
G01Y58300D02*
X1587050D01*
G01X1584450Y60800D02*
X1584783Y60717D01*
X1585033Y60508D01*
X1585200Y60258D01*
X1585325Y59925D01*
X1585367Y59550D01*
X1585325Y59175D01*
X1585200Y58842D01*
X1585033Y58592D01*
X1584783Y58383D01*
X1584450Y58300D01*
X1584117Y58383D01*
X1583867Y58592D01*
X1583700Y58842D01*
X1583575Y59175D01*
X1583533Y59550D01*
X1583575Y59925D01*
X1583700Y60258D01*
X1583867Y60508D01*
X1584117Y60717D01*
X1584450Y60800D01*
G01X1600980Y34865D02*
Y37365D01*
X1599939D01*
X1599605Y37240D01*
X1599397Y37073D01*
X1599314Y36740D01*
X1599397Y36407D01*
X1599647Y36198D01*
X1599939Y36073D01*
X1600980D01*
G01X1599939D02*
X1599314Y34865D01*
G01X1597047D02*
X1596755Y34907D01*
X1596422Y35032D01*
X1596214Y35240D01*
X1596130Y35532D01*
X1596214Y35823D01*
X1596464Y36073D01*
X1596839Y36198D01*
X1597255D01*
X1597505Y36282D01*
X1597714Y36490D01*
X1597797Y36782D01*
X1597672Y37073D01*
X1597380Y37282D01*
X1597047Y37365D01*
X1596714Y37282D01*
X1596422Y37073D01*
X1596297Y36782D01*
X1596380Y36490D01*
X1596589Y36282D01*
X1596839Y36198D01*
X1597255D01*
X1597630Y36073D01*
X1597880Y35823D01*
X1597964Y35532D01*
X1597880Y35240D01*
X1597672Y35032D01*
X1597339Y34907D01*
X1597047Y34865D01*
G01X1594864D02*
Y37365D01*
X1594030D01*
X1593697Y37240D01*
X1593447Y37073D01*
X1593239Y36823D01*
X1593072Y36532D01*
X1593030Y36115D01*
X1593072Y35698D01*
X1593239Y35407D01*
X1593447Y35157D01*
X1593697Y34990D01*
X1594030Y34865D01*
X1594864D01*
G01X1590347D02*
Y37365D01*
X1591889Y35573D01*
X1589805D01*
G01X1588539Y36948D02*
X1588289Y37198D01*
X1587997Y37323D01*
X1587664Y37365D01*
X1587247Y37282D01*
X1586955Y37073D01*
X1586872Y36823D01*
X1586914Y36573D01*
X1587080Y36365D01*
X1587914Y35948D01*
X1588289Y35657D01*
X1588539Y35240D01*
X1588622Y34865D01*
X1586872D01*
G01X1597533Y54150D02*
Y56650D01*
X1596492D01*
X1596158Y56525D01*
X1595950Y56358D01*
X1595867Y56025D01*
X1595950Y55692D01*
X1596200Y55483D01*
X1596492Y55358D01*
X1597533D01*
G01X1596492D02*
X1595867Y54150D01*
G01X1593600D02*
X1593308Y54192D01*
X1592975Y54317D01*
X1592767Y54525D01*
X1592683Y54817D01*
X1592767Y55108D01*
X1593017Y55358D01*
X1593392Y55483D01*
X1593808D01*
X1594058Y55567D01*
X1594267Y55775D01*
X1594350Y56067D01*
X1594225Y56358D01*
X1593933Y56567D01*
X1593600Y56650D01*
X1593267Y56567D01*
X1592975Y56358D01*
X1592850Y56067D01*
X1592933Y55775D01*
X1593142Y55567D01*
X1593392Y55483D01*
X1593808D01*
X1594183Y55358D01*
X1594433Y55108D01*
X1594517Y54817D01*
X1594433Y54525D01*
X1594225Y54317D01*
X1593892Y54192D01*
X1593600Y54150D01*
G01X1591292D02*
Y56650D01*
X1589708D01*
G01X1590292Y55442D02*
X1591292D01*
G01X1588192Y56233D02*
X1587942Y56483D01*
X1587650Y56608D01*
X1587317Y56650D01*
X1586900Y56567D01*
X1586608Y56358D01*
X1586525Y56108D01*
X1586567Y55858D01*
X1586733Y55650D01*
X1587567Y55233D01*
X1587942Y54942D01*
X1588192Y54525D01*
X1588275Y54150D01*
X1586525D01*
G01X1583800D02*
Y56650D01*
X1585342Y54858D01*
X1583258D01*
G01X1568619Y83776D02*
X1571119D01*
Y84817D01*
X1570994Y85151D01*
X1570827Y85359D01*
X1570494Y85442D01*
X1570161Y85359D01*
X1569952Y85109D01*
X1569827Y84817D01*
Y83776D01*
G01Y84817D02*
X1568619Y85442D01*
G01Y87709D02*
X1571119D01*
X1570619Y87209D01*
G01X1568619D02*
Y88209D01*
G01X1571119Y89892D02*
X1569327D01*
X1568952Y90059D01*
X1568702Y90392D01*
X1568619Y90809D01*
X1568702Y91226D01*
X1568952Y91559D01*
X1569327Y91726D01*
X1571119D01*
G01X1568619Y94409D02*
X1571119D01*
X1569327Y92867D01*
Y94951D01*
G01X1568619Y96926D02*
X1569161Y97009D01*
X1569619Y97134D01*
X1570036Y97301D01*
X1570494Y97509D01*
X1571119Y97842D01*
Y96176D01*
G01X1575340Y80299D02*
Y82799D01*
X1574299D01*
X1573965Y82674D01*
X1573757Y82507D01*
X1573674Y82174D01*
X1573757Y81841D01*
X1574007Y81632D01*
X1574299Y81507D01*
X1575340D01*
G01X1574299D02*
X1573674Y80299D01*
G01X1572324Y80799D02*
X1572074Y80507D01*
X1571740Y80341D01*
X1571365Y80299D01*
X1571032Y80341D01*
X1570699Y80549D01*
X1570490Y80799D01*
X1570449Y81049D01*
X1570532Y81341D01*
X1570824Y81549D01*
X1571115Y81632D01*
X1571490D01*
G01X1571115D02*
X1570865Y81757D01*
X1570657Y81966D01*
X1570574Y82216D01*
X1570657Y82466D01*
X1570865Y82674D01*
X1571240Y82799D01*
X1571615Y82757D01*
X1571990Y82591D01*
G01X1569099Y82382D02*
X1568849Y82632D01*
X1568557Y82757D01*
X1568224Y82799D01*
X1567807Y82716D01*
X1567515Y82507D01*
X1567432Y82257D01*
X1567474Y82007D01*
X1567640Y81799D01*
X1568474Y81382D01*
X1568849Y81091D01*
X1569099Y80674D01*
X1569182Y80299D01*
X1567432D01*
G01X1566457Y82799D02*
X1565874Y80299D01*
X1565207Y82799D01*
X1564540Y80299D01*
X1563957Y82799D01*
G01X1563024Y80799D02*
X1562774Y80507D01*
X1562440Y80341D01*
X1562065Y80299D01*
X1561732Y80341D01*
X1561399Y80549D01*
X1561190Y80799D01*
X1561149Y81049D01*
X1561232Y81341D01*
X1561524Y81549D01*
X1561815Y81632D01*
X1562190D01*
G01X1561815D02*
X1561565Y81757D01*
X1561357Y81966D01*
X1561274Y82216D01*
X1561357Y82466D01*
X1561565Y82674D01*
X1561940Y82799D01*
X1562315Y82757D01*
X1562690Y82591D01*
G01X1575091Y76817D02*
Y79317D01*
X1574050D01*
X1573716Y79192D01*
X1573508Y79025D01*
X1573425Y78692D01*
X1573508Y78359D01*
X1573758Y78150D01*
X1574050Y78025D01*
X1575091D01*
G01X1574050D02*
X1573425Y76817D01*
G01X1572075Y77317D02*
X1571825Y77025D01*
X1571491Y76859D01*
X1571116Y76817D01*
X1570783Y76859D01*
X1570450Y77067D01*
X1570241Y77317D01*
X1570200Y77567D01*
X1570283Y77859D01*
X1570575Y78067D01*
X1570866Y78150D01*
X1571241D01*
G01X1570866D02*
X1570616Y78275D01*
X1570408Y78484D01*
X1570325Y78734D01*
X1570408Y78984D01*
X1570616Y79192D01*
X1570991Y79317D01*
X1571366Y79275D01*
X1571741Y79109D01*
G01X1568850Y78900D02*
X1568600Y79150D01*
X1568308Y79275D01*
X1567975Y79317D01*
X1567558Y79234D01*
X1567266Y79025D01*
X1567183Y78775D01*
X1567225Y78525D01*
X1567391Y78317D01*
X1568225Y77900D01*
X1568600Y77609D01*
X1568850Y77192D01*
X1568933Y76817D01*
X1567183D01*
G01X1566208Y79317D02*
X1565625Y76817D01*
X1564958Y79317D01*
X1564291Y76817D01*
X1563708Y79317D01*
G01X1561358Y76817D02*
Y79317D01*
X1562900Y77525D01*
X1560816D01*
G01X1565235Y72587D02*
Y75087D01*
X1564194D01*
X1563860Y74962D01*
X1563652Y74795D01*
X1563569Y74462D01*
X1563652Y74129D01*
X1563902Y73920D01*
X1564194Y73795D01*
X1565235D01*
G01X1564194D02*
X1563569Y72587D01*
G01X1562219Y73087D02*
X1561969Y72795D01*
X1561635Y72629D01*
X1561260Y72587D01*
X1560927Y72629D01*
X1560594Y72837D01*
X1560385Y73087D01*
X1560344Y73337D01*
X1560427Y73629D01*
X1560719Y73837D01*
X1561010Y73920D01*
X1561385D01*
G01X1561010D02*
X1560760Y74045D01*
X1560552Y74254D01*
X1560469Y74504D01*
X1560552Y74754D01*
X1560760Y74962D01*
X1561135Y75087D01*
X1561510Y75045D01*
X1561885Y74879D01*
G01X1558994Y74670D02*
X1558744Y74920D01*
X1558452Y75045D01*
X1558119Y75087D01*
X1557702Y75004D01*
X1557410Y74795D01*
X1557327Y74545D01*
X1557369Y74295D01*
X1557535Y74087D01*
X1558369Y73670D01*
X1558744Y73379D01*
X1558994Y72962D01*
X1559077Y72587D01*
X1557327D01*
G01X1556352Y75087D02*
X1555769Y72587D01*
X1555102Y75087D01*
X1554435Y72587D01*
X1553852Y75087D01*
G01X1552002Y72587D02*
Y75087D01*
X1552502Y74587D01*
G01Y72587D02*
X1551502D01*
G01X1541411Y83217D02*
X1543911D01*
Y84258D01*
X1543786Y84592D01*
X1543619Y84800D01*
X1543286Y84883D01*
X1542953Y84800D01*
X1542744Y84550D01*
X1542619Y84258D01*
Y83217D01*
G01Y84258D02*
X1541411Y84883D01*
G01X1541911Y86233D02*
X1541619Y86483D01*
X1541453Y86817D01*
X1541411Y87192D01*
X1541453Y87525D01*
X1541661Y87858D01*
X1541911Y88067D01*
X1542161Y88108D01*
X1542453Y88025D01*
X1542661Y87733D01*
X1542744Y87442D01*
Y87067D01*
G01Y87442D02*
X1542869Y87692D01*
X1543078Y87900D01*
X1543328Y87983D01*
X1543578Y87900D01*
X1543786Y87692D01*
X1543911Y87317D01*
X1543869Y86942D01*
X1543703Y86567D01*
G01X1543494Y89458D02*
X1543744Y89708D01*
X1543869Y90000D01*
X1543911Y90333D01*
X1543828Y90750D01*
X1543619Y91042D01*
X1543369Y91125D01*
X1543119Y91083D01*
X1542911Y90917D01*
X1542494Y90083D01*
X1542203Y89708D01*
X1541786Y89458D01*
X1541411Y89375D01*
Y91125D01*
G01X1543911Y92100D02*
X1541411Y92683D01*
X1543911Y93350D01*
X1541411Y94017D01*
X1543911Y94600D01*
G01X1543494Y95658D02*
X1543744Y95908D01*
X1543869Y96200D01*
X1543911Y96533D01*
X1543828Y96950D01*
X1543619Y97242D01*
X1543369Y97325D01*
X1543119Y97283D01*
X1542911Y97117D01*
X1542494Y96283D01*
X1542203Y95908D01*
X1541786Y95658D01*
X1541411Y95575D01*
Y97325D01*
G01X1570082Y58104D02*
X1572582D01*
Y59145D01*
X1572457Y59479D01*
X1572290Y59687D01*
X1571957Y59770D01*
X1571624Y59687D01*
X1571415Y59437D01*
X1571290Y59145D01*
Y58104D01*
G01Y59145D02*
X1570082Y59770D01*
G01X1570582Y61120D02*
X1570290Y61370D01*
X1570124Y61704D01*
X1570082Y62079D01*
X1570124Y62412D01*
X1570332Y62745D01*
X1570582Y62954D01*
X1570832Y62995D01*
X1571124Y62912D01*
X1571332Y62620D01*
X1571415Y62329D01*
Y61954D01*
G01Y62329D02*
X1571540Y62579D01*
X1571749Y62787D01*
X1571999Y62870D01*
X1572249Y62787D01*
X1572457Y62579D01*
X1572582Y62204D01*
X1572540Y61829D01*
X1572374Y61454D01*
G01X1572165Y64345D02*
X1572415Y64595D01*
X1572540Y64887D01*
X1572582Y65220D01*
X1572499Y65637D01*
X1572290Y65929D01*
X1572040Y66012D01*
X1571790Y65970D01*
X1571582Y65804D01*
X1571165Y64970D01*
X1570874Y64595D01*
X1570457Y64345D01*
X1570082Y64262D01*
Y66012D01*
G01X1572582Y66987D02*
X1570082Y67570D01*
X1572582Y68237D01*
X1570082Y68904D01*
X1572582Y69487D01*
G01X1570457Y70420D02*
X1570249Y70670D01*
X1570124Y70962D01*
X1570082Y71337D01*
X1570165Y71712D01*
X1570332Y72004D01*
X1570624Y72212D01*
X1570957Y72254D01*
X1571290Y72170D01*
X1571499Y71962D01*
X1571665Y71670D01*
X1571707Y71379D01*
X1571665Y71087D01*
X1571499Y70712D01*
X1572582Y70837D01*
Y71962D01*
G01X1566563Y58121D02*
X1569063D01*
Y59162D01*
X1568938Y59496D01*
X1568771Y59704D01*
X1568438Y59787D01*
X1568105Y59704D01*
X1567896Y59454D01*
X1567771Y59162D01*
Y58121D01*
G01Y59162D02*
X1566563Y59787D01*
G01X1567063Y61137D02*
X1566771Y61387D01*
X1566605Y61721D01*
X1566563Y62096D01*
X1566605Y62429D01*
X1566813Y62762D01*
X1567063Y62971D01*
X1567313Y63012D01*
X1567605Y62929D01*
X1567813Y62637D01*
X1567896Y62346D01*
Y61971D01*
G01Y62346D02*
X1568021Y62596D01*
X1568230Y62804D01*
X1568480Y62887D01*
X1568730Y62804D01*
X1568938Y62596D01*
X1569063Y62221D01*
X1569021Y61846D01*
X1568855Y61471D01*
G01X1568646Y64362D02*
X1568896Y64612D01*
X1569021Y64904D01*
X1569063Y65237D01*
X1568980Y65654D01*
X1568771Y65946D01*
X1568521Y66029D01*
X1568271Y65987D01*
X1568063Y65821D01*
X1567646Y64987D01*
X1567355Y64612D01*
X1566938Y64362D01*
X1566563Y64279D01*
Y66029D01*
G01X1569063Y67004D02*
X1566563Y67587D01*
X1569063Y68254D01*
X1566563Y68921D01*
X1569063Y69504D01*
G01X1567605Y70562D02*
X1567896Y70854D01*
X1568063Y71104D01*
X1568146Y71437D01*
X1568063Y71729D01*
X1567896Y71937D01*
X1567646Y72104D01*
X1567355Y72146D01*
X1567105Y72104D01*
X1566855Y71937D01*
X1566646Y71687D01*
X1566563Y71396D01*
X1566646Y71062D01*
X1566896Y70771D01*
X1567271Y70604D01*
X1567688Y70562D01*
X1568230Y70646D01*
X1568521Y70771D01*
X1568813Y70979D01*
X1569021Y71271D01*
X1569063Y71562D01*
X1568980Y71854D01*
X1568771Y72062D01*
G01X1594582Y39650D02*
Y42150D01*
X1593541D01*
X1593207Y42025D01*
X1592999Y41858D01*
X1592916Y41525D01*
X1592999Y41192D01*
X1593249Y40983D01*
X1593541Y40858D01*
X1594582D01*
G01X1593541D02*
X1592916Y39650D01*
G01X1590649D02*
X1590357Y39692D01*
X1590024Y39817D01*
X1589816Y40025D01*
X1589732Y40317D01*
X1589816Y40608D01*
X1590066Y40858D01*
X1590441Y40983D01*
X1590857D01*
X1591107Y41067D01*
X1591316Y41275D01*
X1591399Y41567D01*
X1591274Y41858D01*
X1590982Y42067D01*
X1590649Y42150D01*
X1590316Y42067D01*
X1590024Y41858D01*
X1589899Y41567D01*
X1589982Y41275D01*
X1590191Y41067D01*
X1590441Y40983D01*
X1590857D01*
X1591232Y40858D01*
X1591482Y40608D01*
X1591566Y40317D01*
X1591482Y40025D01*
X1591274Y39817D01*
X1590941Y39692D01*
X1590649Y39650D01*
G01X1586716D02*
X1588382D01*
Y42150D01*
X1586716D01*
G01X1587382Y40942D02*
X1588382D01*
G01X1585366Y40150D02*
X1585116Y39858D01*
X1584782Y39692D01*
X1584407Y39650D01*
X1584074Y39692D01*
X1583741Y39900D01*
X1583532Y40150D01*
X1583491Y40400D01*
X1583574Y40692D01*
X1583866Y40900D01*
X1584157Y40983D01*
X1584532D01*
G01X1584157D02*
X1583907Y41108D01*
X1583699Y41317D01*
X1583616Y41567D01*
X1583699Y41817D01*
X1583907Y42025D01*
X1584282Y42150D01*
X1584657Y42108D01*
X1585032Y41942D01*
G01X1582141Y41733D02*
X1581891Y41983D01*
X1581599Y42108D01*
X1581266Y42150D01*
X1580849Y42067D01*
X1580557Y41858D01*
X1580474Y41608D01*
X1580516Y41358D01*
X1580682Y41150D01*
X1581516Y40733D01*
X1581891Y40442D01*
X1582141Y40025D01*
X1582224Y39650D01*
X1580474D01*
G01X1576267Y68464D02*
X1578767D01*
Y69505D01*
X1578642Y69839D01*
X1578475Y70047D01*
X1578142Y70130D01*
X1577809Y70047D01*
X1577600Y69797D01*
X1577475Y69505D01*
Y68464D01*
G01Y69505D02*
X1576267Y70130D01*
G01Y72397D02*
X1578767D01*
X1578267Y71897D01*
G01X1576267D02*
Y72897D01*
G01X1578767Y74580D02*
X1576975D01*
X1576600Y74747D01*
X1576350Y75080D01*
X1576267Y75497D01*
X1576350Y75914D01*
X1576600Y76247D01*
X1576975Y76414D01*
X1578767D01*
G01X1578350Y77805D02*
X1578600Y78055D01*
X1578725Y78347D01*
X1578767Y78680D01*
X1578684Y79097D01*
X1578475Y79389D01*
X1578225Y79472D01*
X1577975Y79430D01*
X1577767Y79264D01*
X1577350Y78430D01*
X1577059Y78055D01*
X1576642Y77805D01*
X1576267Y77722D01*
Y79472D01*
G01X1577309Y80905D02*
X1577600Y81197D01*
X1577767Y81447D01*
X1577850Y81780D01*
X1577767Y82072D01*
X1577600Y82280D01*
X1577350Y82447D01*
X1577059Y82489D01*
X1576809Y82447D01*
X1576559Y82280D01*
X1576350Y82030D01*
X1576267Y81739D01*
X1576350Y81405D01*
X1576600Y81114D01*
X1576975Y80947D01*
X1577392Y80905D01*
X1577934Y80989D01*
X1578225Y81114D01*
X1578517Y81322D01*
X1578725Y81614D01*
X1578767Y81905D01*
X1578684Y82197D01*
X1578475Y82405D01*
G01X1597403Y81110D02*
Y83610D01*
X1596362D01*
X1596028Y83485D01*
X1595820Y83318D01*
X1595737Y82985D01*
X1595820Y82652D01*
X1596070Y82443D01*
X1596362Y82318D01*
X1597403D01*
G01X1596362D02*
X1595737Y81110D01*
G01X1593470D02*
Y83610D01*
X1593970Y83110D01*
G01Y81110D02*
X1592970D01*
G01X1591287Y83610D02*
Y81818D01*
X1591120Y81443D01*
X1590787Y81193D01*
X1590370Y81110D01*
X1589953Y81193D01*
X1589620Y81443D01*
X1589453Y81818D01*
Y83610D01*
G01X1588062Y83193D02*
X1587812Y83443D01*
X1587520Y83568D01*
X1587187Y83610D01*
X1586770Y83527D01*
X1586478Y83318D01*
X1586395Y83068D01*
X1586437Y82818D01*
X1586603Y82610D01*
X1587437Y82193D01*
X1587812Y81902D01*
X1588062Y81485D01*
X1588145Y81110D01*
X1586395D01*
G01X1584253D02*
X1584170Y81652D01*
X1584045Y82110D01*
X1583878Y82527D01*
X1583670Y82985D01*
X1583337Y83610D01*
X1585003D01*
G01X1597907Y87877D02*
X1598157Y88002D01*
X1598449Y88085D01*
X1598782D01*
X1599157Y87960D01*
X1599449Y87752D01*
X1599657Y87502D01*
X1599824Y87085D01*
X1599866Y86710D01*
X1599782Y86335D01*
X1599657Y86085D01*
X1599407Y85835D01*
X1599116Y85668D01*
X1598824Y85585D01*
X1598532D01*
X1598241Y85668D01*
X1597991Y85793D01*
X1597782Y85960D01*
G01X1596516Y87668D02*
X1596266Y87918D01*
X1595974Y88043D01*
X1595641Y88085D01*
X1595224Y88002D01*
X1594932Y87793D01*
X1594849Y87543D01*
X1594891Y87293D01*
X1595057Y87085D01*
X1595891Y86668D01*
X1596266Y86377D01*
X1596516Y85960D01*
X1596599Y85585D01*
X1594849D01*
G01X1593541Y85960D02*
X1593291Y85752D01*
X1592999Y85627D01*
X1592624Y85585D01*
X1592249Y85668D01*
X1591957Y85835D01*
X1591749Y86127D01*
X1591707Y86460D01*
X1591791Y86793D01*
X1591999Y87002D01*
X1592291Y87168D01*
X1592582Y87210D01*
X1592874Y87168D01*
X1593249Y87002D01*
X1593124Y88085D01*
X1591999D01*
G01X1590774D02*
X1590191Y85585D01*
X1589524Y88085D01*
X1588857Y85585D01*
X1588274Y88085D01*
G01X1587216Y86627D02*
X1586924Y86918D01*
X1586674Y87085D01*
X1586341Y87168D01*
X1586049Y87085D01*
X1585841Y86918D01*
X1585674Y86668D01*
X1585632Y86377D01*
X1585674Y86127D01*
X1585841Y85877D01*
X1586091Y85668D01*
X1586382Y85585D01*
X1586716Y85668D01*
X1587007Y85918D01*
X1587174Y86293D01*
X1587216Y86710D01*
X1587132Y87252D01*
X1587007Y87543D01*
X1586799Y87835D01*
X1586507Y88043D01*
X1586216Y88085D01*
X1585924Y88002D01*
X1585716Y87793D01*
G01X1584116Y87668D02*
X1583866Y87918D01*
X1583574Y88043D01*
X1583241Y88085D01*
X1582824Y88002D01*
X1582532Y87793D01*
X1582449Y87543D01*
X1582491Y87293D01*
X1582657Y87085D01*
X1583491Y86668D01*
X1583866Y86377D01*
X1584116Y85960D01*
X1584199Y85585D01*
X1582449D01*
G01X1592332Y45942D02*
X1592582Y46067D01*
X1592874Y46150D01*
X1593207D01*
X1593582Y46025D01*
X1593874Y45817D01*
X1594082Y45567D01*
X1594249Y45150D01*
X1594291Y44775D01*
X1594207Y44400D01*
X1594082Y44150D01*
X1593832Y43900D01*
X1593541Y43733D01*
X1593249Y43650D01*
X1592957D01*
X1592666Y43733D01*
X1592416Y43858D01*
X1592207Y44025D01*
G01X1590941Y45733D02*
X1590691Y45983D01*
X1590399Y46108D01*
X1590066Y46150D01*
X1589649Y46067D01*
X1589357Y45858D01*
X1589274Y45608D01*
X1589316Y45358D01*
X1589482Y45150D01*
X1590316Y44733D01*
X1590691Y44442D01*
X1590941Y44025D01*
X1591024Y43650D01*
X1589274D01*
G01X1587882D02*
Y46150D01*
X1586841D01*
X1586507Y46025D01*
X1586299Y45858D01*
X1586216Y45525D01*
X1586299Y45192D01*
X1586549Y44983D01*
X1586841Y44858D01*
X1587882D01*
G01X1586841D02*
X1586216Y43650D01*
G01X1583949D02*
Y46150D01*
X1584449Y45650D01*
G01Y43650D02*
X1583449D01*
G01X1581641Y45733D02*
X1581391Y45983D01*
X1581099Y46108D01*
X1580766Y46150D01*
X1580349Y46067D01*
X1580057Y45858D01*
X1579974Y45608D01*
X1580016Y45358D01*
X1580182Y45150D01*
X1581016Y44733D01*
X1581391Y44442D01*
X1581641Y44025D01*
X1581724Y43650D01*
X1579974D01*
G01X1581492Y53317D02*
X1581617Y53067D01*
X1581700Y52775D01*
Y52442D01*
X1581575Y52067D01*
X1581367Y51775D01*
X1581117Y51567D01*
X1580700Y51400D01*
X1580325Y51358D01*
X1579950Y51442D01*
X1579700Y51567D01*
X1579450Y51817D01*
X1579283Y52108D01*
X1579200Y52400D01*
Y52692D01*
X1579283Y52983D01*
X1579408Y53233D01*
X1579575Y53442D01*
G01X1581283Y54708D02*
X1581533Y54958D01*
X1581658Y55250D01*
X1581700Y55583D01*
X1581617Y56000D01*
X1581408Y56292D01*
X1581158Y56375D01*
X1580908Y56333D01*
X1580700Y56167D01*
X1580283Y55333D01*
X1579992Y54958D01*
X1579575Y54708D01*
X1579200Y54625D01*
Y56375D01*
G01X1581700Y58600D02*
X1579200D01*
G01X1581700Y57642D02*
Y59558D01*
G01X1579700Y60783D02*
X1579408Y61033D01*
X1579242Y61367D01*
X1579200Y61742D01*
X1579242Y62075D01*
X1579450Y62408D01*
X1579700Y62617D01*
X1579950Y62658D01*
X1580242Y62575D01*
X1580450Y62283D01*
X1580533Y61992D01*
Y61617D01*
G01Y61992D02*
X1580658Y62242D01*
X1580867Y62450D01*
X1581117Y62533D01*
X1581367Y62450D01*
X1581575Y62242D01*
X1581700Y61867D01*
X1581658Y61492D01*
X1581492Y61117D01*
G01X1562081Y40792D02*
X1562206Y40542D01*
X1562289Y40250D01*
Y39917D01*
X1562164Y39542D01*
X1561956Y39250D01*
X1561706Y39042D01*
X1561289Y38875D01*
X1560914Y38833D01*
X1560539Y38917D01*
X1560289Y39042D01*
X1560039Y39292D01*
X1559872Y39583D01*
X1559789Y39875D01*
Y40167D01*
X1559872Y40458D01*
X1559997Y40708D01*
X1560164Y40917D01*
G01X1560289Y42058D02*
X1559997Y42308D01*
X1559831Y42642D01*
X1559789Y43017D01*
X1559831Y43350D01*
X1560039Y43683D01*
X1560289Y43892D01*
X1560539Y43933D01*
X1560831Y43850D01*
X1561039Y43558D01*
X1561122Y43267D01*
Y42892D01*
G01Y43267D02*
X1561247Y43517D01*
X1561456Y43725D01*
X1561706Y43808D01*
X1561956Y43725D01*
X1562164Y43517D01*
X1562289Y43142D01*
X1562247Y42767D01*
X1562081Y42392D01*
G01X1561872Y45283D02*
X1562122Y45533D01*
X1562247Y45825D01*
X1562289Y46158D01*
X1562206Y46575D01*
X1561997Y46867D01*
X1561747Y46950D01*
X1561497Y46908D01*
X1561289Y46742D01*
X1560872Y45908D01*
X1560581Y45533D01*
X1560164Y45283D01*
X1559789Y45200D01*
Y46950D01*
G01X1562289Y47925D02*
X1559789Y48508D01*
X1562289Y49175D01*
X1559789Y49842D01*
X1562289Y50425D01*
G01X1559789Y52275D02*
X1562289D01*
X1561789Y51775D01*
G01X1559789D02*
Y52775D01*
G01X1548241Y87827D02*
X1548366Y87577D01*
X1548449Y87285D01*
Y86952D01*
X1548324Y86577D01*
X1548116Y86285D01*
X1547866Y86077D01*
X1547449Y85910D01*
X1547074Y85868D01*
X1546699Y85952D01*
X1546449Y86077D01*
X1546199Y86327D01*
X1546032Y86618D01*
X1545949Y86910D01*
Y87202D01*
X1546032Y87493D01*
X1546157Y87743D01*
X1546324Y87952D01*
G01X1546449Y89093D02*
X1546157Y89343D01*
X1545991Y89677D01*
X1545949Y90052D01*
X1545991Y90385D01*
X1546199Y90718D01*
X1546449Y90927D01*
X1546699Y90968D01*
X1546991Y90885D01*
X1547199Y90593D01*
X1547282Y90302D01*
Y89927D01*
G01Y90302D02*
X1547407Y90552D01*
X1547616Y90760D01*
X1547866Y90843D01*
X1548116Y90760D01*
X1548324Y90552D01*
X1548449Y90177D01*
X1548407Y89802D01*
X1548241Y89427D01*
G01X1548032Y92318D02*
X1548282Y92568D01*
X1548407Y92860D01*
X1548449Y93193D01*
X1548366Y93610D01*
X1548157Y93902D01*
X1547907Y93985D01*
X1547657Y93943D01*
X1547449Y93777D01*
X1547032Y92943D01*
X1546741Y92568D01*
X1546324Y92318D01*
X1545949Y92235D01*
Y93985D01*
G01X1548449Y94960D02*
X1545949Y95543D01*
X1548449Y96210D01*
X1545949Y96877D01*
X1548449Y97460D01*
G01X1546324Y98393D02*
X1546116Y98643D01*
X1545991Y98935D01*
X1545949Y99310D01*
X1546032Y99685D01*
X1546199Y99977D01*
X1546491Y100185D01*
X1546824Y100227D01*
X1547157Y100143D01*
X1547366Y99935D01*
X1547532Y99643D01*
X1547574Y99352D01*
X1547532Y99060D01*
X1547366Y98685D01*
X1548449Y98810D01*
Y99935D01*
G01X1582506Y70045D02*
X1582631Y69795D01*
X1582714Y69503D01*
Y69170D01*
X1582589Y68795D01*
X1582381Y68503D01*
X1582131Y68295D01*
X1581714Y68128D01*
X1581339Y68086D01*
X1580964Y68170D01*
X1580714Y68295D01*
X1580464Y68545D01*
X1580297Y68836D01*
X1580214Y69128D01*
Y69420D01*
X1580297Y69711D01*
X1580422Y69961D01*
X1580589Y70170D01*
G01X1580506Y71520D02*
X1580297Y71811D01*
X1580214Y72145D01*
X1580297Y72478D01*
X1580547Y72770D01*
X1580922Y72978D01*
X1581297Y73061D01*
X1581756D01*
X1582131Y72978D01*
X1582464Y72770D01*
X1582631Y72520D01*
X1582714Y72228D01*
X1582631Y71895D01*
X1582464Y71645D01*
X1582214Y71478D01*
X1581881Y71395D01*
X1581589Y71478D01*
X1581297Y71686D01*
X1581131Y71936D01*
X1581089Y72228D01*
X1581172Y72561D01*
X1581381Y72811D01*
X1581756Y73061D01*
G01X1581464Y75578D02*
Y76411D01*
X1580714D01*
X1580464Y76161D01*
X1580297Y75870D01*
X1580214Y75453D01*
X1580297Y75036D01*
X1580464Y74745D01*
X1580714Y74495D01*
X1581006Y74328D01*
X1581339Y74245D01*
X1581631D01*
X1581881Y74328D01*
X1582172Y74495D01*
X1582422Y74745D01*
X1582589Y74995D01*
X1582714Y75328D01*
Y75620D01*
X1582631Y75953D01*
X1582464Y76203D01*
G01X1580214Y78428D02*
X1582714D01*
X1582214Y77928D01*
G01X1580214D02*
Y78928D01*
G01Y82028D02*
X1582714D01*
X1580922Y80486D01*
Y82570D01*
G01X1599192Y63617D02*
Y66117D01*
X1597608D01*
G01X1598192Y64909D02*
X1599192D01*
G01X1594967Y64950D02*
X1594800Y65075D01*
X1594675Y65284D01*
X1594592Y65575D01*
X1594675Y65825D01*
X1594842Y65992D01*
X1595133Y66117D01*
X1596258D01*
Y63617D01*
X1594883D01*
X1594592Y63784D01*
X1594425Y64034D01*
X1594342Y64325D01*
X1594425Y64617D01*
X1594675Y64867D01*
X1594967Y64950D01*
X1596258D01*
G01X1592200Y63617D02*
Y66117D01*
X1592700Y65617D01*
G01Y63617D02*
X1591700D01*
G01X1590017Y66117D02*
Y64325D01*
X1589850Y63950D01*
X1589517Y63700D01*
X1589100Y63617D01*
X1588683Y63700D01*
X1588350Y63950D01*
X1588183Y64325D01*
Y66117D01*
G01X1585500Y63617D02*
Y66117D01*
X1587042Y64325D01*
X1584958D01*
G01X1580849Y101488D02*
X1584849D01*
Y94088D01*
G01X1558121Y56578D02*
X1556329D01*
X1555954Y56745D01*
X1555704Y57078D01*
X1555621Y57495D01*
X1555704Y57912D01*
X1555954Y58245D01*
X1556329Y58412D01*
X1558121D01*
G01X1556121Y59678D02*
X1555829Y59928D01*
X1555663Y60262D01*
X1555621Y60637D01*
X1555663Y60970D01*
X1555871Y61303D01*
X1556121Y61512D01*
X1556371Y61553D01*
X1556663Y61470D01*
X1556871Y61178D01*
X1556954Y60887D01*
Y60512D01*
G01Y60887D02*
X1557079Y61137D01*
X1557288Y61345D01*
X1557538Y61428D01*
X1557788Y61345D01*
X1557996Y61137D01*
X1558121Y60762D01*
X1558079Y60387D01*
X1557913Y60012D01*
G01X1557704Y62903D02*
X1557954Y63153D01*
X1558079Y63445D01*
X1558121Y63778D01*
X1558038Y64195D01*
X1557829Y64487D01*
X1557579Y64570D01*
X1557329Y64528D01*
X1557121Y64362D01*
X1556704Y63528D01*
X1556413Y63153D01*
X1555996Y62903D01*
X1555621Y62820D01*
Y64570D01*
G01X1558121Y65545D02*
X1555621Y66128D01*
X1558121Y66795D01*
X1555621Y67462D01*
X1558121Y68045D01*
G01X1555621Y69895D02*
X1558121D01*
X1557621Y69395D01*
G01X1555621D02*
Y70395D01*
G01X1543017Y53626D02*
Y61626D01*
X1554967D01*
Y53626D01*
X1543017D01*
G01X1554967Y59776D02*
X1552967Y57776D01*
X1554967Y55776D01*
G01X1538773Y51258D02*
X1536773Y49258D01*
X1538773Y47258D01*
G01X1567356Y84816D02*
X1564856Y85858D01*
X1567356Y86900D01*
G01X1564856Y88125D02*
X1567356D01*
Y89166D01*
X1567231Y89500D01*
X1567064Y89708D01*
X1566731Y89791D01*
X1566398Y89708D01*
X1566189Y89458D01*
X1566064Y89166D01*
Y88125D01*
G01Y89166D02*
X1564856Y89791D01*
G01X1565356Y91141D02*
X1565064Y91391D01*
X1564898Y91725D01*
X1564856Y92100D01*
X1564898Y92433D01*
X1565106Y92766D01*
X1565356Y92975D01*
X1565606Y93016D01*
X1565898Y92933D01*
X1566106Y92641D01*
X1566189Y92350D01*
Y91975D01*
G01Y92350D02*
X1566314Y92600D01*
X1566523Y92808D01*
X1566773Y92891D01*
X1567023Y92808D01*
X1567231Y92600D01*
X1567356Y92225D01*
X1567314Y91850D01*
X1567148Y91475D01*
G01X1566939Y94366D02*
X1567189Y94616D01*
X1567314Y94908D01*
X1567356Y95241D01*
X1567273Y95658D01*
X1567064Y95950D01*
X1566814Y96033D01*
X1566564Y95991D01*
X1566356Y95825D01*
X1565939Y94991D01*
X1565648Y94616D01*
X1565231Y94366D01*
X1564856Y94283D01*
Y96033D01*
G01X1567356Y97008D02*
X1564856Y97591D01*
X1567356Y98258D01*
X1564856Y98925D01*
X1567356Y99508D01*
G01X1564856Y101358D02*
X1567356D01*
X1566856Y100858D01*
G01X1564856D02*
Y101858D01*
G01X1555500Y83300D02*
Y96700D01*
G01X1557500Y83300D02*
X1555500D01*
G01X1557500Y96700D02*
Y83300D01*
G01X1574700Y115500D02*
X1576500D01*
Y106524D01*
G01X1574700Y115500D02*
X1572700D01*
Y116600D01*
G01Y123400D02*
Y127812D01*
G01X1653104Y130000D02*
Y132911D01*
X1659074D01*
Y148469D01*
X1653306D01*
Y161100D01*
X1621700D01*
Y150400D01*
X1625100D01*
Y139800D01*
X1595100D01*
Y143000D01*
X1590500D01*
Y144600D01*
X1586900D01*
Y154300D01*
X1590700D01*
Y156700D01*
X1593700D01*
Y171500D01*
X1578900D01*
Y141866D01*
G01X1569646Y101014D02*
X1572146D01*
Y102055D01*
X1572021Y102389D01*
X1571854Y102597D01*
X1571521Y102680D01*
X1571188Y102597D01*
X1570979Y102347D01*
X1570854Y102055D01*
Y101014D01*
G01Y102055D02*
X1569646Y102680D01*
G01X1571729Y104155D02*
X1571979Y104405D01*
X1572104Y104697D01*
X1572146Y105030D01*
X1572063Y105447D01*
X1571854Y105739D01*
X1571604Y105822D01*
X1571354Y105780D01*
X1571146Y105614D01*
X1570729Y104780D01*
X1570438Y104405D01*
X1570021Y104155D01*
X1569646Y104072D01*
Y105822D01*
G01X1572146Y108047D02*
X1569646D01*
G01X1572146Y107089D02*
Y109005D01*
G01X1570146Y110230D02*
X1569854Y110480D01*
X1569688Y110814D01*
X1569646Y111189D01*
X1569688Y111522D01*
X1569896Y111855D01*
X1570146Y112064D01*
X1570396Y112105D01*
X1570688Y112022D01*
X1570896Y111730D01*
X1570979Y111439D01*
Y111064D01*
G01Y111439D02*
X1571104Y111689D01*
X1571313Y111897D01*
X1571563Y111980D01*
X1571813Y111897D01*
X1572021Y111689D01*
X1572146Y111314D01*
X1572104Y110939D01*
X1571938Y110564D01*
G01X1569646Y114747D02*
X1572146D01*
X1570354Y113205D01*
Y115289D01*
G01X1550433Y121350D02*
Y123850D01*
X1549392D01*
X1549058Y123725D01*
X1548850Y123558D01*
X1548767Y123225D01*
X1548850Y122892D01*
X1549100Y122683D01*
X1549392Y122558D01*
X1550433D01*
G01X1549392D02*
X1548767Y121350D01*
G01X1546500D02*
X1546208Y121392D01*
X1545875Y121517D01*
X1545667Y121725D01*
X1545583Y122017D01*
X1545667Y122308D01*
X1545917Y122558D01*
X1546292Y122683D01*
X1546708D01*
X1546958Y122767D01*
X1547167Y122975D01*
X1547250Y123267D01*
X1547125Y123558D01*
X1546833Y123767D01*
X1546500Y123850D01*
X1546167Y123767D01*
X1545875Y123558D01*
X1545750Y123267D01*
X1545833Y122975D01*
X1546042Y122767D01*
X1546292Y122683D01*
X1546708D01*
X1547083Y122558D01*
X1547333Y122308D01*
X1547417Y122017D01*
X1547333Y121725D01*
X1547125Y121517D01*
X1546792Y121392D01*
X1546500Y121350D01*
G01X1544192D02*
Y123850D01*
X1542608D01*
G01X1543192Y122642D02*
X1544192D01*
G01X1541092Y123433D02*
X1540842Y123683D01*
X1540550Y123808D01*
X1540217Y123850D01*
X1539800Y123767D01*
X1539508Y123558D01*
X1539425Y123308D01*
X1539467Y123058D01*
X1539633Y122850D01*
X1540467Y122433D01*
X1540842Y122142D01*
X1541092Y121725D01*
X1541175Y121350D01*
X1539425D01*
G01X1537992Y122392D02*
X1537700Y122683D01*
X1537450Y122850D01*
X1537117Y122933D01*
X1536825Y122850D01*
X1536617Y122683D01*
X1536450Y122433D01*
X1536408Y122142D01*
X1536450Y121892D01*
X1536617Y121642D01*
X1536867Y121433D01*
X1537158Y121350D01*
X1537492Y121433D01*
X1537783Y121683D01*
X1537950Y122058D01*
X1537992Y122475D01*
X1537908Y123017D01*
X1537783Y123308D01*
X1537575Y123600D01*
X1537283Y123808D01*
X1536992Y123850D01*
X1536700Y123767D01*
X1536492Y123558D01*
G01X1547633Y124900D02*
Y127400D01*
X1546592D01*
X1546258Y127275D01*
X1546050Y127108D01*
X1545967Y126775D01*
X1546050Y126442D01*
X1546300Y126233D01*
X1546592Y126108D01*
X1547633D01*
G01X1546592D02*
X1545967Y124900D01*
G01X1544492Y126983D02*
X1544242Y127233D01*
X1543950Y127358D01*
X1543617Y127400D01*
X1543200Y127317D01*
X1542908Y127108D01*
X1542825Y126858D01*
X1542867Y126608D01*
X1543033Y126400D01*
X1543867Y125983D01*
X1544242Y125692D01*
X1544492Y125275D01*
X1544575Y124900D01*
X1542825D01*
G01X1540600Y127400D02*
Y124900D01*
G01X1541558Y127400D02*
X1539642D01*
G01X1538292Y126983D02*
X1538042Y127233D01*
X1537750Y127358D01*
X1537417Y127400D01*
X1537000Y127317D01*
X1536708Y127108D01*
X1536625Y126858D01*
X1536667Y126608D01*
X1536833Y126400D01*
X1537667Y125983D01*
X1538042Y125692D01*
X1538292Y125275D01*
X1538375Y124900D01*
X1536625D01*
G01X1535192Y126983D02*
X1534942Y127233D01*
X1534650Y127358D01*
X1534317Y127400D01*
X1533900Y127317D01*
X1533608Y127108D01*
X1533525Y126858D01*
X1533567Y126608D01*
X1533733Y126400D01*
X1534567Y125983D01*
X1534942Y125692D01*
X1535192Y125275D01*
X1535275Y124900D01*
X1533525D01*
G01X1570390Y151123D02*
X1572890D01*
Y152164D01*
X1572765Y152498D01*
X1572598Y152706D01*
X1572265Y152789D01*
X1571932Y152706D01*
X1571723Y152456D01*
X1571598Y152164D01*
Y151123D01*
G01Y152164D02*
X1570390Y152789D01*
G01Y155056D02*
X1570432Y155348D01*
X1570557Y155681D01*
X1570765Y155889D01*
X1571057Y155973D01*
X1571348Y155889D01*
X1571598Y155639D01*
X1571723Y155264D01*
Y154848D01*
X1571807Y154598D01*
X1572015Y154389D01*
X1572307Y154306D01*
X1572598Y154431D01*
X1572807Y154723D01*
X1572890Y155056D01*
X1572807Y155389D01*
X1572598Y155681D01*
X1572307Y155806D01*
X1572015Y155723D01*
X1571807Y155514D01*
X1571723Y155264D01*
Y154848D01*
X1571598Y154473D01*
X1571348Y154223D01*
X1571057Y154139D01*
X1570765Y154223D01*
X1570557Y154431D01*
X1570432Y154764D01*
X1570390Y155056D01*
G01X1571640Y158406D02*
Y159239D01*
X1570890D01*
X1570640Y158989D01*
X1570473Y158698D01*
X1570390Y158281D01*
X1570473Y157864D01*
X1570640Y157573D01*
X1570890Y157323D01*
X1571182Y157156D01*
X1571515Y157073D01*
X1571807D01*
X1572057Y157156D01*
X1572348Y157323D01*
X1572598Y157573D01*
X1572765Y157823D01*
X1572890Y158156D01*
Y158448D01*
X1572807Y158781D01*
X1572640Y159031D01*
G01X1572473Y160464D02*
X1572723Y160714D01*
X1572848Y161006D01*
X1572890Y161339D01*
X1572807Y161756D01*
X1572598Y162048D01*
X1572348Y162131D01*
X1572098Y162089D01*
X1571890Y161923D01*
X1571473Y161089D01*
X1571182Y160714D01*
X1570765Y160464D01*
X1570390Y160381D01*
Y162131D01*
G01X1567156Y145245D02*
X1569656D01*
Y146286D01*
X1569531Y146620D01*
X1569364Y146828D01*
X1569031Y146911D01*
X1568698Y146828D01*
X1568489Y146578D01*
X1568364Y146286D01*
Y145245D01*
G01Y146286D02*
X1567156Y146911D01*
G01X1569239Y148386D02*
X1569489Y148636D01*
X1569614Y148928D01*
X1569656Y149261D01*
X1569573Y149678D01*
X1569364Y149970D01*
X1569114Y150053D01*
X1568864Y150011D01*
X1568656Y149845D01*
X1568239Y149011D01*
X1567948Y148636D01*
X1567531Y148386D01*
X1567156Y148303D01*
Y150053D01*
G01X1569656Y151361D02*
X1567864D01*
X1567489Y151528D01*
X1567239Y151861D01*
X1567156Y152278D01*
X1567239Y152695D01*
X1567489Y153028D01*
X1567864Y153195D01*
X1569656D01*
G01X1569239Y154586D02*
X1569489Y154836D01*
X1569614Y155128D01*
X1569656Y155461D01*
X1569573Y155878D01*
X1569364Y156170D01*
X1569114Y156253D01*
X1568864Y156211D01*
X1568656Y156045D01*
X1568239Y155211D01*
X1567948Y154836D01*
X1567531Y154586D01*
X1567156Y154503D01*
Y156253D01*
G01X1556833Y134587D02*
Y137087D01*
X1555792D01*
X1555458Y136962D01*
X1555250Y136795D01*
X1555167Y136462D01*
X1555250Y136129D01*
X1555500Y135920D01*
X1555792Y135795D01*
X1556833D01*
G01X1555792D02*
X1555167Y134587D01*
G01X1553692Y136670D02*
X1553442Y136920D01*
X1553150Y137045D01*
X1552817Y137087D01*
X1552400Y137004D01*
X1552108Y136795D01*
X1552025Y136545D01*
X1552067Y136295D01*
X1552233Y136087D01*
X1553067Y135670D01*
X1553442Y135379D01*
X1553692Y134962D01*
X1553775Y134587D01*
X1552025D01*
G01X1549800Y137087D02*
Y134587D01*
G01X1550758Y137087D02*
X1548842D01*
G01X1546700Y134587D02*
Y137087D01*
X1547200Y136587D01*
G01Y134587D02*
X1546200D01*
G01X1543600D02*
X1543308Y134629D01*
X1542975Y134754D01*
X1542767Y134962D01*
X1542683Y135254D01*
X1542767Y135545D01*
X1543017Y135795D01*
X1543392Y135920D01*
X1543808D01*
X1544058Y136004D01*
X1544267Y136212D01*
X1544350Y136504D01*
X1544225Y136795D01*
X1543933Y137004D01*
X1543600Y137087D01*
X1543267Y137004D01*
X1542975Y136795D01*
X1542850Y136504D01*
X1542933Y136212D01*
X1543142Y136004D01*
X1543392Y135920D01*
X1543808D01*
X1544183Y135795D01*
X1544433Y135545D01*
X1544517Y135254D01*
X1544433Y134962D01*
X1544225Y134754D01*
X1543892Y134629D01*
X1543600Y134587D01*
G01X1553383Y139400D02*
Y141900D01*
X1552342D01*
X1552008Y141775D01*
X1551800Y141608D01*
X1551717Y141275D01*
X1551800Y140942D01*
X1552050Y140733D01*
X1552342Y140608D01*
X1553383D01*
G01X1552342D02*
X1551717Y139400D01*
G01X1549450D02*
X1549158Y139442D01*
X1548825Y139567D01*
X1548617Y139775D01*
X1548533Y140067D01*
X1548617Y140358D01*
X1548867Y140608D01*
X1549242Y140733D01*
X1549658D01*
X1549908Y140817D01*
X1550117Y141025D01*
X1550200Y141317D01*
X1550075Y141608D01*
X1549783Y141817D01*
X1549450Y141900D01*
X1549117Y141817D01*
X1548825Y141608D01*
X1548700Y141317D01*
X1548783Y141025D01*
X1548992Y140817D01*
X1549242Y140733D01*
X1549658D01*
X1550033Y140608D01*
X1550283Y140358D01*
X1550367Y140067D01*
X1550283Y139775D01*
X1550075Y139567D01*
X1549742Y139442D01*
X1549450Y139400D01*
G01X1547142D02*
Y141900D01*
X1545558D01*
G01X1546142Y140692D02*
X1547142D01*
G01X1544167Y139900D02*
X1543917Y139608D01*
X1543583Y139442D01*
X1543208Y139400D01*
X1542875Y139442D01*
X1542542Y139650D01*
X1542333Y139900D01*
X1542292Y140150D01*
X1542375Y140442D01*
X1542667Y140650D01*
X1542958Y140733D01*
X1543333D01*
G01X1542958D02*
X1542708Y140858D01*
X1542500Y141067D01*
X1542417Y141317D01*
X1542500Y141567D01*
X1542708Y141775D01*
X1543083Y141900D01*
X1543458Y141858D01*
X1543833Y141692D01*
G01X1540942Y140442D02*
X1540650Y140733D01*
X1540400Y140900D01*
X1540067Y140983D01*
X1539775Y140900D01*
X1539567Y140733D01*
X1539400Y140483D01*
X1539358Y140192D01*
X1539400Y139942D01*
X1539567Y139692D01*
X1539817Y139483D01*
X1540108Y139400D01*
X1540442Y139483D01*
X1540733Y139733D01*
X1540900Y140108D01*
X1540942Y140525D01*
X1540858Y141067D01*
X1540733Y141358D01*
X1540525Y141650D01*
X1540233Y141858D01*
X1539942Y141900D01*
X1539650Y141817D01*
X1539442Y141608D01*
G01X1569272Y117918D02*
X1571772D01*
Y118959D01*
X1571647Y119293D01*
X1571480Y119501D01*
X1571147Y119584D01*
X1570814Y119501D01*
X1570605Y119251D01*
X1570480Y118959D01*
Y117918D01*
G01Y118959D02*
X1569272Y119584D01*
G01X1571355Y121059D02*
X1571605Y121309D01*
X1571730Y121601D01*
X1571772Y121934D01*
X1571689Y122351D01*
X1571480Y122643D01*
X1571230Y122726D01*
X1570980Y122684D01*
X1570772Y122518D01*
X1570355Y121684D01*
X1570064Y121309D01*
X1569647Y121059D01*
X1569272Y120976D01*
Y122726D01*
G01X1571772Y124951D02*
X1569272D01*
G01X1571772Y123993D02*
Y125909D01*
G01X1571355Y127259D02*
X1571605Y127509D01*
X1571730Y127801D01*
X1571772Y128134D01*
X1571689Y128551D01*
X1571480Y128843D01*
X1571230Y128926D01*
X1570980Y128884D01*
X1570772Y128718D01*
X1570355Y127884D01*
X1570064Y127509D01*
X1569647Y127259D01*
X1569272Y127176D01*
Y128926D01*
G01Y131151D02*
X1569314Y131443D01*
X1569439Y131776D01*
X1569647Y131984D01*
X1569939Y132068D01*
X1570230Y131984D01*
X1570480Y131734D01*
X1570605Y131359D01*
Y130943D01*
X1570689Y130693D01*
X1570897Y130484D01*
X1571189Y130401D01*
X1571480Y130526D01*
X1571689Y130818D01*
X1571772Y131151D01*
X1571689Y131484D01*
X1571480Y131776D01*
X1571189Y131901D01*
X1570897Y131818D01*
X1570689Y131609D01*
X1570605Y131359D01*
Y130943D01*
X1570480Y130568D01*
X1570230Y130318D01*
X1569939Y130234D01*
X1569647Y130318D01*
X1569439Y130526D01*
X1569314Y130859D01*
X1569272Y131151D01*
G01X1549233Y128550D02*
Y131050D01*
X1548192D01*
X1547858Y130925D01*
X1547650Y130758D01*
X1547567Y130425D01*
X1547650Y130092D01*
X1547900Y129883D01*
X1548192Y129758D01*
X1549233D01*
G01X1548192D02*
X1547567Y128550D01*
G01X1546092Y130633D02*
X1545842Y130883D01*
X1545550Y131008D01*
X1545217Y131050D01*
X1544800Y130967D01*
X1544508Y130758D01*
X1544425Y130508D01*
X1544467Y130258D01*
X1544633Y130050D01*
X1545467Y129633D01*
X1545842Y129342D01*
X1546092Y128925D01*
X1546175Y128550D01*
X1544425D01*
G01X1543117Y128925D02*
X1542867Y128717D01*
X1542575Y128592D01*
X1542200Y128550D01*
X1541825Y128633D01*
X1541533Y128800D01*
X1541325Y129092D01*
X1541283Y129425D01*
X1541367Y129758D01*
X1541575Y129967D01*
X1541867Y130133D01*
X1542158Y130175D01*
X1542450Y130133D01*
X1542825Y129967D01*
X1542700Y131050D01*
X1541575D01*
G01X1540350D02*
X1539767Y128550D01*
X1539100Y131050D01*
X1538433Y128550D01*
X1537850Y131050D01*
G01X1536000Y128550D02*
Y131050D01*
X1536500Y130550D01*
G01Y128550D02*
X1535500D01*
G01X1532900D02*
X1532608Y128592D01*
X1532275Y128717D01*
X1532067Y128925D01*
X1531983Y129217D01*
X1532067Y129508D01*
X1532317Y129758D01*
X1532692Y129883D01*
X1533108D01*
X1533358Y129967D01*
X1533567Y130175D01*
X1533650Y130467D01*
X1533525Y130758D01*
X1533233Y130967D01*
X1532900Y131050D01*
X1532567Y130967D01*
X1532275Y130758D01*
X1532150Y130467D01*
X1532233Y130175D01*
X1532442Y129967D01*
X1532692Y129883D01*
X1533108D01*
X1533483Y129758D01*
X1533733Y129508D01*
X1533817Y129217D01*
X1533733Y128925D01*
X1533525Y128717D01*
X1533192Y128592D01*
X1532900Y128550D01*
G01X1529800D02*
Y131050D01*
X1530300Y130550D01*
G01Y128550D02*
X1529300D01*
G01X1570205Y133963D02*
X1572705D01*
Y135004D01*
X1572580Y135338D01*
X1572413Y135546D01*
X1572080Y135629D01*
X1571747Y135546D01*
X1571538Y135296D01*
X1571413Y135004D01*
Y133963D01*
G01Y135004D02*
X1570205Y135629D01*
G01X1572288Y137104D02*
X1572538Y137354D01*
X1572663Y137646D01*
X1572705Y137979D01*
X1572622Y138396D01*
X1572413Y138688D01*
X1572163Y138771D01*
X1571913Y138729D01*
X1571705Y138563D01*
X1571288Y137729D01*
X1570997Y137354D01*
X1570580Y137104D01*
X1570205Y137021D01*
Y138771D01*
G01X1572705Y140996D02*
X1570205D01*
G01X1572705Y140038D02*
Y141954D01*
G01X1570705Y143179D02*
X1570413Y143429D01*
X1570247Y143763D01*
X1570205Y144138D01*
X1570247Y144471D01*
X1570455Y144804D01*
X1570705Y145013D01*
X1570955Y145054D01*
X1571247Y144971D01*
X1571455Y144679D01*
X1571538Y144388D01*
Y144013D01*
G01Y144388D02*
X1571663Y144638D01*
X1571872Y144846D01*
X1572122Y144929D01*
X1572372Y144846D01*
X1572580Y144638D01*
X1572705Y144263D01*
X1572663Y143888D01*
X1572497Y143513D01*
G01X1570580Y146279D02*
X1570372Y146529D01*
X1570247Y146821D01*
X1570205Y147196D01*
X1570288Y147571D01*
X1570455Y147863D01*
X1570747Y148071D01*
X1571080Y148113D01*
X1571413Y148029D01*
X1571622Y147821D01*
X1571788Y147529D01*
X1571830Y147238D01*
X1571788Y146946D01*
X1571622Y146571D01*
X1572705Y146696D01*
Y147821D01*
G01X1574574Y144340D02*
X1577074D01*
Y145381D01*
X1576949Y145715D01*
X1576782Y145923D01*
X1576449Y146006D01*
X1576116Y145923D01*
X1575907Y145673D01*
X1575782Y145381D01*
Y144340D01*
G01Y145381D02*
X1574574Y146006D01*
G01X1576657Y147481D02*
X1576907Y147731D01*
X1577032Y148023D01*
X1577074Y148356D01*
X1576991Y148773D01*
X1576782Y149065D01*
X1576532Y149148D01*
X1576282Y149106D01*
X1576074Y148940D01*
X1575657Y148106D01*
X1575366Y147731D01*
X1574949Y147481D01*
X1574574Y147398D01*
Y149148D01*
G01X1574949Y150456D02*
X1574741Y150706D01*
X1574616Y150998D01*
X1574574Y151373D01*
X1574657Y151748D01*
X1574824Y152040D01*
X1575116Y152248D01*
X1575449Y152290D01*
X1575782Y152206D01*
X1575991Y151998D01*
X1576157Y151706D01*
X1576199Y151415D01*
X1576157Y151123D01*
X1575991Y150748D01*
X1577074Y150873D01*
Y151998D01*
G01Y153223D02*
X1574574Y153806D01*
X1577074Y154473D01*
X1574574Y155140D01*
X1577074Y155723D01*
G01X1574866Y156865D02*
X1574657Y157156D01*
X1574574Y157490D01*
X1574657Y157823D01*
X1574907Y158115D01*
X1575282Y158323D01*
X1575657Y158406D01*
X1576116D01*
X1576491Y158323D01*
X1576824Y158115D01*
X1576991Y157865D01*
X1577074Y157573D01*
X1576991Y157240D01*
X1576824Y156990D01*
X1576574Y156823D01*
X1576241Y156740D01*
X1575949Y156823D01*
X1575657Y157031D01*
X1575491Y157281D01*
X1575449Y157573D01*
X1575532Y157906D01*
X1575741Y158156D01*
X1576116Y158406D01*
G01X1575074Y159756D02*
X1574782Y160006D01*
X1574616Y160340D01*
X1574574Y160715D01*
X1574616Y161048D01*
X1574824Y161381D01*
X1575074Y161590D01*
X1575324Y161631D01*
X1575616Y161548D01*
X1575824Y161256D01*
X1575907Y160965D01*
Y160590D01*
G01Y160965D02*
X1576032Y161215D01*
X1576241Y161423D01*
X1576491Y161506D01*
X1576741Y161423D01*
X1576949Y161215D01*
X1577074Y160840D01*
X1577032Y160465D01*
X1576866Y160090D01*
G01X1542183Y106192D02*
X1542433Y106317D01*
X1542725Y106400D01*
X1543058D01*
X1543433Y106275D01*
X1543725Y106067D01*
X1543933Y105817D01*
X1544100Y105400D01*
X1544142Y105025D01*
X1544058Y104650D01*
X1543933Y104400D01*
X1543683Y104150D01*
X1543392Y103983D01*
X1543100Y103900D01*
X1542808D01*
X1542517Y103983D01*
X1542267Y104108D01*
X1542058Y104275D01*
G01X1540792Y105983D02*
X1540542Y106233D01*
X1540250Y106358D01*
X1539917Y106400D01*
X1539500Y106317D01*
X1539208Y106108D01*
X1539125Y105858D01*
X1539167Y105608D01*
X1539333Y105400D01*
X1540167Y104983D01*
X1540542Y104692D01*
X1540792Y104275D01*
X1540875Y103900D01*
X1539125D01*
G01X1536900Y106400D02*
Y103900D01*
G01X1537858Y106400D02*
X1535942D01*
G01X1534717Y104400D02*
X1534467Y104108D01*
X1534133Y103942D01*
X1533758Y103900D01*
X1533425Y103942D01*
X1533092Y104150D01*
X1532883Y104400D01*
X1532842Y104650D01*
X1532925Y104942D01*
X1533217Y105150D01*
X1533508Y105233D01*
X1533883D01*
G01X1533508D02*
X1533258Y105358D01*
X1533050Y105567D01*
X1532967Y105817D01*
X1533050Y106067D01*
X1533258Y106275D01*
X1533633Y106400D01*
X1534008Y106358D01*
X1534383Y106192D01*
G01X1531617Y104275D02*
X1531367Y104067D01*
X1531075Y103942D01*
X1530700Y103900D01*
X1530325Y103983D01*
X1530033Y104150D01*
X1529825Y104442D01*
X1529783Y104775D01*
X1529867Y105108D01*
X1530075Y105317D01*
X1530367Y105483D01*
X1530658Y105525D01*
X1530950Y105483D01*
X1531325Y105317D01*
X1531200Y106400D01*
X1530075D01*
G01X1583849Y110488D02*
X1587849D01*
Y103088D01*
G01X1549260Y142900D02*
Y156300D01*
G01X1560660Y142900D02*
X1549260D01*
G01X1560660Y156300D02*
Y142900D01*
G01X1551067Y120000D02*
Y118208D01*
X1550900Y117833D01*
X1550567Y117583D01*
X1550150Y117500D01*
X1549733Y117583D01*
X1549400Y117833D01*
X1549233Y118208D01*
Y120000D01*
G01X1547050Y117500D02*
X1546758Y117542D01*
X1546425Y117667D01*
X1546217Y117875D01*
X1546133Y118167D01*
X1546217Y118458D01*
X1546467Y118708D01*
X1546842Y118833D01*
X1547258D01*
X1547508Y118917D01*
X1547717Y119125D01*
X1547800Y119417D01*
X1547675Y119708D01*
X1547383Y119917D01*
X1547050Y120000D01*
X1546717Y119917D01*
X1546425Y119708D01*
X1546300Y119417D01*
X1546383Y119125D01*
X1546592Y118917D01*
X1546842Y118833D01*
X1547258D01*
X1547633Y118708D01*
X1547883Y118458D01*
X1547967Y118167D01*
X1547883Y117875D01*
X1547675Y117667D01*
X1547342Y117542D01*
X1547050Y117500D01*
G01X1544742D02*
Y120000D01*
X1543158D01*
G01X1543742Y118792D02*
X1544742D01*
G01X1541767Y118000D02*
X1541517Y117708D01*
X1541183Y117542D01*
X1540808Y117500D01*
X1540475Y117542D01*
X1540142Y117750D01*
X1539933Y118000D01*
X1539892Y118250D01*
X1539975Y118542D01*
X1540267Y118750D01*
X1540558Y118833D01*
X1540933D01*
G01X1540558D02*
X1540308Y118958D01*
X1540100Y119167D01*
X1540017Y119417D01*
X1540100Y119667D01*
X1540308Y119875D01*
X1540683Y120000D01*
X1541058Y119958D01*
X1541433Y119792D01*
G01X1564900Y115640D02*
Y104240D01*
G01X1551500Y115640D02*
X1564900D01*
G01X1551500Y104240D02*
Y115640D01*
G01X1564900Y104240D02*
X1551500D01*
G01X1555500Y96700D02*
X1557500D01*
G01X1594664Y177783D02*
X1594357Y177525D01*
X1594012Y177370D01*
X1593706D01*
X1593399Y177525D01*
X1593169Y177783D01*
X1593054Y178145D01*
X1593131Y178507D01*
X1593322Y178817D01*
X1593667Y179023D01*
X1594127Y179127D01*
X1594396Y179333D01*
X1594511Y179695D01*
X1594434Y180057D01*
X1594242Y180315D01*
X1593974Y180470D01*
X1593706D01*
X1593437Y180367D01*
X1593207Y180108D01*
G01X1589992Y177370D02*
X1591526D01*
Y180470D01*
X1589992D01*
G01X1590606Y178972D02*
X1591526D01*
G01X1586816Y180212D02*
X1587046Y180367D01*
X1587314Y180470D01*
X1587621D01*
X1587966Y180315D01*
X1588234Y180057D01*
X1588426Y179747D01*
X1588579Y179230D01*
X1588617Y178765D01*
X1588541Y178300D01*
X1588426Y177990D01*
X1588196Y177680D01*
X1587927Y177473D01*
X1587659Y177370D01*
X1587391D01*
X1587122Y177473D01*
X1586892Y177628D01*
X1586701Y177835D01*
G01X1584559Y177370D02*
X1584866Y177422D01*
X1585134Y177628D01*
X1585364Y177938D01*
X1585517Y178300D01*
X1585594Y178713D01*
Y179127D01*
X1585517Y179540D01*
X1585364Y179902D01*
X1585134Y180212D01*
X1584866Y180418D01*
X1584559Y180470D01*
X1584252Y180418D01*
X1583984Y180212D01*
X1583754Y179902D01*
X1583601Y179540D01*
X1583524Y179127D01*
Y178713D01*
X1583601Y178300D01*
X1583754Y177938D01*
X1583984Y177628D01*
X1584252Y177422D01*
X1584559Y177370D01*
G01X1582341D02*
Y180470D01*
X1580577Y177370D01*
Y180470D01*
G01X1579202Y177370D02*
Y180470D01*
X1578436D01*
X1578129Y180315D01*
X1577899Y180108D01*
X1577707Y179798D01*
X1577554Y179437D01*
X1577516Y178920D01*
X1577554Y178403D01*
X1577707Y178042D01*
X1577899Y177732D01*
X1578129Y177525D01*
X1578436Y177370D01*
X1579202D01*
G01X1576217D02*
X1575259Y180470D01*
X1574301Y177370D01*
G01X1574646Y178455D02*
X1575872D01*
G01X1572926Y177370D02*
Y180470D01*
X1571967D01*
X1571661Y180315D01*
X1571469Y180108D01*
X1571392Y179695D01*
X1571469Y179282D01*
X1571699Y179023D01*
X1571967Y178868D01*
X1572926D01*
G01X1571967D02*
X1571392Y177370D01*
G01X1569059D02*
Y178765D01*
X1569826Y180470D01*
G01X1568292D02*
X1569059Y178765D01*
G01X1562552Y179023D02*
X1562399Y179178D01*
X1562284Y179437D01*
X1562207Y179798D01*
X1562284Y180108D01*
X1562437Y180315D01*
X1562706Y180470D01*
X1563741D01*
Y177370D01*
X1562476D01*
X1562207Y177577D01*
X1562054Y177887D01*
X1561977Y178248D01*
X1562054Y178610D01*
X1562284Y178920D01*
X1562552Y179023D01*
X1563741D01*
G01X1560219Y180470D02*
X1559299D01*
G01X1559759D02*
Y177370D01*
G01X1560219D02*
X1559299D01*
G01X1556659D02*
X1556966Y177422D01*
X1557234Y177628D01*
X1557464Y177938D01*
X1557617Y178300D01*
X1557694Y178713D01*
Y179127D01*
X1557617Y179540D01*
X1557464Y179902D01*
X1557234Y180212D01*
X1556966Y180418D01*
X1556659Y180470D01*
X1556352Y180418D01*
X1556084Y180212D01*
X1555854Y179902D01*
X1555701Y179540D01*
X1555624Y179127D01*
Y178713D01*
X1555701Y178300D01*
X1555854Y177938D01*
X1556084Y177628D01*
X1556352Y177422D01*
X1556659Y177370D01*
G01X1554364Y177783D02*
X1554057Y177525D01*
X1553712Y177370D01*
X1553406D01*
X1553099Y177525D01*
X1552869Y177783D01*
X1552754Y178145D01*
X1552831Y178507D01*
X1553022Y178817D01*
X1553367Y179023D01*
X1553827Y179127D01*
X1554096Y179333D01*
X1554211Y179695D01*
X1554134Y180057D01*
X1553942Y180315D01*
X1553674Y180470D01*
X1553406D01*
X1553137Y180367D01*
X1552907Y180108D01*
G01X1577267Y193317D02*
X1579767D01*
Y194358D01*
X1579642Y194692D01*
X1579475Y194900D01*
X1579142Y194983D01*
X1578809Y194900D01*
X1578600Y194650D01*
X1578475Y194358D01*
Y193317D01*
G01Y194358D02*
X1577267Y194983D01*
G01X1577767Y196333D02*
X1577475Y196583D01*
X1577309Y196917D01*
X1577267Y197292D01*
X1577309Y197625D01*
X1577517Y197958D01*
X1577767Y198167D01*
X1578017Y198208D01*
X1578309Y198125D01*
X1578517Y197833D01*
X1578600Y197542D01*
Y197167D01*
G01Y197542D02*
X1578725Y197792D01*
X1578934Y198000D01*
X1579184Y198083D01*
X1579434Y198000D01*
X1579642Y197792D01*
X1579767Y197417D01*
X1579725Y197042D01*
X1579559Y196667D01*
G01X1579767Y200350D02*
X1577267D01*
G01X1579767Y199392D02*
Y201308D01*
G01X1577767Y202533D02*
X1577475Y202783D01*
X1577309Y203117D01*
X1577267Y203492D01*
X1577309Y203825D01*
X1577517Y204158D01*
X1577767Y204367D01*
X1578017Y204408D01*
X1578309Y204325D01*
X1578517Y204033D01*
X1578600Y203742D01*
Y203367D01*
G01Y203742D02*
X1578725Y203992D01*
X1578934Y204200D01*
X1579184Y204283D01*
X1579434Y204200D01*
X1579642Y203992D01*
X1579767Y203617D01*
X1579725Y203242D01*
X1579559Y202867D01*
G01X1585363Y215938D02*
X1587863D01*
Y216979D01*
X1587738Y217313D01*
X1587571Y217521D01*
X1587238Y217604D01*
X1586905Y217521D01*
X1586696Y217271D01*
X1586571Y216979D01*
Y215938D01*
G01Y216979D02*
X1585363Y217604D01*
G01X1585863Y218954D02*
X1585571Y219204D01*
X1585405Y219538D01*
X1585363Y219913D01*
X1585405Y220246D01*
X1585613Y220579D01*
X1585863Y220788D01*
X1586113Y220829D01*
X1586405Y220746D01*
X1586613Y220454D01*
X1586696Y220163D01*
Y219788D01*
G01Y220163D02*
X1586821Y220413D01*
X1587030Y220621D01*
X1587280Y220704D01*
X1587530Y220621D01*
X1587738Y220413D01*
X1587863Y220038D01*
X1587821Y219663D01*
X1587655Y219288D01*
G01X1587863Y222971D02*
X1585363D01*
G01X1587863Y222013D02*
Y223929D01*
G01X1585363Y226571D02*
X1587863D01*
X1586071Y225029D01*
Y227113D01*
G01X1589083Y186366D02*
Y188866D01*
X1588042D01*
X1587708Y188741D01*
X1587500Y188574D01*
X1587417Y188241D01*
X1587500Y187908D01*
X1587750Y187699D01*
X1588042Y187574D01*
X1589083D01*
G01X1588042D02*
X1587417Y186366D01*
G01X1586067Y186866D02*
X1585817Y186574D01*
X1585483Y186408D01*
X1585108Y186366D01*
X1584775Y186408D01*
X1584442Y186616D01*
X1584233Y186866D01*
X1584192Y187116D01*
X1584275Y187408D01*
X1584567Y187616D01*
X1584858Y187699D01*
X1585233D01*
G01X1584858D02*
X1584608Y187824D01*
X1584400Y188033D01*
X1584317Y188283D01*
X1584400Y188533D01*
X1584608Y188741D01*
X1584983Y188866D01*
X1585358Y188824D01*
X1585733Y188658D01*
G01X1582050Y188866D02*
Y186366D01*
G01X1583008Y188866D02*
X1581092D01*
G01X1579867Y186741D02*
X1579617Y186533D01*
X1579325Y186408D01*
X1578950Y186366D01*
X1578575Y186449D01*
X1578283Y186616D01*
X1578075Y186908D01*
X1578033Y187241D01*
X1578117Y187574D01*
X1578325Y187783D01*
X1578617Y187949D01*
X1578908Y187991D01*
X1579200Y187949D01*
X1579575Y187783D01*
X1579450Y188866D01*
X1578325D01*
G01X1550980Y165186D02*
X1551313Y165228D01*
X1551605Y165394D01*
X1551855Y165644D01*
X1552022Y165936D01*
X1552105Y166269D01*
Y166603D01*
X1552022Y166936D01*
X1551855Y167228D01*
X1551605Y167478D01*
X1551313Y167644D01*
X1550980Y167686D01*
X1550647Y167644D01*
X1550355Y167478D01*
X1550105Y167228D01*
X1549938Y166936D01*
X1549855Y166603D01*
Y166269D01*
X1549938Y165936D01*
X1550105Y165644D01*
X1550355Y165394D01*
X1550647Y165228D01*
X1550980Y165186D01*
G01X1550647Y165853D02*
X1550147Y165186D01*
G01X1547963D02*
X1547880Y165728D01*
X1547755Y166186D01*
X1547588Y166603D01*
X1547380Y167061D01*
X1547047Y167686D01*
X1548713D01*
G01X1543947Y165186D02*
X1545613D01*
Y167686D01*
X1543947D01*
G01X1544613Y166478D02*
X1545613D01*
G01X1542597Y165686D02*
X1542347Y165394D01*
X1542013Y165228D01*
X1541638Y165186D01*
X1541305Y165228D01*
X1540972Y165436D01*
X1540763Y165686D01*
X1540722Y165936D01*
X1540805Y166228D01*
X1541097Y166436D01*
X1541388Y166519D01*
X1541763D01*
G01X1541388D02*
X1541138Y166644D01*
X1540930Y166853D01*
X1540847Y167103D01*
X1540930Y167353D01*
X1541138Y167561D01*
X1541513Y167686D01*
X1541888Y167644D01*
X1542263Y167478D01*
G01X1587787Y202742D02*
X1587912Y202492D01*
X1587995Y202200D01*
Y201867D01*
X1587870Y201492D01*
X1587662Y201200D01*
X1587412Y200992D01*
X1586995Y200825D01*
X1586620Y200783D01*
X1586245Y200867D01*
X1585995Y200992D01*
X1585745Y201242D01*
X1585578Y201533D01*
X1585495Y201825D01*
Y202117D01*
X1585578Y202408D01*
X1585703Y202658D01*
X1585870Y202867D01*
G01X1585995Y204008D02*
X1585703Y204258D01*
X1585537Y204592D01*
X1585495Y204967D01*
X1585537Y205300D01*
X1585745Y205633D01*
X1585995Y205842D01*
X1586245Y205883D01*
X1586537Y205800D01*
X1586745Y205508D01*
X1586828Y205217D01*
Y204842D01*
G01Y205217D02*
X1586953Y205467D01*
X1587162Y205675D01*
X1587412Y205758D01*
X1587662Y205675D01*
X1587870Y205467D01*
X1587995Y205092D01*
X1587953Y204717D01*
X1587787Y204342D01*
G01X1587995Y208025D02*
X1585495D01*
G01X1587995Y207067D02*
Y208983D01*
G01X1585870Y210208D02*
X1585662Y210458D01*
X1585537Y210750D01*
X1585495Y211125D01*
X1585578Y211500D01*
X1585745Y211792D01*
X1586037Y212000D01*
X1586370Y212042D01*
X1586703Y211958D01*
X1586912Y211750D01*
X1587078Y211458D01*
X1587120Y211167D01*
X1587078Y210875D01*
X1586912Y210500D01*
X1587995Y210625D01*
Y211750D01*
G01X1591437Y202722D02*
X1591562Y202472D01*
X1591645Y202180D01*
Y201847D01*
X1591520Y201472D01*
X1591312Y201180D01*
X1591062Y200972D01*
X1590645Y200805D01*
X1590270Y200763D01*
X1589895Y200847D01*
X1589645Y200972D01*
X1589395Y201222D01*
X1589228Y201513D01*
X1589145Y201805D01*
Y202097D01*
X1589228Y202388D01*
X1589353Y202638D01*
X1589520Y202847D01*
G01X1589645Y203988D02*
X1589353Y204238D01*
X1589187Y204572D01*
X1589145Y204947D01*
X1589187Y205280D01*
X1589395Y205613D01*
X1589645Y205822D01*
X1589895Y205863D01*
X1590187Y205780D01*
X1590395Y205488D01*
X1590478Y205197D01*
Y204822D01*
G01Y205197D02*
X1590603Y205447D01*
X1590812Y205655D01*
X1591062Y205738D01*
X1591312Y205655D01*
X1591520Y205447D01*
X1591645Y205072D01*
X1591603Y204697D01*
X1591437Y204322D01*
G01X1591645Y208005D02*
X1589145D01*
G01X1591645Y207047D02*
Y208963D01*
G01X1589145Y211605D02*
X1591645D01*
X1589853Y210063D01*
Y212147D01*
G01X1543967Y160012D02*
X1544217Y160137D01*
X1544509Y160220D01*
X1544842D01*
X1545217Y160095D01*
X1545509Y159887D01*
X1545717Y159637D01*
X1545884Y159220D01*
X1545926Y158845D01*
X1545842Y158470D01*
X1545717Y158220D01*
X1545467Y157970D01*
X1545176Y157803D01*
X1544884Y157720D01*
X1544592D01*
X1544301Y157803D01*
X1544051Y157928D01*
X1543842Y158095D01*
G01X1542576Y159803D02*
X1542326Y160053D01*
X1542034Y160178D01*
X1541701Y160220D01*
X1541284Y160137D01*
X1540992Y159928D01*
X1540909Y159678D01*
X1540951Y159428D01*
X1541117Y159220D01*
X1541951Y158803D01*
X1542326Y158512D01*
X1542576Y158095D01*
X1542659Y157720D01*
X1540909D01*
G01X1538684Y160220D02*
Y157720D01*
G01X1539642Y160220D02*
X1537726D01*
G01X1536376Y159803D02*
X1536126Y160053D01*
X1535834Y160178D01*
X1535501Y160220D01*
X1535084Y160137D01*
X1534792Y159928D01*
X1534709Y159678D01*
X1534751Y159428D01*
X1534917Y159220D01*
X1535751Y158803D01*
X1536126Y158512D01*
X1536376Y158095D01*
X1536459Y157720D01*
X1534709D01*
G01X1561424Y184720D02*
Y225420D01*
G01X1536024Y184720D02*
X1561424D01*
G01X1536024Y225420D02*
Y184720D01*
G01X1562996Y161742D02*
Y159950D01*
X1562829Y159575D01*
X1562496Y159325D01*
X1562079Y159242D01*
X1561662Y159325D01*
X1561329Y159575D01*
X1561162Y159950D01*
Y161742D01*
G01X1558979Y159242D02*
X1558687Y159284D01*
X1558354Y159409D01*
X1558146Y159617D01*
X1558062Y159909D01*
X1558146Y160200D01*
X1558396Y160450D01*
X1558771Y160575D01*
X1559187D01*
X1559437Y160659D01*
X1559646Y160867D01*
X1559729Y161159D01*
X1559604Y161450D01*
X1559312Y161659D01*
X1558979Y161742D01*
X1558646Y161659D01*
X1558354Y161450D01*
X1558229Y161159D01*
X1558312Y160867D01*
X1558521Y160659D01*
X1558771Y160575D01*
X1559187D01*
X1559562Y160450D01*
X1559812Y160200D01*
X1559896Y159909D01*
X1559812Y159617D01*
X1559604Y159409D01*
X1559271Y159284D01*
X1558979Y159242D01*
G01X1555629Y160492D02*
X1554796D01*
Y159742D01*
X1555046Y159492D01*
X1555337Y159325D01*
X1555754Y159242D01*
X1556171Y159325D01*
X1556462Y159492D01*
X1556712Y159742D01*
X1556879Y160034D01*
X1556962Y160367D01*
Y160659D01*
X1556879Y160909D01*
X1556712Y161200D01*
X1556462Y161450D01*
X1556212Y161617D01*
X1555879Y161742D01*
X1555587D01*
X1555254Y161659D01*
X1555004Y161492D01*
G01X1552779Y159242D02*
Y161742D01*
X1553279Y161242D01*
G01Y159242D02*
X1552279D01*
G01X1549260Y156300D02*
X1560660D01*
G01X1586974Y278766D02*
X1589474D01*
Y279807D01*
X1589349Y280141D01*
X1589182Y280349D01*
X1588849Y280432D01*
X1588516Y280349D01*
X1588307Y280099D01*
X1588182Y279807D01*
Y278766D01*
G01Y279807D02*
X1586974Y280432D01*
G01X1589057Y281907D02*
X1589307Y282157D01*
X1589432Y282449D01*
X1589474Y282782D01*
X1589391Y283199D01*
X1589182Y283491D01*
X1588932Y283574D01*
X1588682Y283532D01*
X1588474Y283366D01*
X1588057Y282532D01*
X1587766Y282157D01*
X1587349Y281907D01*
X1586974Y281824D01*
Y283574D01*
G01X1589474Y285799D02*
X1586974D01*
G01X1589474Y284841D02*
Y286757D01*
G01X1587349Y287982D02*
X1587141Y288232D01*
X1587016Y288524D01*
X1586974Y288899D01*
X1587057Y289274D01*
X1587224Y289566D01*
X1587516Y289774D01*
X1587849Y289816D01*
X1588182Y289732D01*
X1588391Y289524D01*
X1588557Y289232D01*
X1588599Y288941D01*
X1588557Y288649D01*
X1588391Y288274D01*
X1589474Y288399D01*
Y289524D01*
G01X1587474Y291082D02*
X1587182Y291332D01*
X1587016Y291666D01*
X1586974Y292041D01*
X1587016Y292374D01*
X1587224Y292707D01*
X1587474Y292916D01*
X1587724Y292957D01*
X1588016Y292874D01*
X1588224Y292582D01*
X1588307Y292291D01*
Y291916D01*
G01Y292291D02*
X1588432Y292541D01*
X1588641Y292749D01*
X1588891Y292832D01*
X1589141Y292749D01*
X1589349Y292541D01*
X1589474Y292166D01*
X1589432Y291791D01*
X1589266Y291416D01*
G01X1568114Y272929D02*
Y275429D01*
X1567073D01*
X1566739Y275304D01*
X1566531Y275137D01*
X1566448Y274804D01*
X1566531Y274471D01*
X1566781Y274262D01*
X1567073Y274137D01*
X1568114D01*
G01X1567073D02*
X1566448Y272929D01*
G01X1564973Y275012D02*
X1564723Y275262D01*
X1564431Y275387D01*
X1564098Y275429D01*
X1563681Y275346D01*
X1563389Y275137D01*
X1563306Y274887D01*
X1563348Y274637D01*
X1563514Y274429D01*
X1564348Y274012D01*
X1564723Y273721D01*
X1564973Y273304D01*
X1565056Y272929D01*
X1563306D01*
G01X1561081Y275429D02*
Y272929D01*
G01X1562039Y275429D02*
X1560123D01*
G01X1558689Y273221D02*
X1558398Y273012D01*
X1558064Y272929D01*
X1557731Y273012D01*
X1557439Y273262D01*
X1557231Y273637D01*
X1557148Y274012D01*
Y274471D01*
X1557231Y274846D01*
X1557439Y275179D01*
X1557689Y275346D01*
X1557981Y275429D01*
X1558314Y275346D01*
X1558564Y275179D01*
X1558731Y274929D01*
X1558814Y274596D01*
X1558731Y274304D01*
X1558523Y274012D01*
X1558273Y273846D01*
X1557981Y273804D01*
X1557648Y273887D01*
X1557398Y274096D01*
X1557148Y274471D01*
G01X1568114Y276929D02*
Y279429D01*
X1567073D01*
X1566739Y279304D01*
X1566531Y279137D01*
X1566448Y278804D01*
X1566531Y278471D01*
X1566781Y278262D01*
X1567073Y278137D01*
X1568114D01*
G01X1567073D02*
X1566448Y276929D01*
G01X1564973Y279012D02*
X1564723Y279262D01*
X1564431Y279387D01*
X1564098Y279429D01*
X1563681Y279346D01*
X1563389Y279137D01*
X1563306Y278887D01*
X1563348Y278637D01*
X1563514Y278429D01*
X1564348Y278012D01*
X1564723Y277721D01*
X1564973Y277304D01*
X1565056Y276929D01*
X1563306D01*
G01X1561081Y279429D02*
Y276929D01*
G01X1562039Y279429D02*
X1560123D01*
G01X1557981Y276929D02*
Y279429D01*
X1558481Y278929D01*
G01Y276929D02*
X1557481D01*
G01X1555798Y277429D02*
X1555548Y277137D01*
X1555214Y276971D01*
X1554839Y276929D01*
X1554506Y276971D01*
X1554173Y277179D01*
X1553964Y277429D01*
X1553923Y277679D01*
X1554006Y277971D01*
X1554298Y278179D01*
X1554589Y278262D01*
X1554964D01*
G01X1554589D02*
X1554339Y278387D01*
X1554131Y278596D01*
X1554048Y278846D01*
X1554131Y279096D01*
X1554339Y279304D01*
X1554714Y279429D01*
X1555089Y279387D01*
X1555464Y279221D01*
G01X1554019Y238190D02*
Y240690D01*
X1552978D01*
X1552644Y240565D01*
X1552436Y240398D01*
X1552353Y240065D01*
X1552436Y239732D01*
X1552686Y239523D01*
X1552978Y239398D01*
X1554019D01*
G01X1552978D02*
X1552353Y238190D01*
G01X1550878Y240273D02*
X1550628Y240523D01*
X1550336Y240648D01*
X1550003Y240690D01*
X1549586Y240607D01*
X1549294Y240398D01*
X1549211Y240148D01*
X1549253Y239898D01*
X1549419Y239690D01*
X1550253Y239273D01*
X1550628Y238982D01*
X1550878Y238565D01*
X1550961Y238190D01*
X1549211D01*
G01X1546986Y240690D02*
Y238190D01*
G01X1547944Y240690D02*
X1546028D01*
G01X1543886Y238190D02*
Y240690D01*
X1544386Y240190D01*
G01Y238190D02*
X1543386D01*
G01X1540786D02*
Y240690D01*
X1541286Y240190D01*
G01Y238190D02*
X1540286D01*
G01X1581893Y221453D02*
X1584393D01*
Y222494D01*
X1584268Y222828D01*
X1584101Y223036D01*
X1583768Y223119D01*
X1583435Y223036D01*
X1583226Y222786D01*
X1583101Y222494D01*
Y221453D01*
G01Y222494D02*
X1581893Y223119D01*
G01X1582393Y224469D02*
X1582101Y224719D01*
X1581935Y225053D01*
X1581893Y225428D01*
X1581935Y225761D01*
X1582143Y226094D01*
X1582393Y226303D01*
X1582643Y226344D01*
X1582935Y226261D01*
X1583143Y225969D01*
X1583226Y225678D01*
Y225303D01*
G01Y225678D02*
X1583351Y225928D01*
X1583560Y226136D01*
X1583810Y226219D01*
X1584060Y226136D01*
X1584268Y225928D01*
X1584393Y225553D01*
X1584351Y225178D01*
X1584185Y224803D01*
G01X1584393Y228486D02*
X1581893D01*
G01X1584393Y227528D02*
Y229444D01*
G01X1581893Y231586D02*
X1584393D01*
X1583893Y231086D01*
G01X1581893D02*
Y232086D01*
G01X1549949Y228327D02*
Y230827D01*
X1548908D01*
X1548574Y230702D01*
X1548366Y230535D01*
X1548283Y230202D01*
X1548366Y229869D01*
X1548616Y229660D01*
X1548908Y229535D01*
X1549949D01*
G01X1548908D02*
X1548283Y228327D01*
G01X1546016D02*
X1545724Y228369D01*
X1545391Y228494D01*
X1545183Y228702D01*
X1545099Y228994D01*
X1545183Y229285D01*
X1545433Y229535D01*
X1545808Y229660D01*
X1546224D01*
X1546474Y229744D01*
X1546683Y229952D01*
X1546766Y230244D01*
X1546641Y230535D01*
X1546349Y230744D01*
X1546016Y230827D01*
X1545683Y230744D01*
X1545391Y230535D01*
X1545266Y230244D01*
X1545349Y229952D01*
X1545558Y229744D01*
X1545808Y229660D01*
X1546224D01*
X1546599Y229535D01*
X1546849Y229285D01*
X1546933Y228994D01*
X1546849Y228702D01*
X1546641Y228494D01*
X1546308Y228369D01*
X1546016Y228327D01*
G01X1543708D02*
Y230827D01*
X1542124D01*
G01X1542708Y229619D02*
X1543708D01*
G01X1539899Y228327D02*
X1539816Y228869D01*
X1539691Y229327D01*
X1539524Y229744D01*
X1539316Y230202D01*
X1538983Y230827D01*
X1540649D01*
G01X1542027Y232281D02*
Y234781D01*
X1540986D01*
X1540652Y234656D01*
X1540444Y234489D01*
X1540361Y234156D01*
X1540444Y233823D01*
X1540694Y233614D01*
X1540986Y233489D01*
X1542027D01*
G01X1540986D02*
X1540361Y232281D01*
G01X1539011Y232781D02*
X1538761Y232489D01*
X1538427Y232323D01*
X1538052Y232281D01*
X1537719Y232323D01*
X1537386Y232531D01*
X1537177Y232781D01*
X1537136Y233031D01*
X1537219Y233323D01*
X1537511Y233531D01*
X1537802Y233614D01*
X1538177D01*
G01X1537802D02*
X1537552Y233739D01*
X1537344Y233948D01*
X1537261Y234198D01*
X1537344Y234448D01*
X1537552Y234656D01*
X1537927Y234781D01*
X1538302Y234739D01*
X1538677Y234573D01*
G01X1534994Y234781D02*
Y232281D01*
G01X1535952Y234781D02*
X1534036D01*
G01X1531894Y232281D02*
Y234781D01*
X1532394Y234281D01*
G01Y232281D02*
X1531394D01*
G01X1528794Y234781D02*
X1529127Y234698D01*
X1529377Y234489D01*
X1529544Y234239D01*
X1529669Y233906D01*
X1529711Y233531D01*
X1529669Y233156D01*
X1529544Y232823D01*
X1529377Y232573D01*
X1529127Y232364D01*
X1528794Y232281D01*
X1528461Y232364D01*
X1528211Y232573D01*
X1528044Y232823D01*
X1527919Y233156D01*
X1527877Y233531D01*
X1527919Y233906D01*
X1528044Y234239D01*
X1528211Y234489D01*
X1528461Y234698D01*
X1528794Y234781D01*
G01X1586574Y243468D02*
Y245968D01*
X1585533D01*
X1585199Y245843D01*
X1584991Y245676D01*
X1584908Y245343D01*
X1584991Y245010D01*
X1585241Y244801D01*
X1585533Y244676D01*
X1586574D01*
G01X1585533D02*
X1584908Y243468D01*
G01X1582641D02*
Y245968D01*
X1583141Y245468D01*
G01Y243468D02*
X1582141D01*
G01X1580791Y245968D02*
X1580208Y243468D01*
X1579541Y245968D01*
X1578874Y243468D01*
X1578291Y245968D01*
G01X1577233Y245551D02*
X1576983Y245801D01*
X1576691Y245926D01*
X1576358Y245968D01*
X1575941Y245885D01*
X1575649Y245676D01*
X1575566Y245426D01*
X1575608Y245176D01*
X1575774Y244968D01*
X1576608Y244551D01*
X1576983Y244260D01*
X1577233Y243843D01*
X1577316Y243468D01*
X1575566D01*
G01X1574049Y243760D02*
X1573758Y243551D01*
X1573424Y243468D01*
X1573091Y243551D01*
X1572799Y243801D01*
X1572591Y244176D01*
X1572508Y244551D01*
Y245010D01*
X1572591Y245385D01*
X1572799Y245718D01*
X1573049Y245885D01*
X1573341Y245968D01*
X1573674Y245885D01*
X1573924Y245718D01*
X1574091Y245468D01*
X1574174Y245135D01*
X1574091Y244843D01*
X1573883Y244551D01*
X1573633Y244385D01*
X1573341Y244343D01*
X1573008Y244426D01*
X1572758Y244635D01*
X1572508Y245010D01*
G01X1537646Y267815D02*
X1535854D01*
X1535479Y267982D01*
X1535229Y268315D01*
X1535146Y268732D01*
X1535229Y269149D01*
X1535479Y269482D01*
X1535854Y269649D01*
X1537646D01*
G01X1537229Y271040D02*
X1537479Y271290D01*
X1537604Y271582D01*
X1537646Y271915D01*
X1537563Y272332D01*
X1537354Y272624D01*
X1537104Y272707D01*
X1536854Y272665D01*
X1536646Y272499D01*
X1536229Y271665D01*
X1535938Y271290D01*
X1535521Y271040D01*
X1535146Y270957D01*
Y272707D01*
G01X1537646Y274932D02*
X1535146D01*
G01X1537646Y273974D02*
Y275890D01*
G01X1537229Y277240D02*
X1537479Y277490D01*
X1537604Y277782D01*
X1537646Y278115D01*
X1537563Y278532D01*
X1537354Y278824D01*
X1537104Y278907D01*
X1536854Y278865D01*
X1536646Y278699D01*
X1536229Y277865D01*
X1535938Y277490D01*
X1535521Y277240D01*
X1535146Y277157D01*
Y278907D01*
G01X1560333Y244486D02*
Y242694D01*
X1560166Y242319D01*
X1559833Y242069D01*
X1559416Y241986D01*
X1558999Y242069D01*
X1558666Y242319D01*
X1558499Y242694D01*
Y244486D01*
G01X1557108Y244069D02*
X1556858Y244319D01*
X1556566Y244444D01*
X1556233Y244486D01*
X1555816Y244403D01*
X1555524Y244194D01*
X1555441Y243944D01*
X1555483Y243694D01*
X1555649Y243486D01*
X1556483Y243069D01*
X1556858Y242778D01*
X1557108Y242361D01*
X1557191Y241986D01*
X1555441D01*
G01X1553216Y244486D02*
Y241986D01*
G01X1554174Y244486D02*
X1552258D01*
G01X1551033Y242486D02*
X1550783Y242194D01*
X1550449Y242028D01*
X1550074Y241986D01*
X1549741Y242028D01*
X1549408Y242236D01*
X1549199Y242486D01*
X1549158Y242736D01*
X1549241Y243028D01*
X1549533Y243236D01*
X1549824Y243319D01*
X1550199D01*
G01X1549824D02*
X1549574Y243444D01*
X1549366Y243653D01*
X1549283Y243903D01*
X1549366Y244153D01*
X1549574Y244361D01*
X1549949Y244486D01*
X1550324Y244444D01*
X1550699Y244278D01*
G01X1570364Y267421D02*
X1570614Y267546D01*
X1570906Y267629D01*
X1571239D01*
X1571614Y267504D01*
X1571906Y267296D01*
X1572114Y267046D01*
X1572281Y266629D01*
X1572323Y266254D01*
X1572239Y265879D01*
X1572114Y265629D01*
X1571864Y265379D01*
X1571573Y265212D01*
X1571281Y265129D01*
X1570989D01*
X1570698Y265212D01*
X1570448Y265337D01*
X1570239Y265504D01*
G01X1568973Y267212D02*
X1568723Y267462D01*
X1568431Y267587D01*
X1568098Y267629D01*
X1567681Y267546D01*
X1567389Y267337D01*
X1567306Y267087D01*
X1567348Y266837D01*
X1567514Y266629D01*
X1568348Y266212D01*
X1568723Y265921D01*
X1568973Y265504D01*
X1569056Y265129D01*
X1567306D01*
G01X1565081Y267629D02*
Y265129D01*
G01X1566039Y267629D02*
X1564123D01*
G01X1561981Y265129D02*
Y267629D01*
X1562481Y267129D01*
G01Y265129D02*
X1561481D01*
G01X1559673Y267212D02*
X1559423Y267462D01*
X1559131Y267587D01*
X1558798Y267629D01*
X1558381Y267546D01*
X1558089Y267337D01*
X1558006Y267087D01*
X1558048Y266837D01*
X1558214Y266629D01*
X1559048Y266212D01*
X1559423Y265921D01*
X1559673Y265504D01*
X1559756Y265129D01*
X1558006D01*
G01X1566364Y271221D02*
X1566614Y271346D01*
X1566906Y271429D01*
X1567239D01*
X1567614Y271304D01*
X1567906Y271096D01*
X1568114Y270846D01*
X1568281Y270429D01*
X1568323Y270054D01*
X1568239Y269679D01*
X1568114Y269429D01*
X1567864Y269179D01*
X1567573Y269012D01*
X1567281Y268929D01*
X1566989D01*
X1566698Y269012D01*
X1566448Y269137D01*
X1566239Y269304D01*
G01X1564973Y271012D02*
X1564723Y271262D01*
X1564431Y271387D01*
X1564098Y271429D01*
X1563681Y271346D01*
X1563389Y271137D01*
X1563306Y270887D01*
X1563348Y270637D01*
X1563514Y270429D01*
X1564348Y270012D01*
X1564723Y269721D01*
X1564973Y269304D01*
X1565056Y268929D01*
X1563306D01*
G01X1561081Y271429D02*
Y268929D01*
G01X1562039Y271429D02*
X1560123D01*
G01X1557981Y268929D02*
X1557689Y268971D01*
X1557356Y269096D01*
X1557148Y269304D01*
X1557064Y269596D01*
X1557148Y269887D01*
X1557398Y270137D01*
X1557773Y270262D01*
X1558189D01*
X1558439Y270346D01*
X1558648Y270554D01*
X1558731Y270846D01*
X1558606Y271137D01*
X1558314Y271346D01*
X1557981Y271429D01*
X1557648Y271346D01*
X1557356Y271137D01*
X1557231Y270846D01*
X1557314Y270554D01*
X1557523Y270346D01*
X1557773Y270262D01*
X1558189D01*
X1558564Y270137D01*
X1558814Y269887D01*
X1558898Y269596D01*
X1558814Y269304D01*
X1558606Y269096D01*
X1558273Y268971D01*
X1557981Y268929D01*
G01X1567972Y228934D02*
Y227142D01*
X1567805Y226767D01*
X1567472Y226517D01*
X1567055Y226434D01*
X1566638Y226517D01*
X1566305Y226767D01*
X1566138Y227142D01*
Y228934D01*
G01X1564872Y226934D02*
X1564622Y226642D01*
X1564288Y226476D01*
X1563913Y226434D01*
X1563580Y226476D01*
X1563247Y226684D01*
X1563038Y226934D01*
X1562997Y227184D01*
X1563080Y227476D01*
X1563372Y227684D01*
X1563663Y227767D01*
X1564038D01*
G01X1563663D02*
X1563413Y227892D01*
X1563205Y228101D01*
X1563122Y228351D01*
X1563205Y228601D01*
X1563413Y228809D01*
X1563788Y228934D01*
X1564163Y228892D01*
X1564538Y228726D01*
G01X1560855Y228934D02*
Y226434D01*
G01X1561813Y228934D02*
X1559897D01*
G01X1557755Y226434D02*
Y228934D01*
X1558255Y228434D01*
G01Y226434D02*
X1557255D01*
G01X1548724Y223450D02*
X1550694Y225420D01*
G01X1546754D02*
X1548724Y223450D01*
G01X1561424Y225420D02*
X1536024D01*
G01X1539880Y303997D02*
X1542380D01*
Y305038D01*
X1542255Y305372D01*
X1542088Y305580D01*
X1541755Y305663D01*
X1541422Y305580D01*
X1541213Y305330D01*
X1541088Y305038D01*
Y303997D01*
G01Y305038D02*
X1539880Y305663D01*
G01X1541963Y307138D02*
X1542213Y307388D01*
X1542338Y307680D01*
X1542380Y308013D01*
X1542297Y308430D01*
X1542088Y308722D01*
X1541838Y308805D01*
X1541588Y308763D01*
X1541380Y308597D01*
X1540963Y307763D01*
X1540672Y307388D01*
X1540255Y307138D01*
X1539880Y307055D01*
Y308805D01*
G01X1542380Y310197D02*
X1539880D01*
Y311863D01*
G01X1540922Y313338D02*
X1541213Y313630D01*
X1541380Y313880D01*
X1541463Y314213D01*
X1541380Y314505D01*
X1541213Y314713D01*
X1540963Y314880D01*
X1540672Y314922D01*
X1540422Y314880D01*
X1540172Y314713D01*
X1539963Y314463D01*
X1539880Y314172D01*
X1539963Y313838D01*
X1540213Y313547D01*
X1540588Y313380D01*
X1541005Y313338D01*
X1541547Y313422D01*
X1541838Y313547D01*
X1542130Y313755D01*
X1542338Y314047D01*
X1542380Y314338D01*
X1542297Y314630D01*
X1542088Y314838D01*
G01X1543380Y303997D02*
X1545880D01*
Y305038D01*
X1545755Y305372D01*
X1545588Y305580D01*
X1545255Y305663D01*
X1544922Y305580D01*
X1544713Y305330D01*
X1544588Y305038D01*
Y303997D01*
G01Y305038D02*
X1543380Y305663D01*
G01X1545463Y307138D02*
X1545713Y307388D01*
X1545838Y307680D01*
X1545880Y308013D01*
X1545797Y308430D01*
X1545588Y308722D01*
X1545338Y308805D01*
X1545088Y308763D01*
X1544880Y308597D01*
X1544463Y307763D01*
X1544172Y307388D01*
X1543755Y307138D01*
X1543380Y307055D01*
Y308805D01*
G01X1545880Y310197D02*
X1543380D01*
Y311863D01*
G01X1543755Y313213D02*
X1543547Y313463D01*
X1543422Y313755D01*
X1543380Y314130D01*
X1543463Y314505D01*
X1543630Y314797D01*
X1543922Y315005D01*
X1544255Y315047D01*
X1544588Y314963D01*
X1544797Y314755D01*
X1544963Y314463D01*
X1545005Y314172D01*
X1544963Y313880D01*
X1544797Y313505D01*
X1545880Y313630D01*
Y314755D01*
G01X1597368Y318062D02*
Y320562D01*
X1596327D01*
X1595993Y320437D01*
X1595785Y320270D01*
X1595702Y319937D01*
X1595785Y319604D01*
X1596035Y319395D01*
X1596327Y319270D01*
X1597368D01*
G01X1596327D02*
X1595702Y318062D01*
G01X1594227Y319104D02*
X1593935Y319395D01*
X1593685Y319562D01*
X1593352Y319645D01*
X1593060Y319562D01*
X1592852Y319395D01*
X1592685Y319145D01*
X1592643Y318854D01*
X1592685Y318604D01*
X1592852Y318354D01*
X1593102Y318145D01*
X1593393Y318062D01*
X1593727Y318145D01*
X1594018Y318395D01*
X1594185Y318770D01*
X1594227Y319187D01*
X1594143Y319729D01*
X1594018Y320020D01*
X1593810Y320312D01*
X1593518Y320520D01*
X1593227Y320562D01*
X1592935Y320479D01*
X1592727Y320270D01*
G01X1591585Y320562D02*
X1591002Y318062D01*
X1590335Y320562D01*
X1589668Y318062D01*
X1589085Y320562D01*
G01X1588027Y320145D02*
X1587777Y320395D01*
X1587485Y320520D01*
X1587152Y320562D01*
X1586735Y320479D01*
X1586443Y320270D01*
X1586360Y320020D01*
X1586402Y319770D01*
X1586568Y319562D01*
X1587402Y319145D01*
X1587777Y318854D01*
X1588027Y318437D01*
X1588110Y318062D01*
X1586360D01*
G01X1584135D02*
X1583843Y318104D01*
X1583510Y318229D01*
X1583302Y318437D01*
X1583218Y318729D01*
X1583302Y319020D01*
X1583552Y319270D01*
X1583927Y319395D01*
X1584343D01*
X1584593Y319479D01*
X1584802Y319687D01*
X1584885Y319979D01*
X1584760Y320270D01*
X1584468Y320479D01*
X1584135Y320562D01*
X1583802Y320479D01*
X1583510Y320270D01*
X1583385Y319979D01*
X1583468Y319687D01*
X1583677Y319479D01*
X1583927Y319395D01*
X1584343D01*
X1584718Y319270D01*
X1584968Y319020D01*
X1585052Y318729D01*
X1584968Y318437D01*
X1584760Y318229D01*
X1584427Y318104D01*
X1584135Y318062D01*
G01X1576200Y334667D02*
X1578700D01*
Y335708D01*
X1578575Y336042D01*
X1578408Y336250D01*
X1578075Y336333D01*
X1577742Y336250D01*
X1577533Y336000D01*
X1577408Y335708D01*
Y334667D01*
G01Y335708D02*
X1576200Y336333D01*
G01X1578283Y337808D02*
X1578533Y338058D01*
X1578658Y338350D01*
X1578700Y338683D01*
X1578617Y339100D01*
X1578408Y339392D01*
X1578158Y339475D01*
X1577908Y339433D01*
X1577700Y339267D01*
X1577283Y338433D01*
X1576992Y338058D01*
X1576575Y337808D01*
X1576200Y337725D01*
Y339475D01*
G01Y340742D02*
X1578700D01*
X1576200Y342658D01*
X1578700D01*
G01X1578283Y344008D02*
X1578533Y344258D01*
X1578658Y344550D01*
X1578700Y344883D01*
X1578617Y345300D01*
X1578408Y345592D01*
X1578158Y345675D01*
X1577908Y345633D01*
X1577700Y345467D01*
X1577283Y344633D01*
X1576992Y344258D01*
X1576575Y344008D01*
X1576200Y343925D01*
Y345675D01*
G01X1577242Y347108D02*
X1577533Y347400D01*
X1577700Y347650D01*
X1577783Y347983D01*
X1577700Y348275D01*
X1577533Y348483D01*
X1577283Y348650D01*
X1576992Y348692D01*
X1576742Y348650D01*
X1576492Y348483D01*
X1576283Y348233D01*
X1576200Y347942D01*
X1576283Y347608D01*
X1576533Y347317D01*
X1576908Y347150D01*
X1577325Y347108D01*
X1577867Y347192D01*
X1578158Y347317D01*
X1578450Y347525D01*
X1578658Y347817D01*
X1578700Y348108D01*
X1578617Y348400D01*
X1578408Y348608D01*
G01X1540750Y317167D02*
X1543250D01*
Y318208D01*
X1543125Y318542D01*
X1542958Y318750D01*
X1542625Y318833D01*
X1542292Y318750D01*
X1542083Y318500D01*
X1541958Y318208D01*
Y317167D01*
G01Y318208D02*
X1540750Y318833D01*
G01X1542833Y320308D02*
X1543083Y320558D01*
X1543208Y320850D01*
X1543250Y321183D01*
X1543167Y321600D01*
X1542958Y321892D01*
X1542708Y321975D01*
X1542458Y321933D01*
X1542250Y321767D01*
X1541833Y320933D01*
X1541542Y320558D01*
X1541125Y320308D01*
X1540750Y320225D01*
Y321975D01*
G01Y323242D02*
X1543250D01*
X1540750Y325158D01*
X1543250D01*
G01X1540750Y327300D02*
X1543250D01*
X1542750Y326800D01*
G01X1540750D02*
Y327800D01*
G01X1541042Y329692D02*
X1540833Y329983D01*
X1540750Y330317D01*
X1540833Y330650D01*
X1541083Y330942D01*
X1541458Y331150D01*
X1541833Y331233D01*
X1542292D01*
X1542667Y331150D01*
X1543000Y330942D01*
X1543167Y330692D01*
X1543250Y330400D01*
X1543167Y330067D01*
X1543000Y329817D01*
X1542750Y329650D01*
X1542417Y329567D01*
X1542125Y329650D01*
X1541833Y329858D01*
X1541667Y330108D01*
X1541625Y330400D01*
X1541708Y330733D01*
X1541917Y330983D01*
X1542292Y331233D01*
G01X1556600Y316817D02*
X1559100D01*
Y317858D01*
X1558975Y318192D01*
X1558808Y318400D01*
X1558475Y318483D01*
X1558142Y318400D01*
X1557933Y318150D01*
X1557808Y317858D01*
Y316817D01*
G01Y317858D02*
X1556600Y318483D01*
G01X1558683Y319958D02*
X1558933Y320208D01*
X1559058Y320500D01*
X1559100Y320833D01*
X1559017Y321250D01*
X1558808Y321542D01*
X1558558Y321625D01*
X1558308Y321583D01*
X1558100Y321417D01*
X1557683Y320583D01*
X1557392Y320208D01*
X1556975Y319958D01*
X1556600Y319875D01*
Y321625D01*
G01X1559100Y322933D02*
X1557308D01*
X1556933Y323100D01*
X1556683Y323433D01*
X1556600Y323850D01*
X1556683Y324267D01*
X1556933Y324600D01*
X1557308Y324767D01*
X1559100D01*
G01X1556600Y326950D02*
X1556642Y327242D01*
X1556767Y327575D01*
X1556975Y327783D01*
X1557267Y327867D01*
X1557558Y327783D01*
X1557808Y327533D01*
X1557933Y327158D01*
Y326742D01*
X1558017Y326492D01*
X1558225Y326283D01*
X1558517Y326200D01*
X1558808Y326325D01*
X1559017Y326617D01*
X1559100Y326950D01*
X1559017Y327283D01*
X1558808Y327575D01*
X1558517Y327700D01*
X1558225Y327617D01*
X1558017Y327408D01*
X1557933Y327158D01*
Y326742D01*
X1557808Y326367D01*
X1557558Y326117D01*
X1557267Y326033D01*
X1556975Y326117D01*
X1556767Y326325D01*
X1556642Y326658D01*
X1556600Y326950D01*
G01X1552800Y316467D02*
X1555300D01*
Y317508D01*
X1555175Y317842D01*
X1555008Y318050D01*
X1554675Y318133D01*
X1554342Y318050D01*
X1554133Y317800D01*
X1554008Y317508D01*
Y316467D01*
G01Y317508D02*
X1552800Y318133D01*
G01X1554883Y319608D02*
X1555133Y319858D01*
X1555258Y320150D01*
X1555300Y320483D01*
X1555217Y320900D01*
X1555008Y321192D01*
X1554758Y321275D01*
X1554508Y321233D01*
X1554300Y321067D01*
X1553883Y320233D01*
X1553592Y319858D01*
X1553175Y319608D01*
X1552800Y319525D01*
Y321275D01*
G01X1555300Y322583D02*
X1553508D01*
X1553133Y322750D01*
X1552883Y323083D01*
X1552800Y323500D01*
X1552883Y323917D01*
X1553133Y324250D01*
X1553508Y324417D01*
X1555300D01*
G01X1552800Y326600D02*
X1555300D01*
X1554800Y326100D01*
G01X1552800D02*
Y327100D01*
G01X1554883Y328908D02*
X1555133Y329158D01*
X1555258Y329450D01*
X1555300Y329783D01*
X1555217Y330200D01*
X1555008Y330492D01*
X1554758Y330575D01*
X1554508Y330533D01*
X1554300Y330367D01*
X1553883Y329533D01*
X1553592Y329158D01*
X1553175Y328908D01*
X1552800Y328825D01*
Y330575D01*
G01X1547750Y317167D02*
X1550250D01*
Y318208D01*
X1550125Y318542D01*
X1549958Y318750D01*
X1549625Y318833D01*
X1549292Y318750D01*
X1549083Y318500D01*
X1548958Y318208D01*
Y317167D01*
G01Y318208D02*
X1547750Y318833D01*
G01Y321100D02*
X1547792Y321392D01*
X1547917Y321725D01*
X1548125Y321933D01*
X1548417Y322017D01*
X1548708Y321933D01*
X1548958Y321683D01*
X1549083Y321308D01*
Y320892D01*
X1549167Y320642D01*
X1549375Y320433D01*
X1549667Y320350D01*
X1549958Y320475D01*
X1550167Y320767D01*
X1550250Y321100D01*
X1550167Y321433D01*
X1549958Y321725D01*
X1549667Y321850D01*
X1549375Y321767D01*
X1549167Y321558D01*
X1549083Y321308D01*
Y320892D01*
X1548958Y320517D01*
X1548708Y320267D01*
X1548417Y320183D01*
X1548125Y320267D01*
X1547917Y320475D01*
X1547792Y320808D01*
X1547750Y321100D01*
G01Y323283D02*
X1550250D01*
Y324117D01*
X1550125Y324450D01*
X1549958Y324700D01*
X1549708Y324908D01*
X1549417Y325075D01*
X1549000Y325117D01*
X1548583Y325075D01*
X1548292Y324908D01*
X1548042Y324700D01*
X1547875Y324450D01*
X1547750Y324117D01*
Y323283D01*
G01X1549833Y326508D02*
X1550083Y326758D01*
X1550208Y327050D01*
X1550250Y327383D01*
X1550167Y327800D01*
X1549958Y328092D01*
X1549708Y328175D01*
X1549458Y328133D01*
X1549250Y327967D01*
X1548833Y327133D01*
X1548542Y326758D01*
X1548125Y326508D01*
X1547750Y326425D01*
Y328175D01*
G01X1550250Y330400D02*
X1550167Y330067D01*
X1549958Y329817D01*
X1549708Y329650D01*
X1549375Y329525D01*
X1549000Y329483D01*
X1548625Y329525D01*
X1548292Y329650D01*
X1548042Y329817D01*
X1547833Y330067D01*
X1547750Y330400D01*
X1547833Y330733D01*
X1548042Y330983D01*
X1548292Y331150D01*
X1548625Y331275D01*
X1549000Y331317D01*
X1549375Y331275D01*
X1549708Y331150D01*
X1549958Y330983D01*
X1550167Y330733D01*
X1550250Y330400D01*
G01X1561700Y317267D02*
X1564200D01*
Y318308D01*
X1564075Y318642D01*
X1563908Y318850D01*
X1563575Y318933D01*
X1563242Y318850D01*
X1563033Y318600D01*
X1562908Y318308D01*
Y317267D01*
G01Y318308D02*
X1561700Y318933D01*
G01Y321200D02*
X1561742Y321492D01*
X1561867Y321825D01*
X1562075Y322033D01*
X1562367Y322117D01*
X1562658Y322033D01*
X1562908Y321783D01*
X1563033Y321408D01*
Y320992D01*
X1563117Y320742D01*
X1563325Y320533D01*
X1563617Y320450D01*
X1563908Y320575D01*
X1564117Y320867D01*
X1564200Y321200D01*
X1564117Y321533D01*
X1563908Y321825D01*
X1563617Y321950D01*
X1563325Y321867D01*
X1563117Y321658D01*
X1563033Y321408D01*
Y320992D01*
X1562908Y320617D01*
X1562658Y320367D01*
X1562367Y320283D01*
X1562075Y320367D01*
X1561867Y320575D01*
X1561742Y320908D01*
X1561700Y321200D01*
G01Y323383D02*
X1564200D01*
Y324217D01*
X1564075Y324550D01*
X1563908Y324800D01*
X1563658Y325008D01*
X1563367Y325175D01*
X1562950Y325217D01*
X1562533Y325175D01*
X1562242Y325008D01*
X1561992Y324800D01*
X1561825Y324550D01*
X1561700Y324217D01*
Y323383D01*
G01Y327400D02*
X1564200D01*
X1563700Y326900D01*
G01X1561700D02*
Y327900D01*
G01X1562075Y329583D02*
X1561867Y329833D01*
X1561742Y330125D01*
X1561700Y330500D01*
X1561783Y330875D01*
X1561950Y331167D01*
X1562242Y331375D01*
X1562575Y331417D01*
X1562908Y331333D01*
X1563117Y331125D01*
X1563283Y330833D01*
X1563325Y330542D01*
X1563283Y330250D01*
X1563117Y329875D01*
X1564200Y330000D01*
Y331125D01*
G01X1565300Y317567D02*
X1567800D01*
Y318608D01*
X1567675Y318942D01*
X1567508Y319150D01*
X1567175Y319233D01*
X1566842Y319150D01*
X1566633Y318900D01*
X1566508Y318608D01*
Y317567D01*
G01Y318608D02*
X1565300Y319233D01*
G01Y321500D02*
X1565342Y321792D01*
X1565467Y322125D01*
X1565675Y322333D01*
X1565967Y322417D01*
X1566258Y322333D01*
X1566508Y322083D01*
X1566633Y321708D01*
Y321292D01*
X1566717Y321042D01*
X1566925Y320833D01*
X1567217Y320750D01*
X1567508Y320875D01*
X1567717Y321167D01*
X1567800Y321500D01*
X1567717Y321833D01*
X1567508Y322125D01*
X1567217Y322250D01*
X1566925Y322167D01*
X1566717Y321958D01*
X1566633Y321708D01*
Y321292D01*
X1566508Y320917D01*
X1566258Y320667D01*
X1565967Y320583D01*
X1565675Y320667D01*
X1565467Y320875D01*
X1565342Y321208D01*
X1565300Y321500D01*
G01Y323683D02*
X1567800D01*
Y324517D01*
X1567675Y324850D01*
X1567508Y325100D01*
X1567258Y325308D01*
X1566967Y325475D01*
X1566550Y325517D01*
X1566133Y325475D01*
X1565842Y325308D01*
X1565592Y325100D01*
X1565425Y324850D01*
X1565300Y324517D01*
Y323683D01*
G01Y327700D02*
X1567800D01*
X1567300Y327200D01*
G01X1565300D02*
Y328200D01*
G01Y330717D02*
X1565842Y330800D01*
X1566300Y330925D01*
X1566717Y331092D01*
X1567175Y331300D01*
X1567800Y331633D01*
Y329967D01*
G01X1544250Y317167D02*
X1546750D01*
Y318208D01*
X1546625Y318542D01*
X1546458Y318750D01*
X1546125Y318833D01*
X1545792Y318750D01*
X1545583Y318500D01*
X1545458Y318208D01*
Y317167D01*
G01Y318208D02*
X1544250Y318833D01*
G01Y321100D02*
X1544292Y321392D01*
X1544417Y321725D01*
X1544625Y321933D01*
X1544917Y322017D01*
X1545208Y321933D01*
X1545458Y321683D01*
X1545583Y321308D01*
Y320892D01*
X1545667Y320642D01*
X1545875Y320433D01*
X1546167Y320350D01*
X1546458Y320475D01*
X1546667Y320767D01*
X1546750Y321100D01*
X1546667Y321433D01*
X1546458Y321725D01*
X1546167Y321850D01*
X1545875Y321767D01*
X1545667Y321558D01*
X1545583Y321308D01*
Y320892D01*
X1545458Y320517D01*
X1545208Y320267D01*
X1544917Y320183D01*
X1544625Y320267D01*
X1544417Y320475D01*
X1544292Y320808D01*
X1544250Y321100D01*
G01Y323283D02*
X1546750D01*
Y324117D01*
X1546625Y324450D01*
X1546458Y324700D01*
X1546208Y324908D01*
X1545917Y325075D01*
X1545500Y325117D01*
X1545083Y325075D01*
X1544792Y324908D01*
X1544542Y324700D01*
X1544375Y324450D01*
X1544250Y324117D01*
Y323283D01*
G01Y327300D02*
X1546750D01*
X1546250Y326800D01*
G01X1544250D02*
Y327800D01*
G01X1544542Y329692D02*
X1544333Y329983D01*
X1544250Y330317D01*
X1544333Y330650D01*
X1544583Y330942D01*
X1544958Y331150D01*
X1545333Y331233D01*
X1545792D01*
X1546167Y331150D01*
X1546500Y330942D01*
X1546667Y330692D01*
X1546750Y330400D01*
X1546667Y330067D01*
X1546500Y329817D01*
X1546250Y329650D01*
X1545917Y329567D01*
X1545625Y329650D01*
X1545333Y329858D01*
X1545167Y330108D01*
X1545125Y330400D01*
X1545208Y330733D01*
X1545417Y330983D01*
X1545792Y331233D01*
G01X1535500Y310367D02*
X1538000D01*
Y311408D01*
X1537875Y311742D01*
X1537708Y311950D01*
X1537375Y312033D01*
X1537042Y311950D01*
X1536833Y311700D01*
X1536708Y311408D01*
Y310367D01*
G01Y311408D02*
X1535500Y312033D01*
G01X1537583Y313508D02*
X1537833Y313758D01*
X1537958Y314050D01*
X1538000Y314383D01*
X1537917Y314800D01*
X1537708Y315092D01*
X1537458Y315175D01*
X1537208Y315133D01*
X1537000Y314967D01*
X1536583Y314133D01*
X1536292Y313758D01*
X1535875Y313508D01*
X1535500Y313425D01*
Y315175D01*
G01Y316442D02*
X1538000D01*
X1535500Y318358D01*
X1538000D01*
G01X1537583Y319708D02*
X1537833Y319958D01*
X1537958Y320250D01*
X1538000Y320583D01*
X1537917Y321000D01*
X1537708Y321292D01*
X1537458Y321375D01*
X1537208Y321333D01*
X1537000Y321167D01*
X1536583Y320333D01*
X1536292Y319958D01*
X1535875Y319708D01*
X1535500Y319625D01*
Y321375D01*
G01X1537583Y322808D02*
X1537833Y323058D01*
X1537958Y323350D01*
X1538000Y323683D01*
X1537917Y324100D01*
X1537708Y324392D01*
X1537458Y324475D01*
X1537208Y324433D01*
X1537000Y324267D01*
X1536583Y323433D01*
X1536292Y323058D01*
X1535875Y322808D01*
X1535500Y322725D01*
Y324475D01*
G01X1531700Y312767D02*
X1534200D01*
Y313808D01*
X1534075Y314142D01*
X1533908Y314350D01*
X1533575Y314433D01*
X1533242Y314350D01*
X1533033Y314100D01*
X1532908Y313808D01*
Y312767D01*
G01Y313808D02*
X1531700Y314433D01*
G01X1533783Y315908D02*
X1534033Y316158D01*
X1534158Y316450D01*
X1534200Y316783D01*
X1534117Y317200D01*
X1533908Y317492D01*
X1533658Y317575D01*
X1533408Y317533D01*
X1533200Y317367D01*
X1532783Y316533D01*
X1532492Y316158D01*
X1532075Y315908D01*
X1531700Y315825D01*
Y317575D01*
G01Y318842D02*
X1534200D01*
X1531700Y320758D01*
X1534200D01*
G01X1532200Y321983D02*
X1531908Y322233D01*
X1531742Y322567D01*
X1531700Y322942D01*
X1531742Y323275D01*
X1531950Y323608D01*
X1532200Y323817D01*
X1532450Y323858D01*
X1532742Y323775D01*
X1532950Y323483D01*
X1533033Y323192D01*
Y322817D01*
G01Y323192D02*
X1533158Y323442D01*
X1533367Y323650D01*
X1533617Y323733D01*
X1533867Y323650D01*
X1534075Y323442D01*
X1534200Y323067D01*
X1534158Y322692D01*
X1533992Y322317D01*
G01X1531700Y326000D02*
X1534200D01*
X1533700Y325500D01*
G01X1531700D02*
Y326500D01*
G01X1569100Y319917D02*
X1571600D01*
Y320958D01*
X1571475Y321292D01*
X1571308Y321500D01*
X1570975Y321583D01*
X1570642Y321500D01*
X1570433Y321250D01*
X1570308Y320958D01*
Y319917D01*
G01Y320958D02*
X1569100Y321583D01*
G01Y323850D02*
X1569142Y324142D01*
X1569267Y324475D01*
X1569475Y324683D01*
X1569767Y324767D01*
X1570058Y324683D01*
X1570308Y324433D01*
X1570433Y324058D01*
Y323642D01*
X1570517Y323392D01*
X1570725Y323183D01*
X1571017Y323100D01*
X1571308Y323225D01*
X1571517Y323517D01*
X1571600Y323850D01*
X1571517Y324183D01*
X1571308Y324475D01*
X1571017Y324600D01*
X1570725Y324517D01*
X1570517Y324308D01*
X1570433Y324058D01*
Y323642D01*
X1570308Y323267D01*
X1570058Y323017D01*
X1569767Y322933D01*
X1569475Y323017D01*
X1569267Y323225D01*
X1569142Y323558D01*
X1569100Y323850D01*
G01Y326033D02*
X1571600D01*
Y326867D01*
X1571475Y327200D01*
X1571308Y327450D01*
X1571058Y327658D01*
X1570767Y327825D01*
X1570350Y327867D01*
X1569933Y327825D01*
X1569642Y327658D01*
X1569392Y327450D01*
X1569225Y327200D01*
X1569100Y326867D01*
Y326033D01*
G01Y329967D02*
X1569642Y330050D01*
X1570100Y330175D01*
X1570517Y330342D01*
X1570975Y330550D01*
X1571600Y330883D01*
Y329217D01*
G01X1572700Y325217D02*
X1575200D01*
Y326258D01*
X1575075Y326592D01*
X1574908Y326800D01*
X1574575Y326883D01*
X1574242Y326800D01*
X1574033Y326550D01*
X1573908Y326258D01*
Y325217D01*
G01Y326258D02*
X1572700Y326883D01*
G01Y329150D02*
X1572742Y329442D01*
X1572867Y329775D01*
X1573075Y329983D01*
X1573367Y330067D01*
X1573658Y329983D01*
X1573908Y329733D01*
X1574033Y329358D01*
Y328942D01*
X1574117Y328692D01*
X1574325Y328483D01*
X1574617Y328400D01*
X1574908Y328525D01*
X1575117Y328817D01*
X1575200Y329150D01*
X1575117Y329483D01*
X1574908Y329775D01*
X1574617Y329900D01*
X1574325Y329817D01*
X1574117Y329608D01*
X1574033Y329358D01*
Y328942D01*
X1573908Y328567D01*
X1573658Y328317D01*
X1573367Y328233D01*
X1573075Y328317D01*
X1572867Y328525D01*
X1572742Y328858D01*
X1572700Y329150D01*
G01X1575200Y331000D02*
X1572700Y331583D01*
X1575200Y332250D01*
X1572700Y332917D01*
X1575200Y333500D01*
G01X1573742Y334558D02*
X1574033Y334850D01*
X1574200Y335100D01*
X1574283Y335433D01*
X1574200Y335725D01*
X1574033Y335933D01*
X1573783Y336100D01*
X1573492Y336142D01*
X1573242Y336100D01*
X1572992Y335933D01*
X1572783Y335683D01*
X1572700Y335392D01*
X1572783Y335058D01*
X1573033Y334767D01*
X1573408Y334600D01*
X1573825Y334558D01*
X1574367Y334642D01*
X1574658Y334767D01*
X1574950Y334975D01*
X1575158Y335267D01*
X1575200Y335558D01*
X1575117Y335850D01*
X1574908Y336058D01*
G01X1567189Y280694D02*
Y283194D01*
X1566148D01*
X1565814Y283069D01*
X1565606Y282902D01*
X1565523Y282569D01*
X1565606Y282236D01*
X1565856Y282027D01*
X1566148Y281902D01*
X1567189D01*
G01X1566148D02*
X1565523Y280694D01*
G01X1563339D02*
X1563256Y281236D01*
X1563131Y281694D01*
X1562964Y282111D01*
X1562756Y282569D01*
X1562423Y283194D01*
X1564089D01*
G01X1561406D02*
X1560823Y280694D01*
X1560156Y283194D01*
X1559489Y280694D01*
X1558906Y283194D01*
G01X1557973Y281069D02*
X1557723Y280861D01*
X1557431Y280736D01*
X1557056Y280694D01*
X1556681Y280777D01*
X1556389Y280944D01*
X1556181Y281236D01*
X1556139Y281569D01*
X1556223Y281902D01*
X1556431Y282111D01*
X1556723Y282277D01*
X1557014Y282319D01*
X1557306Y282277D01*
X1557681Y282111D01*
X1557556Y283194D01*
X1556431D01*
G01X1564033Y288992D02*
X1564283Y289117D01*
X1564575Y289200D01*
X1564908D01*
X1565283Y289075D01*
X1565575Y288867D01*
X1565783Y288617D01*
X1565950Y288200D01*
X1565992Y287825D01*
X1565908Y287450D01*
X1565783Y287200D01*
X1565533Y286950D01*
X1565242Y286783D01*
X1564950Y286700D01*
X1564658D01*
X1564367Y286783D01*
X1564117Y286908D01*
X1563908Y287075D01*
G01X1562642Y287742D02*
X1562350Y288033D01*
X1562100Y288200D01*
X1561767Y288283D01*
X1561475Y288200D01*
X1561267Y288033D01*
X1561100Y287783D01*
X1561058Y287492D01*
X1561100Y287242D01*
X1561267Y286992D01*
X1561517Y286783D01*
X1561808Y286700D01*
X1562142Y286783D01*
X1562433Y287033D01*
X1562600Y287408D01*
X1562642Y287825D01*
X1562558Y288367D01*
X1562433Y288658D01*
X1562225Y288950D01*
X1561933Y289158D01*
X1561642Y289200D01*
X1561350Y289117D01*
X1561142Y288908D01*
G01X1560000Y289200D02*
X1559417Y286700D01*
X1558750Y289200D01*
X1558083Y286700D01*
X1557500Y289200D01*
G01X1556442Y288783D02*
X1556192Y289033D01*
X1555900Y289158D01*
X1555567Y289200D01*
X1555150Y289117D01*
X1554858Y288908D01*
X1554775Y288658D01*
X1554817Y288408D01*
X1554983Y288200D01*
X1555817Y287783D01*
X1556192Y287492D01*
X1556442Y287075D01*
X1556525Y286700D01*
X1554775D01*
G01X1558833Y299792D02*
X1559083Y299917D01*
X1559375Y300000D01*
X1559708D01*
X1560083Y299875D01*
X1560375Y299667D01*
X1560583Y299417D01*
X1560750Y299000D01*
X1560792Y298625D01*
X1560708Y298250D01*
X1560583Y298000D01*
X1560333Y297750D01*
X1560042Y297583D01*
X1559750Y297500D01*
X1559458D01*
X1559167Y297583D01*
X1558917Y297708D01*
X1558708Y297875D01*
G01X1557442Y298542D02*
X1557150Y298833D01*
X1556900Y299000D01*
X1556567Y299083D01*
X1556275Y299000D01*
X1556067Y298833D01*
X1555900Y298583D01*
X1555858Y298292D01*
X1555900Y298042D01*
X1556067Y297792D01*
X1556317Y297583D01*
X1556608Y297500D01*
X1556942Y297583D01*
X1557233Y297833D01*
X1557400Y298208D01*
X1557442Y298625D01*
X1557358Y299167D01*
X1557233Y299458D01*
X1557025Y299750D01*
X1556733Y299958D01*
X1556442Y300000D01*
X1556150Y299917D01*
X1555942Y299708D01*
G01X1554800Y300000D02*
X1554217Y297500D01*
X1553550Y300000D01*
X1552883Y297500D01*
X1552300Y300000D01*
G01X1549950Y297500D02*
Y300000D01*
X1551492Y298208D01*
X1549408D01*
G01X1563667Y304800D02*
Y303008D01*
X1563500Y302633D01*
X1563167Y302383D01*
X1562750Y302300D01*
X1562333Y302383D01*
X1562000Y302633D01*
X1561833Y303008D01*
Y304800D01*
G01X1560442Y303342D02*
X1560150Y303633D01*
X1559900Y303800D01*
X1559567Y303883D01*
X1559275Y303800D01*
X1559067Y303633D01*
X1558900Y303383D01*
X1558858Y303092D01*
X1558900Y302842D01*
X1559067Y302592D01*
X1559317Y302383D01*
X1559608Y302300D01*
X1559942Y302383D01*
X1560233Y302633D01*
X1560400Y303008D01*
X1560442Y303425D01*
X1560358Y303967D01*
X1560233Y304258D01*
X1560025Y304550D01*
X1559733Y304758D01*
X1559442Y304800D01*
X1559150Y304717D01*
X1558942Y304508D01*
G01X1557800Y304800D02*
X1557217Y302300D01*
X1556550Y304800D01*
X1555883Y302300D01*
X1555300Y304800D01*
G01X1554242Y304383D02*
X1553992Y304633D01*
X1553700Y304758D01*
X1553367Y304800D01*
X1552950Y304717D01*
X1552658Y304508D01*
X1552575Y304258D01*
X1552617Y304008D01*
X1552783Y303800D01*
X1553617Y303383D01*
X1553992Y303092D01*
X1554242Y302675D01*
X1554325Y302300D01*
X1552575D01*
G01X1583060Y294140D02*
X1581060Y296140D01*
X1579060Y294140D01*
G01X1576910Y306090D02*
X1584910D01*
Y294140D01*
X1576910D01*
Y306090D01*
G01X1530600Y349200D02*
Y342300D01*
G01X1644200Y443600D02*
X1632363D01*
Y437963D01*
X1628254D01*
Y415568D01*
X1625100D01*
Y400500D01*
X1596300D01*
Y396100D01*
X1582700D01*
Y390800D01*
G01X1563702Y402510D02*
X1566202D01*
Y403551D01*
X1566077Y403885D01*
X1565910Y404093D01*
X1565577Y404176D01*
X1565244Y404093D01*
X1565035Y403843D01*
X1564910Y403551D01*
Y402510D01*
G01Y403551D02*
X1563702Y404176D01*
G01X1564744Y405651D02*
X1565035Y405943D01*
X1565202Y406193D01*
X1565285Y406526D01*
X1565202Y406818D01*
X1565035Y407026D01*
X1564785Y407193D01*
X1564494Y407235D01*
X1564244Y407193D01*
X1563994Y407026D01*
X1563785Y406776D01*
X1563702Y406485D01*
X1563785Y406151D01*
X1564035Y405860D01*
X1564410Y405693D01*
X1564827Y405651D01*
X1565369Y405735D01*
X1565660Y405860D01*
X1565952Y406068D01*
X1566160Y406360D01*
X1566202Y406651D01*
X1566119Y406943D01*
X1565910Y407151D01*
G01X1566202Y408293D02*
X1563702Y408876D01*
X1566202Y409543D01*
X1563702Y410210D01*
X1566202Y410793D01*
G01X1565785Y411851D02*
X1566035Y412101D01*
X1566160Y412393D01*
X1566202Y412726D01*
X1566119Y413143D01*
X1565910Y413435D01*
X1565660Y413518D01*
X1565410Y413476D01*
X1565202Y413310D01*
X1564785Y412476D01*
X1564494Y412101D01*
X1564077Y411851D01*
X1563702Y411768D01*
Y413518D01*
G01X1564077Y414826D02*
X1563869Y415076D01*
X1563744Y415368D01*
X1563702Y415743D01*
X1563785Y416118D01*
X1563952Y416410D01*
X1564244Y416618D01*
X1564577Y416660D01*
X1564910Y416576D01*
X1565119Y416368D01*
X1565285Y416076D01*
X1565327Y415785D01*
X1565285Y415493D01*
X1565119Y415118D01*
X1566202Y415243D01*
Y416368D01*
G01X1555860Y357655D02*
X1558360D01*
Y358696D01*
X1558235Y359030D01*
X1558068Y359238D01*
X1557735Y359321D01*
X1557402Y359238D01*
X1557193Y358988D01*
X1557068Y358696D01*
Y357655D01*
G01Y358696D02*
X1555860Y359321D01*
G01X1557943Y360796D02*
X1558193Y361046D01*
X1558318Y361338D01*
X1558360Y361671D01*
X1558277Y362088D01*
X1558068Y362380D01*
X1557818Y362463D01*
X1557568Y362421D01*
X1557360Y362255D01*
X1556943Y361421D01*
X1556652Y361046D01*
X1556235Y360796D01*
X1555860Y360713D01*
Y362463D01*
G01Y363730D02*
X1558360D01*
X1555860Y365646D01*
X1558360D01*
G01X1557943Y366996D02*
X1558193Y367246D01*
X1558318Y367538D01*
X1558360Y367871D01*
X1558277Y368288D01*
X1558068Y368580D01*
X1557818Y368663D01*
X1557568Y368621D01*
X1557360Y368455D01*
X1556943Y367621D01*
X1556652Y367246D01*
X1556235Y366996D01*
X1555860Y366913D01*
Y368663D01*
G01X1558360Y370888D02*
X1558277Y370555D01*
X1558068Y370305D01*
X1557818Y370138D01*
X1557485Y370013D01*
X1557110Y369971D01*
X1556735Y370013D01*
X1556402Y370138D01*
X1556152Y370305D01*
X1555943Y370555D01*
X1555860Y370888D01*
X1555943Y371221D01*
X1556152Y371471D01*
X1556402Y371638D01*
X1556735Y371763D01*
X1557110Y371805D01*
X1557485Y371763D01*
X1557818Y371638D01*
X1558068Y371471D01*
X1558277Y371221D01*
X1558360Y370888D01*
G01X1559900Y355167D02*
X1562400D01*
Y356208D01*
X1562275Y356542D01*
X1562108Y356750D01*
X1561775Y356833D01*
X1561442Y356750D01*
X1561233Y356500D01*
X1561108Y356208D01*
Y355167D01*
G01Y356208D02*
X1559900Y356833D01*
G01X1561983Y358308D02*
X1562233Y358558D01*
X1562358Y358850D01*
X1562400Y359183D01*
X1562317Y359600D01*
X1562108Y359892D01*
X1561858Y359975D01*
X1561608Y359933D01*
X1561400Y359767D01*
X1560983Y358933D01*
X1560692Y358558D01*
X1560275Y358308D01*
X1559900Y358225D01*
Y359975D01*
G01Y361242D02*
X1562400D01*
X1559900Y363158D01*
X1562400D01*
G01X1561983Y364508D02*
X1562233Y364758D01*
X1562358Y365050D01*
X1562400Y365383D01*
X1562317Y365800D01*
X1562108Y366092D01*
X1561858Y366175D01*
X1561608Y366133D01*
X1561400Y365967D01*
X1560983Y365133D01*
X1560692Y364758D01*
X1560275Y364508D01*
X1559900Y364425D01*
Y366175D01*
G01Y368400D02*
X1562400D01*
X1561900Y367900D01*
G01X1559900D02*
Y368900D01*
G01X1563531Y356589D02*
X1566031D01*
Y357630D01*
X1565906Y357964D01*
X1565739Y358172D01*
X1565406Y358255D01*
X1565073Y358172D01*
X1564864Y357922D01*
X1564739Y357630D01*
Y356589D01*
G01Y357630D02*
X1563531Y358255D01*
G01X1565614Y359730D02*
X1565864Y359980D01*
X1565989Y360272D01*
X1566031Y360605D01*
X1565948Y361022D01*
X1565739Y361314D01*
X1565489Y361397D01*
X1565239Y361355D01*
X1565031Y361189D01*
X1564614Y360355D01*
X1564323Y359980D01*
X1563906Y359730D01*
X1563531Y359647D01*
Y361397D01*
G01Y362664D02*
X1566031D01*
X1563531Y364580D01*
X1566031D01*
G01X1564031Y365805D02*
X1563739Y366055D01*
X1563573Y366389D01*
X1563531Y366764D01*
X1563573Y367097D01*
X1563781Y367430D01*
X1564031Y367639D01*
X1564281Y367680D01*
X1564573Y367597D01*
X1564781Y367305D01*
X1564864Y367014D01*
Y366639D01*
G01Y367014D02*
X1564989Y367264D01*
X1565198Y367472D01*
X1565448Y367555D01*
X1565698Y367472D01*
X1565906Y367264D01*
X1566031Y366889D01*
X1565989Y366514D01*
X1565823Y366139D01*
G01X1565614Y369030D02*
X1565864Y369280D01*
X1565989Y369572D01*
X1566031Y369905D01*
X1565948Y370322D01*
X1565739Y370614D01*
X1565489Y370697D01*
X1565239Y370655D01*
X1565031Y370489D01*
X1564614Y369655D01*
X1564323Y369280D01*
X1563906Y369030D01*
X1563531Y368947D01*
Y370697D01*
G01X1541083Y351500D02*
Y354000D01*
X1540042D01*
X1539708Y353875D01*
X1539500Y353708D01*
X1539417Y353375D01*
X1539500Y353042D01*
X1539750Y352833D01*
X1540042Y352708D01*
X1541083D01*
G01X1540042D02*
X1539417Y351500D01*
G01X1537942Y353583D02*
X1537692Y353833D01*
X1537400Y353958D01*
X1537067Y354000D01*
X1536650Y353917D01*
X1536358Y353708D01*
X1536275Y353458D01*
X1536317Y353208D01*
X1536483Y353000D01*
X1537317Y352583D01*
X1537692Y352292D01*
X1537942Y351875D01*
X1538025Y351500D01*
X1536275D01*
G01X1535300Y354000D02*
X1534717Y351500D01*
X1534050Y354000D01*
X1533383Y351500D01*
X1532800Y354000D01*
G01X1530450Y351500D02*
Y354000D01*
X1531992Y352208D01*
X1529908D01*
G01X1542583Y346500D02*
Y349000D01*
X1541542D01*
X1541208Y348875D01*
X1541000Y348708D01*
X1540917Y348375D01*
X1541000Y348042D01*
X1541250Y347833D01*
X1541542Y347708D01*
X1542583D01*
G01X1541542D02*
X1540917Y346500D01*
G01X1539442Y348583D02*
X1539192Y348833D01*
X1538900Y348958D01*
X1538567Y349000D01*
X1538150Y348917D01*
X1537858Y348708D01*
X1537775Y348458D01*
X1537817Y348208D01*
X1537983Y348000D01*
X1538817Y347583D01*
X1539192Y347292D01*
X1539442Y346875D01*
X1539525Y346500D01*
X1537775D01*
G01X1536800Y349000D02*
X1536217Y346500D01*
X1535550Y349000D01*
X1534883Y346500D01*
X1534300Y349000D01*
G01X1533367Y347000D02*
X1533117Y346708D01*
X1532783Y346542D01*
X1532408Y346500D01*
X1532075Y346542D01*
X1531742Y346750D01*
X1531533Y347000D01*
X1531492Y347250D01*
X1531575Y347542D01*
X1531867Y347750D01*
X1532158Y347833D01*
X1532533D01*
G01X1532158D02*
X1531908Y347958D01*
X1531700Y348167D01*
X1531617Y348417D01*
X1531700Y348667D01*
X1531908Y348875D01*
X1532283Y349000D01*
X1532658Y348958D01*
X1533033Y348792D01*
G01X1567890Y357211D02*
X1570390D01*
Y358252D01*
X1570265Y358586D01*
X1570098Y358794D01*
X1569765Y358877D01*
X1569432Y358794D01*
X1569223Y358544D01*
X1569098Y358252D01*
Y357211D01*
G01Y358252D02*
X1567890Y358877D01*
G01Y361144D02*
X1567932Y361436D01*
X1568057Y361769D01*
X1568265Y361977D01*
X1568557Y362061D01*
X1568848Y361977D01*
X1569098Y361727D01*
X1569223Y361352D01*
Y360936D01*
X1569307Y360686D01*
X1569515Y360477D01*
X1569807Y360394D01*
X1570098Y360519D01*
X1570307Y360811D01*
X1570390Y361144D01*
X1570307Y361477D01*
X1570098Y361769D01*
X1569807Y361894D01*
X1569515Y361811D01*
X1569307Y361602D01*
X1569223Y361352D01*
Y360936D01*
X1569098Y360561D01*
X1568848Y360311D01*
X1568557Y360227D01*
X1568265Y360311D01*
X1568057Y360519D01*
X1567932Y360852D01*
X1567890Y361144D01*
G01X1570390Y362994D02*
X1567890Y363577D01*
X1570390Y364244D01*
X1567890Y364911D01*
X1570390Y365494D01*
G01X1567890Y367261D02*
X1568432Y367344D01*
X1568890Y367469D01*
X1569307Y367636D01*
X1569765Y367844D01*
X1570390Y368177D01*
Y366511D01*
G01X1573700Y350917D02*
X1576200D01*
Y351958D01*
X1576075Y352292D01*
X1575908Y352500D01*
X1575575Y352583D01*
X1575242Y352500D01*
X1575033Y352250D01*
X1574908Y351958D01*
Y350917D01*
G01Y351958D02*
X1573700Y352583D01*
G01Y354850D02*
X1573742Y355142D01*
X1573867Y355475D01*
X1574075Y355683D01*
X1574367Y355767D01*
X1574658Y355683D01*
X1574908Y355433D01*
X1575033Y355058D01*
Y354642D01*
X1575117Y354392D01*
X1575325Y354183D01*
X1575617Y354100D01*
X1575908Y354225D01*
X1576117Y354517D01*
X1576200Y354850D01*
X1576117Y355183D01*
X1575908Y355475D01*
X1575617Y355600D01*
X1575325Y355517D01*
X1575117Y355308D01*
X1575033Y355058D01*
Y354642D01*
X1574908Y354267D01*
X1574658Y354017D01*
X1574367Y353933D01*
X1574075Y354017D01*
X1573867Y354225D01*
X1573742Y354558D01*
X1573700Y354850D01*
G01Y357033D02*
X1576200D01*
Y357867D01*
X1576075Y358200D01*
X1575908Y358450D01*
X1575658Y358658D01*
X1575367Y358825D01*
X1574950Y358867D01*
X1574533Y358825D01*
X1574242Y358658D01*
X1573992Y358450D01*
X1573825Y358200D01*
X1573700Y357867D01*
Y357033D01*
G01Y361550D02*
X1576200D01*
X1574408Y360008D01*
Y362092D01*
G01X1572623Y393704D02*
X1572748Y393454D01*
X1572831Y393162D01*
Y392829D01*
X1572706Y392454D01*
X1572498Y392162D01*
X1572248Y391954D01*
X1571831Y391787D01*
X1571456Y391745D01*
X1571081Y391829D01*
X1570831Y391954D01*
X1570581Y392204D01*
X1570414Y392495D01*
X1570331Y392787D01*
Y393079D01*
X1570414Y393370D01*
X1570539Y393620D01*
X1570706Y393829D01*
G01X1572414Y395095D02*
X1572664Y395345D01*
X1572789Y395637D01*
X1572831Y395970D01*
X1572748Y396387D01*
X1572539Y396679D01*
X1572289Y396762D01*
X1572039Y396720D01*
X1571831Y396554D01*
X1571414Y395720D01*
X1571123Y395345D01*
X1570706Y395095D01*
X1570331Y395012D01*
Y396762D01*
G01Y398029D02*
X1572831D01*
X1570331Y399945D01*
X1572831D01*
G01X1570331Y402087D02*
X1572831D01*
X1572331Y401587D01*
G01X1570331D02*
Y402587D01*
G01Y405687D02*
X1572831D01*
X1571039Y404145D01*
Y406229D01*
G01X1569296Y394070D02*
X1569421Y393820D01*
X1569504Y393528D01*
Y393195D01*
X1569379Y392820D01*
X1569171Y392528D01*
X1568921Y392320D01*
X1568504Y392153D01*
X1568129Y392111D01*
X1567754Y392195D01*
X1567504Y392320D01*
X1567254Y392570D01*
X1567087Y392861D01*
X1567004Y393153D01*
Y393445D01*
X1567087Y393736D01*
X1567212Y393986D01*
X1567379Y394195D01*
G01X1567004Y396170D02*
X1567546Y396253D01*
X1568004Y396378D01*
X1568421Y396545D01*
X1568879Y396753D01*
X1569504Y397086D01*
Y395420D01*
G01X1567004Y398436D02*
X1569504D01*
Y399270D01*
X1569379Y399603D01*
X1569212Y399853D01*
X1568962Y400061D01*
X1568671Y400228D01*
X1568254Y400270D01*
X1567837Y400228D01*
X1567546Y400061D01*
X1567296Y399853D01*
X1567129Y399603D01*
X1567004Y399270D01*
Y398436D01*
G01X1569087Y401661D02*
X1569337Y401911D01*
X1569462Y402203D01*
X1569504Y402536D01*
X1569421Y402953D01*
X1569212Y403245D01*
X1568962Y403328D01*
X1568712Y403286D01*
X1568504Y403120D01*
X1568087Y402286D01*
X1567796Y401911D01*
X1567379Y401661D01*
X1567004Y401578D01*
Y403328D01*
G01X1586225Y427040D02*
X1588725D01*
Y428081D01*
X1588600Y428415D01*
X1588433Y428623D01*
X1588100Y428706D01*
X1587767Y428623D01*
X1587558Y428373D01*
X1587433Y428081D01*
Y427040D01*
G01Y428081D02*
X1586225Y428706D01*
G01Y430973D02*
X1586267Y431265D01*
X1586392Y431598D01*
X1586600Y431806D01*
X1586892Y431890D01*
X1587183Y431806D01*
X1587433Y431556D01*
X1587558Y431181D01*
Y430765D01*
X1587642Y430515D01*
X1587850Y430306D01*
X1588142Y430223D01*
X1588433Y430348D01*
X1588642Y430640D01*
X1588725Y430973D01*
X1588642Y431306D01*
X1588433Y431598D01*
X1588142Y431723D01*
X1587850Y431640D01*
X1587642Y431431D01*
X1587558Y431181D01*
Y430765D01*
X1587433Y430390D01*
X1587183Y430140D01*
X1586892Y430056D01*
X1586600Y430140D01*
X1586392Y430348D01*
X1586267Y430681D01*
X1586225Y430973D01*
G01X1588517Y434990D02*
X1588642Y434740D01*
X1588725Y434448D01*
Y434115D01*
X1588600Y433740D01*
X1588392Y433448D01*
X1588142Y433240D01*
X1587725Y433073D01*
X1587350Y433031D01*
X1586975Y433115D01*
X1586725Y433240D01*
X1586475Y433490D01*
X1586308Y433781D01*
X1586225Y434073D01*
Y434365D01*
X1586308Y434656D01*
X1586433Y434906D01*
X1586600Y435115D01*
G01X1587267Y436381D02*
X1587558Y436673D01*
X1587725Y436923D01*
X1587808Y437256D01*
X1587725Y437548D01*
X1587558Y437756D01*
X1587308Y437923D01*
X1587017Y437965D01*
X1586767Y437923D01*
X1586517Y437756D01*
X1586308Y437506D01*
X1586225Y437215D01*
X1586308Y436881D01*
X1586558Y436590D01*
X1586933Y436423D01*
X1587350Y436381D01*
X1587892Y436465D01*
X1588183Y436590D01*
X1588475Y436798D01*
X1588683Y437090D01*
X1588725Y437381D01*
X1588642Y437673D01*
X1588433Y437881D01*
G01X1569300Y445017D02*
X1571800D01*
Y446058D01*
X1571675Y446392D01*
X1571508Y446600D01*
X1571175Y446683D01*
X1570842Y446600D01*
X1570633Y446350D01*
X1570508Y446058D01*
Y445017D01*
G01Y446058D02*
X1569300Y446683D01*
G01X1571383Y448158D02*
X1571633Y448408D01*
X1571758Y448700D01*
X1571800Y449033D01*
X1571717Y449450D01*
X1571508Y449742D01*
X1571258Y449825D01*
X1571008Y449783D01*
X1570800Y449617D01*
X1570383Y448783D01*
X1570092Y448408D01*
X1569675Y448158D01*
X1569300Y448075D01*
Y449825D01*
G01Y452550D02*
X1571800D01*
X1570008Y451008D01*
Y453092D01*
G01X1571800Y453900D02*
X1569300Y454483D01*
X1571800Y455150D01*
X1569300Y455817D01*
X1571800Y456400D01*
G01X1569300Y458250D02*
X1571800D01*
X1571300Y457750D01*
G01X1569300D02*
Y458750D01*
G01X1584600Y443017D02*
X1587100D01*
Y444058D01*
X1586975Y444392D01*
X1586808Y444600D01*
X1586475Y444683D01*
X1586142Y444600D01*
X1585933Y444350D01*
X1585808Y444058D01*
Y443017D01*
G01Y444058D02*
X1584600Y444683D01*
G01X1586683Y446158D02*
X1586933Y446408D01*
X1587058Y446700D01*
X1587100Y447033D01*
X1587017Y447450D01*
X1586808Y447742D01*
X1586558Y447825D01*
X1586308Y447783D01*
X1586100Y447617D01*
X1585683Y446783D01*
X1585392Y446408D01*
X1584975Y446158D01*
X1584600Y446075D01*
Y447825D01*
G01Y450550D02*
X1587100D01*
X1585308Y449008D01*
Y451092D01*
G01X1587100Y451900D02*
X1584600Y452483D01*
X1587100Y453150D01*
X1584600Y453817D01*
X1587100Y454400D01*
G01X1586683Y455458D02*
X1586933Y455708D01*
X1587058Y456000D01*
X1587100Y456333D01*
X1587017Y456750D01*
X1586808Y457042D01*
X1586558Y457125D01*
X1586308Y457083D01*
X1586100Y456917D01*
X1585683Y456083D01*
X1585392Y455708D01*
X1584975Y455458D01*
X1584600Y455375D01*
Y457125D01*
G01X1573200Y463817D02*
X1575700D01*
Y464858D01*
X1575575Y465192D01*
X1575408Y465400D01*
X1575075Y465483D01*
X1574742Y465400D01*
X1574533Y465150D01*
X1574408Y464858D01*
Y463817D01*
G01Y464858D02*
X1573200Y465483D01*
G01Y467667D02*
X1573742Y467750D01*
X1574200Y467875D01*
X1574617Y468042D01*
X1575075Y468250D01*
X1575700Y468583D01*
Y466917D01*
G01Y469600D02*
X1573200Y470183D01*
X1575700Y470850D01*
X1573200Y471517D01*
X1575700Y472100D01*
G01X1575283Y473158D02*
X1575533Y473408D01*
X1575658Y473700D01*
X1575700Y474033D01*
X1575617Y474450D01*
X1575408Y474742D01*
X1575158Y474825D01*
X1574908Y474783D01*
X1574700Y474617D01*
X1574283Y473783D01*
X1573992Y473408D01*
X1573575Y473158D01*
X1573200Y473075D01*
Y474825D01*
G01X1575700Y477050D02*
X1575617Y476717D01*
X1575408Y476467D01*
X1575158Y476300D01*
X1574825Y476175D01*
X1574450Y476133D01*
X1574075Y476175D01*
X1573742Y476300D01*
X1573492Y476467D01*
X1573283Y476717D01*
X1573200Y477050D01*
X1573283Y477383D01*
X1573492Y477633D01*
X1573742Y477800D01*
X1574075Y477925D01*
X1574450Y477967D01*
X1574825Y477925D01*
X1575158Y477800D01*
X1575408Y477633D01*
X1575617Y477383D01*
X1575700Y477050D01*
G01X1572630Y433108D02*
X1572755Y432858D01*
X1572838Y432566D01*
Y432233D01*
X1572713Y431858D01*
X1572505Y431566D01*
X1572255Y431358D01*
X1571838Y431191D01*
X1571463Y431149D01*
X1571088Y431233D01*
X1570838Y431358D01*
X1570588Y431608D01*
X1570421Y431899D01*
X1570338Y432191D01*
Y432483D01*
X1570421Y432774D01*
X1570546Y433024D01*
X1570713Y433233D01*
G01X1572421Y434499D02*
X1572671Y434749D01*
X1572796Y435041D01*
X1572838Y435374D01*
X1572755Y435791D01*
X1572546Y436083D01*
X1572296Y436166D01*
X1572046Y436124D01*
X1571838Y435958D01*
X1571421Y435124D01*
X1571130Y434749D01*
X1570713Y434499D01*
X1570338Y434416D01*
Y436166D01*
G01Y437433D02*
X1572838D01*
X1570338Y439349D01*
X1572838D01*
G01X1571380Y440699D02*
X1571671Y440991D01*
X1571838Y441241D01*
X1571921Y441574D01*
X1571838Y441866D01*
X1571671Y442074D01*
X1571421Y442241D01*
X1571130Y442283D01*
X1570880Y442241D01*
X1570630Y442074D01*
X1570421Y441824D01*
X1570338Y441533D01*
X1570421Y441199D01*
X1570671Y440908D01*
X1571046Y440741D01*
X1571463Y440699D01*
X1572005Y440783D01*
X1572296Y440908D01*
X1572588Y441116D01*
X1572796Y441408D01*
X1572838Y441699D01*
X1572755Y441991D01*
X1572546Y442199D01*
G01X1585269Y428677D02*
X1585394Y428427D01*
X1585477Y428135D01*
Y427802D01*
X1585352Y427427D01*
X1585144Y427135D01*
X1584894Y426927D01*
X1584477Y426760D01*
X1584102Y426718D01*
X1583727Y426802D01*
X1583477Y426927D01*
X1583227Y427177D01*
X1583060Y427468D01*
X1582977Y427760D01*
Y428052D01*
X1583060Y428343D01*
X1583185Y428593D01*
X1583352Y428802D01*
G01X1585060Y430068D02*
X1585310Y430318D01*
X1585435Y430610D01*
X1585477Y430943D01*
X1585394Y431360D01*
X1585185Y431652D01*
X1584935Y431735D01*
X1584685Y431693D01*
X1584477Y431527D01*
X1584060Y430693D01*
X1583769Y430318D01*
X1583352Y430068D01*
X1582977Y429985D01*
Y431735D01*
G01Y433002D02*
X1585477D01*
X1582977Y434918D01*
X1585477D01*
G01X1582977Y437060D02*
X1585477D01*
X1584977Y436560D01*
G01X1582977D02*
Y437560D01*
G01X1585477Y440160D02*
X1585394Y439827D01*
X1585185Y439577D01*
X1584935Y439410D01*
X1584602Y439285D01*
X1584227Y439243D01*
X1583852Y439285D01*
X1583519Y439410D01*
X1583269Y439577D01*
X1583060Y439827D01*
X1582977Y440160D01*
X1583060Y440493D01*
X1583269Y440743D01*
X1583519Y440910D01*
X1583852Y441035D01*
X1584227Y441077D01*
X1584602Y441035D01*
X1584935Y440910D01*
X1585185Y440743D01*
X1585394Y440493D01*
X1585477Y440160D01*
G01X1584692Y409617D02*
X1584817Y409367D01*
X1584900Y409075D01*
Y408742D01*
X1584775Y408367D01*
X1584567Y408075D01*
X1584317Y407867D01*
X1583900Y407700D01*
X1583525Y407658D01*
X1583150Y407742D01*
X1582900Y407867D01*
X1582650Y408117D01*
X1582483Y408408D01*
X1582400Y408700D01*
Y408992D01*
X1582483Y409283D01*
X1582608Y409533D01*
X1582775Y409742D01*
G01X1584483Y411008D02*
X1584733Y411258D01*
X1584858Y411550D01*
X1584900Y411883D01*
X1584817Y412300D01*
X1584608Y412592D01*
X1584358Y412675D01*
X1584108Y412633D01*
X1583900Y412467D01*
X1583483Y411633D01*
X1583192Y411258D01*
X1582775Y411008D01*
X1582400Y410925D01*
Y412675D01*
G01Y413942D02*
X1584900D01*
X1582400Y415858D01*
X1584900D01*
G01X1584483Y417208D02*
X1584733Y417458D01*
X1584858Y417750D01*
X1584900Y418083D01*
X1584817Y418500D01*
X1584608Y418792D01*
X1584358Y418875D01*
X1584108Y418833D01*
X1583900Y418667D01*
X1583483Y417833D01*
X1583192Y417458D01*
X1582775Y417208D01*
X1582400Y417125D01*
Y418875D01*
G01X1583442Y420308D02*
X1583733Y420600D01*
X1583900Y420850D01*
X1583983Y421183D01*
X1583900Y421475D01*
X1583733Y421683D01*
X1583483Y421850D01*
X1583192Y421892D01*
X1582942Y421850D01*
X1582692Y421683D01*
X1582483Y421433D01*
X1582400Y421142D01*
X1582483Y420808D01*
X1582733Y420517D01*
X1583108Y420350D01*
X1583525Y420308D01*
X1584067Y420392D01*
X1584358Y420517D01*
X1584650Y420725D01*
X1584858Y421017D01*
X1584900Y421308D01*
X1584817Y421600D01*
X1584608Y421808D01*
G01X1568392Y429767D02*
X1568517Y429517D01*
X1568600Y429225D01*
Y428892D01*
X1568475Y428517D01*
X1568267Y428225D01*
X1568017Y428017D01*
X1567600Y427850D01*
X1567225Y427808D01*
X1566850Y427892D01*
X1566600Y428017D01*
X1566350Y428267D01*
X1566183Y428558D01*
X1566100Y428850D01*
Y429142D01*
X1566183Y429433D01*
X1566308Y429683D01*
X1566475Y429892D01*
G01X1568183Y431158D02*
X1568433Y431408D01*
X1568558Y431700D01*
X1568600Y432033D01*
X1568517Y432450D01*
X1568308Y432742D01*
X1568058Y432825D01*
X1567808Y432783D01*
X1567600Y432617D01*
X1567183Y431783D01*
X1566892Y431408D01*
X1566475Y431158D01*
X1566100Y431075D01*
Y432825D01*
G01Y434092D02*
X1568600D01*
X1566100Y436008D01*
X1568600D01*
G01X1566475Y437233D02*
X1566267Y437483D01*
X1566142Y437775D01*
X1566100Y438150D01*
X1566183Y438525D01*
X1566350Y438817D01*
X1566642Y439025D01*
X1566975Y439067D01*
X1567308Y438983D01*
X1567517Y438775D01*
X1567683Y438483D01*
X1567725Y438192D01*
X1567683Y437900D01*
X1567517Y437525D01*
X1568600Y437650D01*
Y438775D01*
G01X1550733Y493300D02*
Y495800D01*
X1549692D01*
X1549358Y495675D01*
X1549150Y495508D01*
X1549067Y495175D01*
X1549150Y494842D01*
X1549400Y494633D01*
X1549692Y494508D01*
X1550733D01*
G01X1549692D02*
X1549067Y493300D01*
G01X1547717Y493800D02*
X1547467Y493508D01*
X1547133Y493342D01*
X1546758Y493300D01*
X1546425Y493342D01*
X1546092Y493550D01*
X1545883Y493800D01*
X1545842Y494050D01*
X1545925Y494342D01*
X1546217Y494550D01*
X1546508Y494633D01*
X1546883D01*
G01X1546508D02*
X1546258Y494758D01*
X1546050Y494967D01*
X1545967Y495217D01*
X1546050Y495467D01*
X1546258Y495675D01*
X1546633Y495800D01*
X1547008Y495758D01*
X1547383Y495592D01*
G01X1544783Y493300D02*
Y495800D01*
X1543700Y493717D01*
X1542617Y495800D01*
Y493300D01*
G01X1540600D02*
Y495800D01*
X1541100Y495300D01*
G01Y493300D02*
X1540100D01*
G01X1537500D02*
Y495800D01*
X1538000Y495300D01*
G01Y493300D02*
X1537000D01*
G01X1535350Y510077D02*
X1537850D01*
Y511118D01*
X1537725Y511452D01*
X1537558Y511660D01*
X1537225Y511743D01*
X1536892Y511660D01*
X1536683Y511410D01*
X1536558Y511118D01*
Y510077D01*
G01Y511118D02*
X1535350Y511743D01*
G01X1535850Y513093D02*
X1535558Y513343D01*
X1535392Y513677D01*
X1535350Y514052D01*
X1535392Y514385D01*
X1535600Y514718D01*
X1535850Y514927D01*
X1536100Y514968D01*
X1536392Y514885D01*
X1536600Y514593D01*
X1536683Y514302D01*
Y513927D01*
G01Y514302D02*
X1536808Y514552D01*
X1537017Y514760D01*
X1537267Y514843D01*
X1537517Y514760D01*
X1537725Y514552D01*
X1537850Y514177D01*
X1537808Y513802D01*
X1537642Y513427D01*
G01X1535350Y516027D02*
X1537850D01*
X1535767Y517110D01*
X1537850Y518193D01*
X1535350D01*
G01X1535642Y519502D02*
X1535433Y519793D01*
X1535350Y520127D01*
X1535433Y520460D01*
X1535683Y520752D01*
X1536058Y520960D01*
X1536433Y521043D01*
X1536892D01*
X1537267Y520960D01*
X1537600Y520752D01*
X1537767Y520502D01*
X1537850Y520210D01*
X1537767Y519877D01*
X1537600Y519627D01*
X1537350Y519460D01*
X1537017Y519377D01*
X1536725Y519460D01*
X1536433Y519668D01*
X1536267Y519918D01*
X1536225Y520210D01*
X1536308Y520543D01*
X1536517Y520793D01*
X1536892Y521043D01*
G01X1538650Y510077D02*
X1541150D01*
Y511118D01*
X1541025Y511452D01*
X1540858Y511660D01*
X1540525Y511743D01*
X1540192Y511660D01*
X1539983Y511410D01*
X1539858Y511118D01*
Y510077D01*
G01Y511118D02*
X1538650Y511743D01*
G01X1539150Y513093D02*
X1538858Y513343D01*
X1538692Y513677D01*
X1538650Y514052D01*
X1538692Y514385D01*
X1538900Y514718D01*
X1539150Y514927D01*
X1539400Y514968D01*
X1539692Y514885D01*
X1539900Y514593D01*
X1539983Y514302D01*
Y513927D01*
G01Y514302D02*
X1540108Y514552D01*
X1540317Y514760D01*
X1540567Y514843D01*
X1540817Y514760D01*
X1541025Y514552D01*
X1541150Y514177D01*
X1541108Y513802D01*
X1540942Y513427D01*
G01X1538650Y516027D02*
X1541150D01*
X1539067Y517110D01*
X1541150Y518193D01*
X1538650D01*
G01Y520210D02*
X1538692Y520502D01*
X1538817Y520835D01*
X1539025Y521043D01*
X1539317Y521127D01*
X1539608Y521043D01*
X1539858Y520793D01*
X1539983Y520418D01*
Y520002D01*
X1540067Y519752D01*
X1540275Y519543D01*
X1540567Y519460D01*
X1540858Y519585D01*
X1541067Y519877D01*
X1541150Y520210D01*
X1541067Y520543D01*
X1540858Y520835D01*
X1540567Y520960D01*
X1540275Y520877D01*
X1540067Y520668D01*
X1539983Y520418D01*
Y520002D01*
X1539858Y519627D01*
X1539608Y519377D01*
X1539317Y519293D01*
X1539025Y519377D01*
X1538817Y519585D01*
X1538692Y519918D01*
X1538650Y520210D01*
G01X1577000Y475817D02*
X1579500D01*
Y476858D01*
X1579375Y477192D01*
X1579208Y477400D01*
X1578875Y477483D01*
X1578542Y477400D01*
X1578333Y477150D01*
X1578208Y476858D01*
Y475817D01*
G01Y476858D02*
X1577000Y477483D01*
G01Y479667D02*
X1577542Y479750D01*
X1578000Y479875D01*
X1578417Y480042D01*
X1578875Y480250D01*
X1579500Y480583D01*
Y478917D01*
G01Y481600D02*
X1577000Y482183D01*
X1579500Y482850D01*
X1577000Y483517D01*
X1579500Y484100D01*
G01X1577000Y485950D02*
X1577042Y486242D01*
X1577167Y486575D01*
X1577375Y486783D01*
X1577667Y486867D01*
X1577958Y486783D01*
X1578208Y486533D01*
X1578333Y486158D01*
Y485742D01*
X1578417Y485492D01*
X1578625Y485283D01*
X1578917Y485200D01*
X1579208Y485325D01*
X1579417Y485617D01*
X1579500Y485950D01*
X1579417Y486283D01*
X1579208Y486575D01*
X1578917Y486700D01*
X1578625Y486617D01*
X1578417Y486408D01*
X1578333Y486158D01*
Y485742D01*
X1578208Y485367D01*
X1577958Y485117D01*
X1577667Y485033D01*
X1577375Y485117D01*
X1577167Y485325D01*
X1577042Y485658D01*
X1577000Y485950D01*
G01X1541683Y525092D02*
X1541933Y525217D01*
X1542225Y525300D01*
X1542558D01*
X1542933Y525175D01*
X1543225Y524967D01*
X1543433Y524717D01*
X1543600Y524300D01*
X1543642Y523925D01*
X1543558Y523550D01*
X1543433Y523300D01*
X1543183Y523050D01*
X1542892Y522883D01*
X1542600Y522800D01*
X1542308D01*
X1542017Y522883D01*
X1541767Y523008D01*
X1541558Y523175D01*
G01X1540417Y523300D02*
X1540167Y523008D01*
X1539833Y522842D01*
X1539458Y522800D01*
X1539125Y522842D01*
X1538792Y523050D01*
X1538583Y523300D01*
X1538542Y523550D01*
X1538625Y523842D01*
X1538917Y524050D01*
X1539208Y524133D01*
X1539583D01*
G01X1539208D02*
X1538958Y524258D01*
X1538750Y524467D01*
X1538667Y524717D01*
X1538750Y524967D01*
X1538958Y525175D01*
X1539333Y525300D01*
X1539708Y525258D01*
X1540083Y525092D01*
G01X1537483Y522800D02*
Y525300D01*
X1536400Y523217D01*
X1535317Y525300D01*
Y522800D01*
G01X1534092Y524883D02*
X1533842Y525133D01*
X1533550Y525258D01*
X1533217Y525300D01*
X1532800Y525217D01*
X1532508Y525008D01*
X1532425Y524758D01*
X1532467Y524508D01*
X1532633Y524300D01*
X1533467Y523883D01*
X1533842Y523592D01*
X1534092Y523175D01*
X1534175Y522800D01*
X1532425D01*
G01X1531117Y523300D02*
X1530867Y523008D01*
X1530533Y522842D01*
X1530158Y522800D01*
X1529825Y522842D01*
X1529492Y523050D01*
X1529283Y523300D01*
X1529242Y523550D01*
X1529325Y523842D01*
X1529617Y524050D01*
X1529908Y524133D01*
X1530283D01*
G01X1529908D02*
X1529658Y524258D01*
X1529450Y524467D01*
X1529367Y524717D01*
X1529450Y524967D01*
X1529658Y525175D01*
X1530033Y525300D01*
X1530408Y525258D01*
X1530783Y525092D01*
G01X1585592Y484267D02*
X1585717Y484017D01*
X1585800Y483725D01*
Y483392D01*
X1585675Y483017D01*
X1585467Y482725D01*
X1585217Y482517D01*
X1584800Y482350D01*
X1584425Y482308D01*
X1584050Y482392D01*
X1583800Y482517D01*
X1583550Y482767D01*
X1583383Y483058D01*
X1583300Y483350D01*
Y483642D01*
X1583383Y483933D01*
X1583508Y484183D01*
X1583675Y484392D01*
G01X1585383Y485658D02*
X1585633Y485908D01*
X1585758Y486200D01*
X1585800Y486533D01*
X1585717Y486950D01*
X1585508Y487242D01*
X1585258Y487325D01*
X1585008Y487283D01*
X1584800Y487117D01*
X1584383Y486283D01*
X1584092Y485908D01*
X1583675Y485658D01*
X1583300Y485575D01*
Y487325D01*
G01Y488467D02*
X1585800D01*
X1583717Y489550D01*
X1585800Y490633D01*
X1583300D01*
G01Y492567D02*
X1583842Y492650D01*
X1584300Y492775D01*
X1584717Y492942D01*
X1585175Y493150D01*
X1585800Y493483D01*
Y491817D01*
G01X1589370Y513475D02*
X1589620Y513600D01*
X1589912Y513683D01*
X1590245D01*
X1590620Y513558D01*
X1590912Y513350D01*
X1591120Y513100D01*
X1591287Y512683D01*
X1591329Y512308D01*
X1591245Y511933D01*
X1591120Y511683D01*
X1590870Y511433D01*
X1590579Y511266D01*
X1590287Y511183D01*
X1589995D01*
X1589704Y511266D01*
X1589454Y511391D01*
X1589245Y511558D01*
G01X1587979Y513266D02*
X1587729Y513516D01*
X1587437Y513641D01*
X1587104Y513683D01*
X1586687Y513600D01*
X1586395Y513391D01*
X1586312Y513141D01*
X1586354Y512891D01*
X1586520Y512683D01*
X1587354Y512266D01*
X1587729Y511975D01*
X1587979Y511558D01*
X1588062Y511183D01*
X1586312D01*
G01X1585170D02*
Y513683D01*
X1584087Y511600D01*
X1583004Y513683D01*
Y511183D01*
G01X1581779Y513266D02*
X1581529Y513516D01*
X1581237Y513641D01*
X1580904Y513683D01*
X1580487Y513600D01*
X1580195Y513391D01*
X1580112Y513141D01*
X1580154Y512891D01*
X1580320Y512683D01*
X1581154Y512266D01*
X1581529Y511975D01*
X1581779Y511558D01*
X1581862Y511183D01*
X1580112D01*
G01X1578804Y511683D02*
X1578554Y511391D01*
X1578220Y511225D01*
X1577845Y511183D01*
X1577512Y511225D01*
X1577179Y511433D01*
X1576970Y511683D01*
X1576929Y511933D01*
X1577012Y512225D01*
X1577304Y512433D01*
X1577595Y512516D01*
X1577970D01*
G01X1577595D02*
X1577345Y512641D01*
X1577137Y512850D01*
X1577054Y513100D01*
X1577137Y513350D01*
X1577345Y513558D01*
X1577720Y513683D01*
X1578095Y513641D01*
X1578470Y513475D01*
G01X1589583Y509759D02*
X1589833Y509884D01*
X1590125Y509967D01*
X1590458D01*
X1590833Y509842D01*
X1591125Y509634D01*
X1591333Y509384D01*
X1591500Y508967D01*
X1591542Y508592D01*
X1591458Y508217D01*
X1591333Y507967D01*
X1591083Y507717D01*
X1590792Y507550D01*
X1590500Y507467D01*
X1590208D01*
X1589917Y507550D01*
X1589667Y507675D01*
X1589458Y507842D01*
G01X1588192Y509550D02*
X1587942Y509800D01*
X1587650Y509925D01*
X1587317Y509967D01*
X1586900Y509884D01*
X1586608Y509675D01*
X1586525Y509425D01*
X1586567Y509175D01*
X1586733Y508967D01*
X1587567Y508550D01*
X1587942Y508259D01*
X1588192Y507842D01*
X1588275Y507467D01*
X1586525D01*
G01X1585383D02*
Y509967D01*
X1584300Y507884D01*
X1583217Y509967D01*
Y507467D01*
G01X1581992Y509550D02*
X1581742Y509800D01*
X1581450Y509925D01*
X1581117Y509967D01*
X1580700Y509884D01*
X1580408Y509675D01*
X1580325Y509425D01*
X1580367Y509175D01*
X1580533Y508967D01*
X1581367Y508550D01*
X1581742Y508259D01*
X1581992Y507842D01*
X1582075Y507467D01*
X1580325D01*
G01X1577600D02*
Y509967D01*
X1579142Y508175D01*
X1577058D01*
G01X1584392Y468417D02*
X1584517Y468167D01*
X1584600Y467875D01*
Y467542D01*
X1584475Y467167D01*
X1584267Y466875D01*
X1584017Y466667D01*
X1583600Y466500D01*
X1583225Y466458D01*
X1582850Y466542D01*
X1582600Y466667D01*
X1582350Y466917D01*
X1582183Y467208D01*
X1582100Y467500D01*
Y467792D01*
X1582183Y468083D01*
X1582308Y468333D01*
X1582475Y468542D01*
G01X1584183Y469808D02*
X1584433Y470058D01*
X1584558Y470350D01*
X1584600Y470683D01*
X1584517Y471100D01*
X1584308Y471392D01*
X1584058Y471475D01*
X1583808Y471433D01*
X1583600Y471267D01*
X1583183Y470433D01*
X1582892Y470058D01*
X1582475Y469808D01*
X1582100Y469725D01*
Y471475D01*
G01Y472617D02*
X1584600D01*
X1582517Y473700D01*
X1584600Y474783D01*
X1582100D01*
G01X1584183Y476008D02*
X1584433Y476258D01*
X1584558Y476550D01*
X1584600Y476883D01*
X1584517Y477300D01*
X1584308Y477592D01*
X1584058Y477675D01*
X1583808Y477633D01*
X1583600Y477467D01*
X1583183Y476633D01*
X1582892Y476258D01*
X1582475Y476008D01*
X1582100Y475925D01*
Y477675D01*
G01X1582475Y478983D02*
X1582267Y479233D01*
X1582142Y479525D01*
X1582100Y479900D01*
X1582183Y480275D01*
X1582350Y480567D01*
X1582642Y480775D01*
X1582975Y480817D01*
X1583308Y480733D01*
X1583517Y480525D01*
X1583683Y480233D01*
X1583725Y479942D01*
X1583683Y479650D01*
X1583517Y479275D01*
X1584600Y479400D01*
Y480525D01*
G01X1565289Y492588D02*
X1565539Y492713D01*
X1565831Y492796D01*
X1566164D01*
X1566539Y492671D01*
X1566831Y492463D01*
X1567039Y492213D01*
X1567206Y491796D01*
X1567248Y491421D01*
X1567164Y491046D01*
X1567039Y490796D01*
X1566789Y490546D01*
X1566498Y490379D01*
X1566206Y490296D01*
X1565914D01*
X1565623Y490379D01*
X1565373Y490504D01*
X1565164Y490671D01*
G01X1563898Y492379D02*
X1563648Y492629D01*
X1563356Y492754D01*
X1563023Y492796D01*
X1562606Y492713D01*
X1562314Y492504D01*
X1562231Y492254D01*
X1562273Y492004D01*
X1562439Y491796D01*
X1563273Y491379D01*
X1563648Y491088D01*
X1563898Y490671D01*
X1563981Y490296D01*
X1562231D01*
G01X1561089D02*
Y492796D01*
X1560006Y490713D01*
X1558923Y492796D01*
Y490296D01*
G01X1556406D02*
Y492796D01*
X1557948Y491004D01*
X1555864D01*
G01X1565289Y496088D02*
X1565539Y496213D01*
X1565831Y496296D01*
X1566164D01*
X1566539Y496171D01*
X1566831Y495963D01*
X1567039Y495713D01*
X1567206Y495296D01*
X1567248Y494921D01*
X1567164Y494546D01*
X1567039Y494296D01*
X1566789Y494046D01*
X1566498Y493879D01*
X1566206Y493796D01*
X1565914D01*
X1565623Y493879D01*
X1565373Y494004D01*
X1565164Y494171D01*
G01X1563898Y495879D02*
X1563648Y496129D01*
X1563356Y496254D01*
X1563023Y496296D01*
X1562606Y496213D01*
X1562314Y496004D01*
X1562231Y495754D01*
X1562273Y495504D01*
X1562439Y495296D01*
X1563273Y494879D01*
X1563648Y494588D01*
X1563898Y494171D01*
X1563981Y493796D01*
X1562231D01*
G01X1561089D02*
Y496296D01*
X1560006Y494213D01*
X1558923Y496296D01*
Y493796D01*
G01X1557823Y494296D02*
X1557573Y494004D01*
X1557239Y493838D01*
X1556864Y493796D01*
X1556531Y493838D01*
X1556198Y494046D01*
X1555989Y494296D01*
X1555948Y494546D01*
X1556031Y494838D01*
X1556323Y495046D01*
X1556614Y495129D01*
X1556989D01*
G01X1556614D02*
X1556364Y495254D01*
X1556156Y495463D01*
X1556073Y495713D01*
X1556156Y495963D01*
X1556364Y496171D01*
X1556739Y496296D01*
X1557114Y496254D01*
X1557489Y496088D01*
G01X1561383Y525092D02*
X1561633Y525217D01*
X1561925Y525300D01*
X1562258D01*
X1562633Y525175D01*
X1562925Y524967D01*
X1563133Y524717D01*
X1563300Y524300D01*
X1563342Y523925D01*
X1563258Y523550D01*
X1563133Y523300D01*
X1562883Y523050D01*
X1562592Y522883D01*
X1562300Y522800D01*
X1562008D01*
X1561717Y522883D01*
X1561467Y523008D01*
X1561258Y523175D01*
G01X1560117Y523300D02*
X1559867Y523008D01*
X1559533Y522842D01*
X1559158Y522800D01*
X1558825Y522842D01*
X1558492Y523050D01*
X1558283Y523300D01*
X1558242Y523550D01*
X1558325Y523842D01*
X1558617Y524050D01*
X1558908Y524133D01*
X1559283D01*
G01X1558908D02*
X1558658Y524258D01*
X1558450Y524467D01*
X1558367Y524717D01*
X1558450Y524967D01*
X1558658Y525175D01*
X1559033Y525300D01*
X1559408Y525258D01*
X1559783Y525092D01*
G01X1557183Y522800D02*
Y525300D01*
X1556100Y523217D01*
X1555017Y525300D01*
Y522800D01*
G01X1553792Y524883D02*
X1553542Y525133D01*
X1553250Y525258D01*
X1552917Y525300D01*
X1552500Y525217D01*
X1552208Y525008D01*
X1552125Y524758D01*
X1552167Y524508D01*
X1552333Y524300D01*
X1553167Y523883D01*
X1553542Y523592D01*
X1553792Y523175D01*
X1553875Y522800D01*
X1552125D01*
G01X1549983D02*
X1549900Y523342D01*
X1549775Y523800D01*
X1549608Y524217D01*
X1549400Y524675D01*
X1549067Y525300D01*
X1550733D01*
G01X1544500Y511908D02*
X1547000D01*
Y513492D01*
G01X1545792Y512908D02*
Y511908D01*
G01X1545833Y516133D02*
X1545958Y516300D01*
X1546167Y516425D01*
X1546458Y516508D01*
X1546708Y516425D01*
X1546875Y516258D01*
X1547000Y515967D01*
Y514842D01*
X1544500D01*
Y516217D01*
X1544667Y516508D01*
X1544917Y516675D01*
X1545208Y516758D01*
X1545500Y516675D01*
X1545750Y516425D01*
X1545833Y516133D01*
Y514842D01*
G01X1545000Y517983D02*
X1544708Y518233D01*
X1544542Y518567D01*
X1544500Y518942D01*
X1544542Y519275D01*
X1544750Y519608D01*
X1545000Y519817D01*
X1545250Y519858D01*
X1545542Y519775D01*
X1545750Y519483D01*
X1545833Y519192D01*
Y518817D01*
G01Y519192D02*
X1545958Y519442D01*
X1546167Y519650D01*
X1546417Y519733D01*
X1546667Y519650D01*
X1546875Y519442D01*
X1547000Y519067D01*
X1546958Y518692D01*
X1546792Y518317D01*
G01X1544500Y520917D02*
X1547000D01*
X1544917Y522000D01*
X1547000Y523083D01*
X1544500D01*
G01X1545000Y524183D02*
X1544708Y524433D01*
X1544542Y524767D01*
X1544500Y525142D01*
X1544542Y525475D01*
X1544750Y525808D01*
X1545000Y526017D01*
X1545250Y526058D01*
X1545542Y525975D01*
X1545750Y525683D01*
X1545833Y525392D01*
Y525017D01*
G01Y525392D02*
X1545958Y525642D01*
X1546167Y525850D01*
X1546417Y525933D01*
X1546667Y525850D01*
X1546875Y525642D01*
X1547000Y525267D01*
X1546958Y524892D01*
X1546792Y524517D01*
G01X1531194Y585683D02*
X1531319Y585433D01*
X1531402Y585141D01*
Y584808D01*
X1531277Y584433D01*
X1531069Y584141D01*
X1530819Y583933D01*
X1530402Y583766D01*
X1530027Y583724D01*
X1529652Y583808D01*
X1529402Y583933D01*
X1529152Y584183D01*
X1528985Y584474D01*
X1528902Y584766D01*
Y585058D01*
X1528985Y585349D01*
X1529110Y585599D01*
X1529277Y585808D01*
G01X1529402Y586949D02*
X1529110Y587199D01*
X1528944Y587533D01*
X1528902Y587908D01*
X1528944Y588241D01*
X1529152Y588574D01*
X1529402Y588783D01*
X1529652Y588824D01*
X1529944Y588741D01*
X1530152Y588449D01*
X1530235Y588158D01*
Y587783D01*
G01Y588158D02*
X1530360Y588408D01*
X1530569Y588616D01*
X1530819Y588699D01*
X1531069Y588616D01*
X1531277Y588408D01*
X1531402Y588033D01*
X1531360Y587658D01*
X1531194Y587283D01*
G01X1531402Y590133D02*
X1528902D01*
Y591799D01*
G01Y594066D02*
X1531402D01*
X1530902Y593566D01*
G01X1528902D02*
Y594566D01*
G01X1531402Y597166D02*
X1531319Y596833D01*
X1531110Y596583D01*
X1530860Y596416D01*
X1530527Y596291D01*
X1530152Y596249D01*
X1529777Y596291D01*
X1529444Y596416D01*
X1529194Y596583D01*
X1528985Y596833D01*
X1528902Y597166D01*
X1528985Y597499D01*
X1529194Y597749D01*
X1529444Y597916D01*
X1529777Y598041D01*
X1530152Y598083D01*
X1530527Y598041D01*
X1530860Y597916D01*
X1531110Y597749D01*
X1531319Y597499D01*
X1531402Y597166D01*
G01X1592183Y549559D02*
X1592433Y549684D01*
X1592725Y549767D01*
X1593058D01*
X1593433Y549642D01*
X1593725Y549434D01*
X1593933Y549184D01*
X1594100Y548767D01*
X1594142Y548392D01*
X1594058Y548017D01*
X1593933Y547767D01*
X1593683Y547517D01*
X1593392Y547350D01*
X1593100Y547267D01*
X1592808D01*
X1592517Y547350D01*
X1592267Y547475D01*
X1592058Y547642D01*
G01X1590792Y549350D02*
X1590542Y549600D01*
X1590250Y549725D01*
X1589917Y549767D01*
X1589500Y549684D01*
X1589208Y549475D01*
X1589125Y549225D01*
X1589167Y548975D01*
X1589333Y548767D01*
X1590167Y548350D01*
X1590542Y548059D01*
X1590792Y547642D01*
X1590875Y547267D01*
X1589125D01*
G01X1587733Y549767D02*
Y547267D01*
X1586067D01*
G01X1583300D02*
Y549767D01*
X1584842Y547975D01*
X1582758D01*
G01X1581617Y547642D02*
X1581367Y547434D01*
X1581075Y547309D01*
X1580700Y547267D01*
X1580325Y547350D01*
X1580033Y547517D01*
X1579825Y547809D01*
X1579783Y548142D01*
X1579867Y548475D01*
X1580075Y548684D01*
X1580367Y548850D01*
X1580658Y548892D01*
X1580950Y548850D01*
X1581325Y548684D01*
X1581200Y549767D01*
X1580075D01*
G01X1592483Y553159D02*
X1592733Y553284D01*
X1593025Y553367D01*
X1593358D01*
X1593733Y553242D01*
X1594025Y553034D01*
X1594233Y552784D01*
X1594400Y552367D01*
X1594442Y551992D01*
X1594358Y551617D01*
X1594233Y551367D01*
X1593983Y551117D01*
X1593692Y550950D01*
X1593400Y550867D01*
X1593108D01*
X1592817Y550950D01*
X1592567Y551075D01*
X1592358Y551242D01*
G01X1591092Y552950D02*
X1590842Y553200D01*
X1590550Y553325D01*
X1590217Y553367D01*
X1589800Y553284D01*
X1589508Y553075D01*
X1589425Y552825D01*
X1589467Y552575D01*
X1589633Y552367D01*
X1590467Y551950D01*
X1590842Y551659D01*
X1591092Y551242D01*
X1591175Y550867D01*
X1589425D01*
G01X1588033Y553367D02*
Y550867D01*
X1586367D01*
G01X1585017Y551367D02*
X1584767Y551075D01*
X1584433Y550909D01*
X1584058Y550867D01*
X1583725Y550909D01*
X1583392Y551117D01*
X1583183Y551367D01*
X1583142Y551617D01*
X1583225Y551909D01*
X1583517Y552117D01*
X1583808Y552200D01*
X1584183D01*
G01X1583808D02*
X1583558Y552325D01*
X1583350Y552534D01*
X1583267Y552784D01*
X1583350Y553034D01*
X1583558Y553242D01*
X1583933Y553367D01*
X1584308Y553325D01*
X1584683Y553159D01*
G01X1581792Y552950D02*
X1581542Y553200D01*
X1581250Y553325D01*
X1580917Y553367D01*
X1580500Y553284D01*
X1580208Y553075D01*
X1580125Y552825D01*
X1580167Y552575D01*
X1580333Y552367D01*
X1581167Y551950D01*
X1581542Y551659D01*
X1581792Y551242D01*
X1581875Y550867D01*
X1580125D01*
G01X1597733Y571667D02*
Y574167D01*
X1596692D01*
X1596358Y574042D01*
X1596150Y573875D01*
X1596067Y573542D01*
X1596150Y573209D01*
X1596400Y573000D01*
X1596692Y572875D01*
X1597733D01*
G01X1596692D02*
X1596067Y571667D01*
G01X1594592Y573750D02*
X1594342Y574000D01*
X1594050Y574125D01*
X1593717Y574167D01*
X1593300Y574084D01*
X1593008Y573875D01*
X1592925Y573625D01*
X1592967Y573375D01*
X1593133Y573167D01*
X1593967Y572750D01*
X1594342Y572459D01*
X1594592Y572042D01*
X1594675Y571667D01*
X1592925D01*
G01X1591533Y574167D02*
Y571667D01*
X1589867D01*
G01X1588392Y573750D02*
X1588142Y574000D01*
X1587850Y574125D01*
X1587517Y574167D01*
X1587100Y574084D01*
X1586808Y573875D01*
X1586725Y573625D01*
X1586767Y573375D01*
X1586933Y573167D01*
X1587767Y572750D01*
X1588142Y572459D01*
X1588392Y572042D01*
X1588475Y571667D01*
X1586725D01*
G01X1584500Y574167D02*
X1584833Y574084D01*
X1585083Y573875D01*
X1585250Y573625D01*
X1585375Y573292D01*
X1585417Y572917D01*
X1585375Y572542D01*
X1585250Y572209D01*
X1585083Y571959D01*
X1584833Y571750D01*
X1584500Y571667D01*
X1584167Y571750D01*
X1583917Y571959D01*
X1583750Y572209D01*
X1583625Y572542D01*
X1583583Y572917D01*
X1583625Y573292D01*
X1583750Y573625D01*
X1583917Y573875D01*
X1584167Y574084D01*
X1584500Y574167D01*
G01X1579767Y570167D02*
X1582267D01*
Y571208D01*
X1582142Y571542D01*
X1581975Y571750D01*
X1581642Y571833D01*
X1581309Y571750D01*
X1581100Y571500D01*
X1580975Y571208D01*
Y570167D01*
G01Y571208D02*
X1579767Y571833D01*
G01X1581850Y573308D02*
X1582100Y573558D01*
X1582225Y573850D01*
X1582267Y574183D01*
X1582184Y574600D01*
X1581975Y574892D01*
X1581725Y574975D01*
X1581475Y574933D01*
X1581267Y574767D01*
X1580850Y573933D01*
X1580559Y573558D01*
X1580142Y573308D01*
X1579767Y573225D01*
Y574975D01*
G01X1582267Y576367D02*
X1579767D01*
Y578033D01*
G01Y580300D02*
X1582267D01*
X1581767Y579800D01*
G01X1579767D02*
Y580800D01*
G01X1580059Y582692D02*
X1579850Y582983D01*
X1579767Y583317D01*
X1579850Y583650D01*
X1580100Y583942D01*
X1580475Y584150D01*
X1580850Y584233D01*
X1581309D01*
X1581684Y584150D01*
X1582017Y583942D01*
X1582184Y583692D01*
X1582267Y583400D01*
X1582184Y583067D01*
X1582017Y582817D01*
X1581767Y582650D01*
X1581434Y582567D01*
X1581142Y582650D01*
X1580850Y582858D01*
X1580684Y583108D01*
X1580642Y583400D01*
X1580725Y583733D01*
X1580934Y583983D01*
X1581309Y584233D01*
G01X1547783Y585000D02*
Y587500D01*
X1546742D01*
X1546408Y587375D01*
X1546200Y587208D01*
X1546117Y586875D01*
X1546200Y586542D01*
X1546450Y586333D01*
X1546742Y586208D01*
X1547783D01*
G01X1546742D02*
X1546117Y585000D01*
G01X1544642Y587083D02*
X1544392Y587333D01*
X1544100Y587458D01*
X1543767Y587500D01*
X1543350Y587417D01*
X1543058Y587208D01*
X1542975Y586958D01*
X1543017Y586708D01*
X1543183Y586500D01*
X1544017Y586083D01*
X1544392Y585792D01*
X1544642Y585375D01*
X1544725Y585000D01*
X1542975D01*
G01X1541583Y587500D02*
Y585000D01*
X1539917D01*
G01X1537650D02*
Y587500D01*
X1538150Y587000D01*
G01Y585000D02*
X1537150D01*
G01X1534550Y587500D02*
X1534883Y587417D01*
X1535133Y587208D01*
X1535300Y586958D01*
X1535425Y586625D01*
X1535467Y586250D01*
X1535425Y585875D01*
X1535300Y585542D01*
X1535133Y585292D01*
X1534883Y585083D01*
X1534550Y585000D01*
X1534217Y585083D01*
X1533967Y585292D01*
X1533800Y585542D01*
X1533675Y585875D01*
X1533633Y586250D01*
X1533675Y586625D01*
X1533800Y586958D01*
X1533967Y587208D01*
X1534217Y587417D01*
X1534550Y587500D01*
G01X1570877Y586942D02*
Y589442D01*
X1569836D01*
X1569502Y589317D01*
X1569294Y589150D01*
X1569211Y588817D01*
X1569294Y588484D01*
X1569544Y588275D01*
X1569836Y588150D01*
X1570877D01*
G01X1569836D02*
X1569211Y586942D01*
G01X1567736Y589025D02*
X1567486Y589275D01*
X1567194Y589400D01*
X1566861Y589442D01*
X1566444Y589359D01*
X1566152Y589150D01*
X1566069Y588900D01*
X1566111Y588650D01*
X1566277Y588442D01*
X1567111Y588025D01*
X1567486Y587734D01*
X1567736Y587317D01*
X1567819Y586942D01*
X1566069D01*
G01X1564677Y589442D02*
Y586942D01*
X1563011D01*
G01X1560744D02*
Y589442D01*
X1561244Y588942D01*
G01Y586942D02*
X1560244D01*
G01X1557144D02*
Y589442D01*
X1558686Y587650D01*
X1556602D01*
G01X1531632Y529596D02*
X1531757Y529346D01*
X1531840Y529054D01*
Y528721D01*
X1531715Y528346D01*
X1531507Y528054D01*
X1531257Y527846D01*
X1530840Y527679D01*
X1530465Y527637D01*
X1530090Y527721D01*
X1529840Y527846D01*
X1529590Y528096D01*
X1529423Y528387D01*
X1529340Y528679D01*
Y528971D01*
X1529423Y529262D01*
X1529548Y529512D01*
X1529715Y529721D01*
G01X1529840Y530862D02*
X1529548Y531112D01*
X1529382Y531446D01*
X1529340Y531821D01*
X1529382Y532154D01*
X1529590Y532487D01*
X1529840Y532696D01*
X1530090Y532737D01*
X1530382Y532654D01*
X1530590Y532362D01*
X1530673Y532071D01*
Y531696D01*
G01Y532071D02*
X1530798Y532321D01*
X1531007Y532529D01*
X1531257Y532612D01*
X1531507Y532529D01*
X1531715Y532321D01*
X1531840Y531946D01*
X1531798Y531571D01*
X1531632Y531196D01*
G01X1529340Y533796D02*
X1531840D01*
X1529757Y534879D01*
X1531840Y535962D01*
X1529340D01*
G01Y537979D02*
X1531840D01*
X1531340Y537479D01*
G01X1529340D02*
Y538479D01*
G01Y540996D02*
X1529882Y541079D01*
X1530340Y541204D01*
X1530757Y541371D01*
X1531215Y541579D01*
X1531840Y541912D01*
Y540246D01*
G01X1539393Y529018D02*
X1539518Y528768D01*
X1539601Y528476D01*
Y528143D01*
X1539476Y527768D01*
X1539268Y527476D01*
X1539018Y527268D01*
X1538601Y527101D01*
X1538226Y527059D01*
X1537851Y527143D01*
X1537601Y527268D01*
X1537351Y527518D01*
X1537184Y527809D01*
X1537101Y528101D01*
Y528393D01*
X1537184Y528684D01*
X1537309Y528934D01*
X1537476Y529143D01*
G01X1537601Y530284D02*
X1537309Y530534D01*
X1537143Y530868D01*
X1537101Y531243D01*
X1537143Y531576D01*
X1537351Y531909D01*
X1537601Y532118D01*
X1537851Y532159D01*
X1538143Y532076D01*
X1538351Y531784D01*
X1538434Y531493D01*
Y531118D01*
G01Y531493D02*
X1538559Y531743D01*
X1538768Y531951D01*
X1539018Y532034D01*
X1539268Y531951D01*
X1539476Y531743D01*
X1539601Y531368D01*
X1539559Y530993D01*
X1539393Y530618D01*
G01X1539601Y533468D02*
X1537101D01*
Y535134D01*
G01X1539184Y536609D02*
X1539434Y536859D01*
X1539559Y537151D01*
X1539601Y537484D01*
X1539518Y537901D01*
X1539309Y538193D01*
X1539059Y538276D01*
X1538809Y538234D01*
X1538601Y538068D01*
X1538184Y537234D01*
X1537893Y536859D01*
X1537476Y536609D01*
X1537101Y536526D01*
Y538276D01*
G01Y540418D02*
X1537643Y540501D01*
X1538101Y540626D01*
X1538518Y540793D01*
X1538976Y541001D01*
X1539601Y541334D01*
Y539668D01*
G01X1550726Y529118D02*
X1550851Y528868D01*
X1550934Y528576D01*
Y528243D01*
X1550809Y527868D01*
X1550601Y527576D01*
X1550351Y527368D01*
X1549934Y527201D01*
X1549559Y527159D01*
X1549184Y527243D01*
X1548934Y527368D01*
X1548684Y527618D01*
X1548517Y527909D01*
X1548434Y528201D01*
Y528493D01*
X1548517Y528784D01*
X1548642Y529034D01*
X1548809Y529243D01*
G01X1548934Y530384D02*
X1548642Y530634D01*
X1548476Y530968D01*
X1548434Y531343D01*
X1548476Y531676D01*
X1548684Y532009D01*
X1548934Y532218D01*
X1549184Y532259D01*
X1549476Y532176D01*
X1549684Y531884D01*
X1549767Y531593D01*
Y531218D01*
G01Y531593D02*
X1549892Y531843D01*
X1550101Y532051D01*
X1550351Y532134D01*
X1550601Y532051D01*
X1550809Y531843D01*
X1550934Y531468D01*
X1550892Y531093D01*
X1550726Y530718D01*
G01X1550934Y533568D02*
X1548434D01*
Y535234D01*
G01X1550517Y536709D02*
X1550767Y536959D01*
X1550892Y537251D01*
X1550934Y537584D01*
X1550851Y538001D01*
X1550642Y538293D01*
X1550392Y538376D01*
X1550142Y538334D01*
X1549934Y538168D01*
X1549517Y537334D01*
X1549226Y536959D01*
X1548809Y536709D01*
X1548434Y536626D01*
Y538376D01*
G01Y541101D02*
X1550934D01*
X1549142Y539559D01*
Y541643D01*
G01X1547026Y529018D02*
X1547151Y528768D01*
X1547234Y528476D01*
Y528143D01*
X1547109Y527768D01*
X1546901Y527476D01*
X1546651Y527268D01*
X1546234Y527101D01*
X1545859Y527059D01*
X1545484Y527143D01*
X1545234Y527268D01*
X1544984Y527518D01*
X1544817Y527809D01*
X1544734Y528101D01*
Y528393D01*
X1544817Y528684D01*
X1544942Y528934D01*
X1545109Y529143D01*
G01X1545234Y530284D02*
X1544942Y530534D01*
X1544776Y530868D01*
X1544734Y531243D01*
X1544776Y531576D01*
X1544984Y531909D01*
X1545234Y532118D01*
X1545484Y532159D01*
X1545776Y532076D01*
X1545984Y531784D01*
X1546067Y531493D01*
Y531118D01*
G01Y531493D02*
X1546192Y531743D01*
X1546401Y531951D01*
X1546651Y532034D01*
X1546901Y531951D01*
X1547109Y531743D01*
X1547234Y531368D01*
X1547192Y530993D01*
X1547026Y530618D01*
G01X1547234Y533468D02*
X1544734D01*
Y535134D01*
G01X1546817Y536609D02*
X1547067Y536859D01*
X1547192Y537151D01*
X1547234Y537484D01*
X1547151Y537901D01*
X1546942Y538193D01*
X1546692Y538276D01*
X1546442Y538234D01*
X1546234Y538068D01*
X1545817Y537234D01*
X1545526Y536859D01*
X1545109Y536609D01*
X1544734Y536526D01*
Y538276D01*
G01X1545109Y539584D02*
X1544901Y539834D01*
X1544776Y540126D01*
X1544734Y540501D01*
X1544817Y540876D01*
X1544984Y541168D01*
X1545276Y541376D01*
X1545609Y541418D01*
X1545942Y541334D01*
X1546151Y541126D01*
X1546317Y540834D01*
X1546359Y540543D01*
X1546317Y540251D01*
X1546151Y539876D01*
X1547234Y540001D01*
Y541126D01*
G01X1543293Y528918D02*
X1543418Y528668D01*
X1543501Y528376D01*
Y528043D01*
X1543376Y527668D01*
X1543168Y527376D01*
X1542918Y527168D01*
X1542501Y527001D01*
X1542126Y526959D01*
X1541751Y527043D01*
X1541501Y527168D01*
X1541251Y527418D01*
X1541084Y527709D01*
X1541001Y528001D01*
Y528293D01*
X1541084Y528584D01*
X1541209Y528834D01*
X1541376Y529043D01*
G01X1541501Y530184D02*
X1541209Y530434D01*
X1541043Y530768D01*
X1541001Y531143D01*
X1541043Y531476D01*
X1541251Y531809D01*
X1541501Y532018D01*
X1541751Y532059D01*
X1542043Y531976D01*
X1542251Y531684D01*
X1542334Y531393D01*
Y531018D01*
G01Y531393D02*
X1542459Y531643D01*
X1542668Y531851D01*
X1542918Y531934D01*
X1543168Y531851D01*
X1543376Y531643D01*
X1543501Y531268D01*
X1543459Y530893D01*
X1543293Y530518D01*
G01X1543501Y533368D02*
X1541001D01*
Y535034D01*
G01X1543084Y536509D02*
X1543334Y536759D01*
X1543459Y537051D01*
X1543501Y537384D01*
X1543418Y537801D01*
X1543209Y538093D01*
X1542959Y538176D01*
X1542709Y538134D01*
X1542501Y537968D01*
X1542084Y537134D01*
X1541793Y536759D01*
X1541376Y536509D01*
X1541001Y536426D01*
Y538176D01*
G01X1542043Y539609D02*
X1542334Y539901D01*
X1542501Y540151D01*
X1542584Y540484D01*
X1542501Y540776D01*
X1542334Y540984D01*
X1542084Y541151D01*
X1541793Y541193D01*
X1541543Y541151D01*
X1541293Y540984D01*
X1541084Y540734D01*
X1541001Y540443D01*
X1541084Y540109D01*
X1541334Y539818D01*
X1541709Y539651D01*
X1542126Y539609D01*
X1542668Y539693D01*
X1542959Y539818D01*
X1543251Y540026D01*
X1543459Y540318D01*
X1543501Y540609D01*
X1543418Y540901D01*
X1543209Y541109D01*
G01X1572509Y567393D02*
X1572634Y567143D01*
X1572717Y566851D01*
Y566518D01*
X1572592Y566143D01*
X1572384Y565851D01*
X1572134Y565643D01*
X1571717Y565476D01*
X1571342Y565434D01*
X1570967Y565518D01*
X1570717Y565643D01*
X1570467Y565893D01*
X1570300Y566184D01*
X1570217Y566476D01*
Y566768D01*
X1570300Y567059D01*
X1570425Y567309D01*
X1570592Y567518D01*
G01X1570217Y569493D02*
X1570759Y569576D01*
X1571217Y569701D01*
X1571634Y569868D01*
X1572092Y570076D01*
X1572717Y570409D01*
Y568743D01*
G01X1571550Y573009D02*
X1571675Y573176D01*
X1571884Y573301D01*
X1572175Y573384D01*
X1572425Y573301D01*
X1572592Y573134D01*
X1572717Y572843D01*
Y571718D01*
X1570217D01*
Y573093D01*
X1570384Y573384D01*
X1570634Y573551D01*
X1570925Y573634D01*
X1571217Y573551D01*
X1571467Y573301D01*
X1571550Y573009D01*
Y571718D01*
G01X1570217Y575776D02*
X1572717D01*
X1572217Y575276D01*
G01X1570217D02*
Y576276D01*
G01Y578793D02*
X1570759Y578876D01*
X1571217Y579001D01*
X1571634Y579168D01*
X1572092Y579376D01*
X1572717Y579709D01*
Y578043D01*
G01X1576538Y567275D02*
X1576663Y567025D01*
X1576746Y566733D01*
Y566400D01*
X1576621Y566025D01*
X1576413Y565733D01*
X1576163Y565525D01*
X1575746Y565358D01*
X1575371Y565316D01*
X1574996Y565400D01*
X1574746Y565525D01*
X1574496Y565775D01*
X1574329Y566066D01*
X1574246Y566358D01*
Y566650D01*
X1574329Y566941D01*
X1574454Y567191D01*
X1574621Y567400D01*
G01X1574246Y569375D02*
X1574788Y569458D01*
X1575246Y569583D01*
X1575663Y569750D01*
X1576121Y569958D01*
X1576746Y570291D01*
Y568625D01*
G01X1575579Y572891D02*
X1575704Y573058D01*
X1575913Y573183D01*
X1576204Y573266D01*
X1576454Y573183D01*
X1576621Y573016D01*
X1576746Y572725D01*
Y571600D01*
X1574246D01*
Y572975D01*
X1574413Y573266D01*
X1574663Y573433D01*
X1574954Y573516D01*
X1575246Y573433D01*
X1575496Y573183D01*
X1575579Y572891D01*
Y571600D01*
G01X1574246Y575658D02*
X1576746D01*
X1576246Y575158D01*
G01X1574246D02*
Y576158D01*
G01X1575288Y577966D02*
X1575579Y578258D01*
X1575746Y578508D01*
X1575829Y578841D01*
X1575746Y579133D01*
X1575579Y579341D01*
X1575329Y579508D01*
X1575038Y579550D01*
X1574788Y579508D01*
X1574538Y579341D01*
X1574329Y579091D01*
X1574246Y578800D01*
X1574329Y578466D01*
X1574579Y578175D01*
X1574954Y578008D01*
X1575371Y577966D01*
X1575913Y578050D01*
X1576204Y578175D01*
X1576496Y578383D01*
X1576704Y578675D01*
X1576746Y578966D01*
X1576663Y579258D01*
X1576454Y579466D01*
G01X1542833Y590892D02*
X1543083Y591017D01*
X1543375Y591100D01*
X1543708D01*
X1544083Y590975D01*
X1544375Y590767D01*
X1544583Y590517D01*
X1544750Y590100D01*
X1544792Y589725D01*
X1544708Y589350D01*
X1544583Y589100D01*
X1544333Y588850D01*
X1544042Y588683D01*
X1543750Y588600D01*
X1543458D01*
X1543167Y588683D01*
X1542917Y588808D01*
X1542708Y588975D01*
G01X1540150Y588600D02*
Y591100D01*
X1541692Y589308D01*
X1539608D01*
G01X1538800Y591100D02*
X1538217Y588600D01*
X1537550Y591100D01*
X1536883Y588600D01*
X1536300Y591100D01*
G01X1535367Y589100D02*
X1535117Y588808D01*
X1534783Y588642D01*
X1534408Y588600D01*
X1534075Y588642D01*
X1533742Y588850D01*
X1533533Y589100D01*
X1533492Y589350D01*
X1533575Y589642D01*
X1533867Y589850D01*
X1534158Y589933D01*
X1534533D01*
G01X1534158D02*
X1533908Y590058D01*
X1533700Y590267D01*
X1533617Y590517D01*
X1533700Y590767D01*
X1533908Y590975D01*
X1534283Y591100D01*
X1534658Y591058D01*
X1535033Y590892D01*
G01X1535693Y529118D02*
X1535818Y528868D01*
X1535901Y528576D01*
Y528243D01*
X1535776Y527868D01*
X1535568Y527576D01*
X1535318Y527368D01*
X1534901Y527201D01*
X1534526Y527159D01*
X1534151Y527243D01*
X1533901Y527368D01*
X1533651Y527618D01*
X1533484Y527909D01*
X1533401Y528201D01*
Y528493D01*
X1533484Y528784D01*
X1533609Y529034D01*
X1533776Y529243D01*
G01X1533901Y530384D02*
X1533609Y530634D01*
X1533443Y530968D01*
X1533401Y531343D01*
X1533443Y531676D01*
X1533651Y532009D01*
X1533901Y532218D01*
X1534151Y532259D01*
X1534443Y532176D01*
X1534651Y531884D01*
X1534734Y531593D01*
Y531218D01*
G01Y531593D02*
X1534859Y531843D01*
X1535068Y532051D01*
X1535318Y532134D01*
X1535568Y532051D01*
X1535776Y531843D01*
X1535901Y531468D01*
X1535859Y531093D01*
X1535693Y530718D01*
G01X1533401Y533318D02*
X1535901D01*
X1533818Y534401D01*
X1535901Y535484D01*
X1533401D01*
G01Y537501D02*
X1535901D01*
X1535401Y537001D01*
G01X1533401D02*
Y538001D01*
G01X1533693Y539893D02*
X1533484Y540184D01*
X1533401Y540518D01*
X1533484Y540851D01*
X1533734Y541143D01*
X1534109Y541351D01*
X1534484Y541434D01*
X1534943D01*
X1535318Y541351D01*
X1535651Y541143D01*
X1535818Y540893D01*
X1535901Y540601D01*
X1535818Y540268D01*
X1535651Y540018D01*
X1535401Y539851D01*
X1535068Y539768D01*
X1534776Y539851D01*
X1534484Y540059D01*
X1534318Y540309D01*
X1534276Y540601D01*
X1534359Y540934D01*
X1534568Y541184D01*
X1534943Y541434D01*
G01X1528000Y582500D02*
Y559925D01*
G01X1563089Y529774D02*
X1563214Y529524D01*
X1563297Y529232D01*
Y528899D01*
X1563172Y528524D01*
X1562964Y528232D01*
X1562714Y528024D01*
X1562297Y527857D01*
X1561922Y527815D01*
X1561547Y527899D01*
X1561297Y528024D01*
X1561047Y528274D01*
X1560880Y528565D01*
X1560797Y528857D01*
Y529149D01*
X1560880Y529440D01*
X1561005Y529690D01*
X1561172Y529899D01*
G01X1562880Y531165D02*
X1563130Y531415D01*
X1563255Y531707D01*
X1563297Y532040D01*
X1563214Y532457D01*
X1563005Y532749D01*
X1562755Y532832D01*
X1562505Y532790D01*
X1562297Y532624D01*
X1561880Y531790D01*
X1561589Y531415D01*
X1561172Y531165D01*
X1560797Y531082D01*
Y532832D01*
G01X1563297Y534224D02*
X1560797D01*
Y535890D01*
G01Y538657D02*
X1563297D01*
X1561505Y537115D01*
Y539199D01*
G01X1561839Y540465D02*
X1562130Y540757D01*
X1562297Y541007D01*
X1562380Y541340D01*
X1562297Y541632D01*
X1562130Y541840D01*
X1561880Y542007D01*
X1561589Y542049D01*
X1561339Y542007D01*
X1561089Y541840D01*
X1560880Y541590D01*
X1560797Y541299D01*
X1560880Y540965D01*
X1561130Y540674D01*
X1561505Y540507D01*
X1561922Y540465D01*
X1562464Y540549D01*
X1562755Y540674D01*
X1563047Y540882D01*
X1563255Y541174D01*
X1563297Y541465D01*
X1563214Y541757D01*
X1563005Y541965D01*
G01X1553030Y543606D02*
X1549239D01*
Y556402D01*
X1553030D01*
G01X1565630Y543606D02*
X1569192D01*
Y556402D01*
X1565630D01*
G01X1568330Y578970D02*
X1565632D01*
G01X1550330D02*
X1553025D01*
G01X1550330D02*
Y556398D01*
G01X1568330Y578970D02*
Y556395D01*
G01X1558433Y529927D02*
X1558558Y529677D01*
X1558641Y529385D01*
Y529052D01*
X1558516Y528677D01*
X1558308Y528385D01*
X1558058Y528177D01*
X1557641Y528010D01*
X1557266Y527968D01*
X1556891Y528052D01*
X1556641Y528177D01*
X1556391Y528427D01*
X1556224Y528718D01*
X1556141Y529010D01*
Y529302D01*
X1556224Y529593D01*
X1556349Y529843D01*
X1556516Y530052D01*
G01X1558224Y531318D02*
X1558474Y531568D01*
X1558599Y531860D01*
X1558641Y532193D01*
X1558558Y532610D01*
X1558349Y532902D01*
X1558099Y532985D01*
X1557849Y532943D01*
X1557641Y532777D01*
X1557224Y531943D01*
X1556933Y531568D01*
X1556516Y531318D01*
X1556141Y531235D01*
Y532985D01*
G01X1558641Y534377D02*
X1556141D01*
Y536043D01*
G01X1558224Y537518D02*
X1558474Y537768D01*
X1558599Y538060D01*
X1558641Y538393D01*
X1558558Y538810D01*
X1558349Y539102D01*
X1558099Y539185D01*
X1557849Y539143D01*
X1557641Y538977D01*
X1557224Y538143D01*
X1556933Y537768D01*
X1556516Y537518D01*
X1556141Y537435D01*
Y539185D01*
G01X1556516Y540493D02*
X1556308Y540743D01*
X1556183Y541035D01*
X1556141Y541410D01*
X1556224Y541785D01*
X1556391Y542077D01*
X1556683Y542285D01*
X1557016Y542327D01*
X1557349Y542243D01*
X1557558Y542035D01*
X1557724Y541743D01*
X1557766Y541452D01*
X1557724Y541160D01*
X1557558Y540785D01*
X1558641Y540910D01*
Y542035D01*
G01X1533810Y543506D02*
X1530019D01*
Y556302D01*
X1533810D01*
G01X1546410Y543506D02*
X1549972D01*
Y556302D01*
X1546410D01*
G01X1549110Y578870D02*
X1546412D01*
G01X1531110D02*
X1533805D01*
G01X1531110D02*
Y556298D01*
G01X1549110Y578870D02*
Y556295D01*
G01X1583767Y595544D02*
Y598044D01*
X1582726D01*
X1582392Y597919D01*
X1582184Y597752D01*
X1582101Y597419D01*
X1582184Y597086D01*
X1582434Y596877D01*
X1582726Y596752D01*
X1583767D01*
G01X1582726D02*
X1582101Y595544D01*
G01X1580626Y597627D02*
X1580376Y597877D01*
X1580084Y598002D01*
X1579751Y598044D01*
X1579334Y597961D01*
X1579042Y597752D01*
X1578959Y597502D01*
X1579001Y597252D01*
X1579167Y597044D01*
X1580001Y596627D01*
X1580376Y596336D01*
X1580626Y595919D01*
X1580709Y595544D01*
X1578959D01*
G01X1577567Y598044D02*
Y595544D01*
X1575901D01*
G01X1573634D02*
Y598044D01*
X1574134Y597544D01*
G01Y595544D02*
X1573134D01*
G01X1570617D02*
X1570534Y596086D01*
X1570409Y596544D01*
X1570242Y596961D01*
X1570034Y597419D01*
X1569701Y598044D01*
X1571367D01*
G01X1600416Y601628D02*
Y604128D01*
X1599375D01*
X1599041Y604003D01*
X1598833Y603836D01*
X1598750Y603503D01*
X1598833Y603170D01*
X1599083Y602961D01*
X1599375Y602836D01*
X1600416D01*
G01X1599375D02*
X1598750Y601628D01*
G01X1597275Y603711D02*
X1597025Y603961D01*
X1596733Y604086D01*
X1596400Y604128D01*
X1595983Y604045D01*
X1595691Y603836D01*
X1595608Y603586D01*
X1595650Y603336D01*
X1595816Y603128D01*
X1596650Y602711D01*
X1597025Y602420D01*
X1597275Y602003D01*
X1597358Y601628D01*
X1595608D01*
G01X1594216Y604128D02*
Y601628D01*
X1592550D01*
G01X1591075Y603711D02*
X1590825Y603961D01*
X1590533Y604086D01*
X1590200Y604128D01*
X1589783Y604045D01*
X1589491Y603836D01*
X1589408Y603586D01*
X1589450Y603336D01*
X1589616Y603128D01*
X1590450Y602711D01*
X1590825Y602420D01*
X1591075Y602003D01*
X1591158Y601628D01*
X1589408D01*
G01X1587975Y602670D02*
X1587683Y602961D01*
X1587433Y603128D01*
X1587100Y603211D01*
X1586808Y603128D01*
X1586600Y602961D01*
X1586433Y602711D01*
X1586391Y602420D01*
X1586433Y602170D01*
X1586600Y601920D01*
X1586850Y601711D01*
X1587141Y601628D01*
X1587475Y601711D01*
X1587766Y601961D01*
X1587933Y602336D01*
X1587975Y602753D01*
X1587891Y603295D01*
X1587766Y603586D01*
X1587558Y603878D01*
X1587266Y604086D01*
X1586975Y604128D01*
X1586683Y604045D01*
X1586475Y603836D01*
G01X1585672Y614700D02*
Y617200D01*
X1584631D01*
X1584297Y617075D01*
X1584089Y616908D01*
X1584006Y616575D01*
X1584089Y616242D01*
X1584339Y616033D01*
X1584631Y615908D01*
X1585672D01*
G01X1584631D02*
X1584006Y614700D01*
G01X1582531Y616783D02*
X1582281Y617033D01*
X1581989Y617158D01*
X1581656Y617200D01*
X1581239Y617117D01*
X1580947Y616908D01*
X1580864Y616658D01*
X1580906Y616408D01*
X1581072Y616200D01*
X1581906Y615783D01*
X1582281Y615492D01*
X1582531Y615075D01*
X1582614Y614700D01*
X1580864D01*
G01X1579472Y617200D02*
Y614700D01*
X1577806D01*
G01X1576331Y616783D02*
X1576081Y617033D01*
X1575789Y617158D01*
X1575456Y617200D01*
X1575039Y617117D01*
X1574747Y616908D01*
X1574664Y616658D01*
X1574706Y616408D01*
X1574872Y616200D01*
X1575706Y615783D01*
X1576081Y615492D01*
X1576331Y615075D01*
X1576414Y614700D01*
X1574664D01*
G01X1571939D02*
Y617200D01*
X1573481Y615408D01*
X1571397D01*
G01X1570038Y607275D02*
Y609775D01*
X1568997D01*
X1568663Y609650D01*
X1568455Y609483D01*
X1568372Y609150D01*
X1568455Y608817D01*
X1568705Y608608D01*
X1568997Y608483D01*
X1570038D01*
G01X1568997D02*
X1568372Y607275D01*
G01X1566897Y609358D02*
X1566647Y609608D01*
X1566355Y609733D01*
X1566022Y609775D01*
X1565605Y609692D01*
X1565313Y609483D01*
X1565230Y609233D01*
X1565272Y608983D01*
X1565438Y608775D01*
X1566272Y608358D01*
X1566647Y608067D01*
X1566897Y607650D01*
X1566980Y607275D01*
X1565230D01*
G01X1563838Y609775D02*
Y607275D01*
X1562172D01*
G01X1560613Y607567D02*
X1560322Y607358D01*
X1559988Y607275D01*
X1559655Y607358D01*
X1559363Y607608D01*
X1559155Y607983D01*
X1559072Y608358D01*
Y608817D01*
X1559155Y609192D01*
X1559363Y609525D01*
X1559613Y609692D01*
X1559905Y609775D01*
X1560238Y609692D01*
X1560488Y609525D01*
X1560655Y609275D01*
X1560738Y608942D01*
X1560655Y608650D01*
X1560447Y608358D01*
X1560197Y608192D01*
X1559905Y608150D01*
X1559572Y608233D01*
X1559322Y608442D01*
X1559072Y608817D01*
G01X1577483Y611100D02*
Y613600D01*
X1576442D01*
X1576108Y613475D01*
X1575900Y613308D01*
X1575817Y612975D01*
X1575900Y612642D01*
X1576150Y612433D01*
X1576442Y612308D01*
X1577483D01*
G01X1576442D02*
X1575817Y611100D01*
G01X1574342Y613183D02*
X1574092Y613433D01*
X1573800Y613558D01*
X1573467Y613600D01*
X1573050Y613517D01*
X1572758Y613308D01*
X1572675Y613058D01*
X1572717Y612808D01*
X1572883Y612600D01*
X1573717Y612183D01*
X1574092Y611892D01*
X1574342Y611475D01*
X1574425Y611100D01*
X1572675D01*
G01X1571283Y613600D02*
Y611100D01*
X1569617D01*
G01X1567350D02*
X1567058Y611142D01*
X1566725Y611267D01*
X1566517Y611475D01*
X1566433Y611767D01*
X1566517Y612058D01*
X1566767Y612308D01*
X1567142Y612433D01*
X1567558D01*
X1567808Y612517D01*
X1568017Y612725D01*
X1568100Y613017D01*
X1567975Y613308D01*
X1567683Y613517D01*
X1567350Y613600D01*
X1567017Y613517D01*
X1566725Y613308D01*
X1566600Y613017D01*
X1566683Y612725D01*
X1566892Y612517D01*
X1567142Y612433D01*
X1567558D01*
X1567933Y612308D01*
X1568183Y612058D01*
X1568267Y611767D01*
X1568183Y611475D01*
X1567975Y611267D01*
X1567642Y611142D01*
X1567350Y611100D01*
G01X1600372Y595647D02*
X1600622Y595772D01*
X1600914Y595855D01*
X1601247D01*
X1601622Y595730D01*
X1601914Y595522D01*
X1602122Y595272D01*
X1602289Y594855D01*
X1602331Y594480D01*
X1602247Y594105D01*
X1602122Y593855D01*
X1601872Y593605D01*
X1601581Y593438D01*
X1601289Y593355D01*
X1600997D01*
X1600706Y593438D01*
X1600456Y593563D01*
X1600247Y593730D01*
G01X1598981Y595438D02*
X1598731Y595688D01*
X1598439Y595813D01*
X1598106Y595855D01*
X1597689Y595772D01*
X1597397Y595563D01*
X1597314Y595313D01*
X1597356Y595063D01*
X1597522Y594855D01*
X1598356Y594438D01*
X1598731Y594147D01*
X1598981Y593730D01*
X1599064Y593355D01*
X1597314D01*
G01X1595922Y595855D02*
Y593355D01*
X1594256D01*
G01X1591989D02*
Y595855D01*
X1592489Y595355D01*
G01Y593355D02*
X1591489D01*
G01X1589681Y594397D02*
X1589389Y594688D01*
X1589139Y594855D01*
X1588806Y594938D01*
X1588514Y594855D01*
X1588306Y594688D01*
X1588139Y594438D01*
X1588097Y594147D01*
X1588139Y593897D01*
X1588306Y593647D01*
X1588556Y593438D01*
X1588847Y593355D01*
X1589181Y593438D01*
X1589472Y593688D01*
X1589639Y594063D01*
X1589681Y594480D01*
X1589597Y595022D01*
X1589472Y595313D01*
X1589264Y595605D01*
X1588972Y595813D01*
X1588681Y595855D01*
X1588389Y595772D01*
X1588181Y595563D01*
G01X1566254Y597251D02*
X1566504Y597376D01*
X1566796Y597459D01*
X1567129D01*
X1567504Y597334D01*
X1567796Y597126D01*
X1568004Y596876D01*
X1568171Y596459D01*
X1568213Y596084D01*
X1568129Y595709D01*
X1568004Y595459D01*
X1567754Y595209D01*
X1567463Y595042D01*
X1567171Y594959D01*
X1566879D01*
X1566588Y595042D01*
X1566338Y595167D01*
X1566129Y595334D01*
G01X1564863Y597042D02*
X1564613Y597292D01*
X1564321Y597417D01*
X1563988Y597459D01*
X1563571Y597376D01*
X1563279Y597167D01*
X1563196Y596917D01*
X1563238Y596667D01*
X1563404Y596459D01*
X1564238Y596042D01*
X1564613Y595751D01*
X1564863Y595334D01*
X1564946Y594959D01*
X1563196D01*
G01X1561804Y597459D02*
Y594959D01*
X1560138D01*
G01X1557871D02*
Y597459D01*
X1558371Y596959D01*
G01Y594959D02*
X1557371D01*
G01X1554771D02*
Y597459D01*
X1555271Y596959D01*
G01Y594959D02*
X1554271D01*
G01X1575220Y605953D02*
X1575470Y606078D01*
X1575762Y606161D01*
X1576095D01*
X1576470Y606036D01*
X1576762Y605828D01*
X1576970Y605578D01*
X1577137Y605161D01*
X1577179Y604786D01*
X1577095Y604411D01*
X1576970Y604161D01*
X1576720Y603911D01*
X1576429Y603744D01*
X1576137Y603661D01*
X1575845D01*
X1575554Y603744D01*
X1575304Y603869D01*
X1575095Y604036D01*
G01X1573829Y605744D02*
X1573579Y605994D01*
X1573287Y606119D01*
X1572954Y606161D01*
X1572537Y606078D01*
X1572245Y605869D01*
X1572162Y605619D01*
X1572204Y605369D01*
X1572370Y605161D01*
X1573204Y604744D01*
X1573579Y604453D01*
X1573829Y604036D01*
X1573912Y603661D01*
X1572162D01*
G01X1570770Y606161D02*
Y603661D01*
X1569104D01*
G01X1566837D02*
X1566545Y603703D01*
X1566212Y603828D01*
X1566004Y604036D01*
X1565920Y604328D01*
X1566004Y604619D01*
X1566254Y604869D01*
X1566629Y604994D01*
X1567045D01*
X1567295Y605078D01*
X1567504Y605286D01*
X1567587Y605578D01*
X1567462Y605869D01*
X1567170Y606078D01*
X1566837Y606161D01*
X1566504Y606078D01*
X1566212Y605869D01*
X1566087Y605578D01*
X1566170Y605286D01*
X1566379Y605078D01*
X1566629Y604994D01*
X1567045D01*
X1567420Y604869D01*
X1567670Y604619D01*
X1567754Y604328D01*
X1567670Y604036D01*
X1567462Y603828D01*
X1567129Y603703D01*
X1566837Y603661D01*
G01X1545391Y624070D02*
X1545641Y624195D01*
X1545933Y624278D01*
X1546266D01*
X1546641Y624153D01*
X1546933Y623945D01*
X1547141Y623695D01*
X1547308Y623278D01*
X1547350Y622903D01*
X1547266Y622528D01*
X1547141Y622278D01*
X1546891Y622028D01*
X1546600Y621861D01*
X1546308Y621778D01*
X1546016D01*
X1545725Y621861D01*
X1545475Y621986D01*
X1545266Y622153D01*
G01X1544000Y623861D02*
X1543750Y624111D01*
X1543458Y624236D01*
X1543125Y624278D01*
X1542708Y624195D01*
X1542416Y623986D01*
X1542333Y623736D01*
X1542375Y623486D01*
X1542541Y623278D01*
X1543375Y622861D01*
X1543750Y622570D01*
X1544000Y622153D01*
X1544083Y621778D01*
X1542333D01*
G01X1540941Y624278D02*
Y621778D01*
X1539275D01*
G01X1537800Y623861D02*
X1537550Y624111D01*
X1537258Y624236D01*
X1536925Y624278D01*
X1536508Y624195D01*
X1536216Y623986D01*
X1536133Y623736D01*
X1536175Y623486D01*
X1536341Y623278D01*
X1537175Y622861D01*
X1537550Y622570D01*
X1537800Y622153D01*
X1537883Y621778D01*
X1536133D01*
G01X1548968Y611360D02*
X1549218Y611485D01*
X1549510Y611568D01*
X1549843D01*
X1550218Y611443D01*
X1550510Y611235D01*
X1550718Y610985D01*
X1550885Y610568D01*
X1550927Y610193D01*
X1550843Y609818D01*
X1550718Y609568D01*
X1550468Y609318D01*
X1550177Y609151D01*
X1549885Y609068D01*
X1549593D01*
X1549302Y609151D01*
X1549052Y609276D01*
X1548843Y609443D01*
G01X1546285Y609068D02*
Y611568D01*
X1547827Y609776D01*
X1545743D01*
G01X1544935Y611568D02*
X1544352Y609068D01*
X1543685Y611568D01*
X1543018Y609068D01*
X1542435Y611568D01*
G01X1540085Y609068D02*
Y611568D01*
X1541627Y609776D01*
X1539543D01*
G01X1562933Y622992D02*
X1563183Y623117D01*
X1563475Y623200D01*
X1563808D01*
X1564183Y623075D01*
X1564475Y622867D01*
X1564683Y622617D01*
X1564850Y622200D01*
X1564892Y621825D01*
X1564808Y621450D01*
X1564683Y621200D01*
X1564433Y620950D01*
X1564142Y620783D01*
X1563850Y620700D01*
X1563558D01*
X1563267Y620783D01*
X1563017Y620908D01*
X1562808Y621075D01*
G01X1561542Y620700D02*
Y623200D01*
X1559958D01*
G01X1560542Y621992D02*
X1561542D01*
G01X1558442Y622783D02*
X1558192Y623033D01*
X1557900Y623158D01*
X1557567Y623200D01*
X1557150Y623117D01*
X1556858Y622908D01*
X1556775Y622658D01*
X1556817Y622408D01*
X1556983Y622200D01*
X1557817Y621783D01*
X1558192Y621492D01*
X1558442Y621075D01*
X1558525Y620700D01*
X1556775D01*
G01X1554050D02*
Y623200D01*
X1555592Y621408D01*
X1553508D01*
G01X1580483Y623342D02*
X1580733Y623467D01*
X1581025Y623550D01*
X1581358D01*
X1581733Y623425D01*
X1582025Y623217D01*
X1582233Y622967D01*
X1582400Y622550D01*
X1582442Y622175D01*
X1582358Y621800D01*
X1582233Y621550D01*
X1581983Y621300D01*
X1581692Y621133D01*
X1581400Y621050D01*
X1581108D01*
X1580817Y621133D01*
X1580567Y621258D01*
X1580358Y621425D01*
G01X1579092Y621050D02*
Y623550D01*
X1577508D01*
G01X1578092Y622342D02*
X1579092D01*
G01X1575992Y623133D02*
X1575742Y623383D01*
X1575450Y623508D01*
X1575117Y623550D01*
X1574700Y623467D01*
X1574408Y623258D01*
X1574325Y623008D01*
X1574367Y622758D01*
X1574533Y622550D01*
X1575367Y622133D01*
X1575742Y621842D01*
X1575992Y621425D01*
X1576075Y621050D01*
X1574325D01*
G01X1573017Y621550D02*
X1572767Y621258D01*
X1572433Y621092D01*
X1572058Y621050D01*
X1571725Y621092D01*
X1571392Y621300D01*
X1571183Y621550D01*
X1571142Y621800D01*
X1571225Y622092D01*
X1571517Y622300D01*
X1571808Y622383D01*
X1572183D01*
G01X1571808D02*
X1571558Y622508D01*
X1571350Y622717D01*
X1571267Y622967D01*
X1571350Y623217D01*
X1571558Y623425D01*
X1571933Y623550D01*
X1572308Y623508D01*
X1572683Y623342D01*
G01X1653182Y-14261D02*
Y-11761D01*
X1652141D01*
X1651807Y-11886D01*
X1651599Y-12053D01*
X1651516Y-12386D01*
X1651599Y-12719D01*
X1651849Y-12928D01*
X1652141Y-13053D01*
X1653182D01*
G01X1652141D02*
X1651516Y-14261D01*
G01X1650166Y-13761D02*
X1649916Y-14053D01*
X1649582Y-14219D01*
X1649207Y-14261D01*
X1648874Y-14219D01*
X1648541Y-14011D01*
X1648332Y-13761D01*
X1648291Y-13511D01*
X1648374Y-13219D01*
X1648666Y-13011D01*
X1648957Y-12928D01*
X1649332D01*
G01X1648957D02*
X1648707Y-12803D01*
X1648499Y-12594D01*
X1648416Y-12344D01*
X1648499Y-12094D01*
X1648707Y-11886D01*
X1649082Y-11761D01*
X1649457Y-11803D01*
X1649832Y-11969D01*
G01X1646982Y-14261D02*
Y-11761D01*
X1645982D01*
X1645649Y-11886D01*
X1645399Y-12178D01*
X1645316Y-12511D01*
X1645399Y-12844D01*
X1645607Y-13094D01*
X1645982Y-13219D01*
X1646982D01*
G01X1643966Y-13886D02*
X1643716Y-14094D01*
X1643424Y-14219D01*
X1643049Y-14261D01*
X1642674Y-14178D01*
X1642382Y-14011D01*
X1642174Y-13719D01*
X1642132Y-13386D01*
X1642216Y-13053D01*
X1642424Y-12844D01*
X1642716Y-12678D01*
X1643007Y-12636D01*
X1643299Y-12678D01*
X1643674Y-12844D01*
X1643549Y-11761D01*
X1642424D01*
G01X1639949D02*
X1640282Y-11844D01*
X1640532Y-12053D01*
X1640699Y-12303D01*
X1640824Y-12636D01*
X1640866Y-13011D01*
X1640824Y-13386D01*
X1640699Y-13719D01*
X1640532Y-13969D01*
X1640282Y-14178D01*
X1639949Y-14261D01*
X1639616Y-14178D01*
X1639366Y-13969D01*
X1639199Y-13719D01*
X1639074Y-13386D01*
X1639032Y-13011D01*
X1639074Y-12636D01*
X1639199Y-12303D01*
X1639366Y-12053D01*
X1639616Y-11844D01*
X1639949Y-11761D01*
G01X1653182Y-10761D02*
Y-8261D01*
X1652141D01*
X1651807Y-8386D01*
X1651599Y-8553D01*
X1651516Y-8886D01*
X1651599Y-9219D01*
X1651849Y-9428D01*
X1652141Y-9553D01*
X1653182D01*
G01X1652141D02*
X1651516Y-10761D01*
G01X1650166Y-10261D02*
X1649916Y-10553D01*
X1649582Y-10719D01*
X1649207Y-10761D01*
X1648874Y-10719D01*
X1648541Y-10511D01*
X1648332Y-10261D01*
X1648291Y-10011D01*
X1648374Y-9719D01*
X1648666Y-9511D01*
X1648957Y-9428D01*
X1649332D01*
G01X1648957D02*
X1648707Y-9303D01*
X1648499Y-9094D01*
X1648416Y-8844D01*
X1648499Y-8594D01*
X1648707Y-8386D01*
X1649082Y-8261D01*
X1649457Y-8303D01*
X1649832Y-8469D01*
G01X1646982Y-10761D02*
Y-8261D01*
X1645982D01*
X1645649Y-8386D01*
X1645399Y-8678D01*
X1645316Y-9011D01*
X1645399Y-9344D01*
X1645607Y-9594D01*
X1645982Y-9719D01*
X1646982D01*
G01X1643966Y-10386D02*
X1643716Y-10594D01*
X1643424Y-10719D01*
X1643049Y-10761D01*
X1642674Y-10678D01*
X1642382Y-10511D01*
X1642174Y-10219D01*
X1642132Y-9886D01*
X1642216Y-9553D01*
X1642424Y-9344D01*
X1642716Y-9178D01*
X1643007Y-9136D01*
X1643299Y-9178D01*
X1643674Y-9344D01*
X1643549Y-8261D01*
X1642424D01*
G01X1639949Y-10761D02*
Y-8261D01*
X1640449Y-8761D01*
G01Y-10761D02*
X1639449D01*
G01X1635634Y-10411D02*
Y-7911D01*
X1634593D01*
X1634259Y-8036D01*
X1634051Y-8203D01*
X1633968Y-8536D01*
X1634051Y-8869D01*
X1634301Y-9078D01*
X1634593Y-9203D01*
X1635634D01*
G01X1634593D02*
X1633968Y-10411D01*
G01X1632493Y-8328D02*
X1632243Y-8078D01*
X1631951Y-7953D01*
X1631618Y-7911D01*
X1631201Y-7994D01*
X1630909Y-8203D01*
X1630826Y-8453D01*
X1630868Y-8703D01*
X1631034Y-8911D01*
X1631868Y-9328D01*
X1632243Y-9619D01*
X1632493Y-10036D01*
X1632576Y-10411D01*
X1630826D01*
G01X1629518Y-7911D02*
Y-9703D01*
X1629351Y-10078D01*
X1629018Y-10328D01*
X1628601Y-10411D01*
X1628184Y-10328D01*
X1627851Y-10078D01*
X1627684Y-9703D01*
Y-7911D01*
G01X1625001Y-10411D02*
Y-7911D01*
X1626543Y-9703D01*
X1624459D01*
G01X1623193Y-8328D02*
X1622943Y-8078D01*
X1622651Y-7953D01*
X1622318Y-7911D01*
X1621901Y-7994D01*
X1621609Y-8203D01*
X1621526Y-8453D01*
X1621568Y-8703D01*
X1621734Y-8911D01*
X1622568Y-9328D01*
X1622943Y-9619D01*
X1623193Y-10036D01*
X1623276Y-10411D01*
X1621526D01*
G01X1595889Y15491D02*
X1598389D01*
Y16532D01*
X1598264Y16866D01*
X1598097Y17074D01*
X1597764Y17157D01*
X1597431Y17074D01*
X1597222Y16824D01*
X1597097Y16532D01*
Y15491D01*
G01Y16532D02*
X1595889Y17157D01*
G01Y19424D02*
X1595931Y19716D01*
X1596056Y20049D01*
X1596264Y20257D01*
X1596556Y20341D01*
X1596847Y20257D01*
X1597097Y20007D01*
X1597222Y19632D01*
Y19216D01*
X1597306Y18966D01*
X1597514Y18757D01*
X1597806Y18674D01*
X1598097Y18799D01*
X1598306Y19091D01*
X1598389Y19424D01*
X1598306Y19757D01*
X1598097Y20049D01*
X1597806Y20174D01*
X1597514Y20091D01*
X1597306Y19882D01*
X1597222Y19632D01*
Y19216D01*
X1597097Y18841D01*
X1596847Y18591D01*
X1596556Y18507D01*
X1596264Y18591D01*
X1596056Y18799D01*
X1595931Y19132D01*
X1595889Y19424D01*
G01Y21607D02*
X1598389D01*
Y22441D01*
X1598264Y22774D01*
X1598097Y23024D01*
X1597847Y23232D01*
X1597556Y23399D01*
X1597139Y23441D01*
X1596722Y23399D01*
X1596431Y23232D01*
X1596181Y23024D01*
X1596014Y22774D01*
X1595889Y22441D01*
Y21607D01*
G01Y26124D02*
X1598389D01*
X1596597Y24582D01*
Y26666D01*
G01X1595889Y28724D02*
X1598389D01*
X1597889Y28224D01*
G01X1595889D02*
Y29224D01*
G01X1591710Y15690D02*
X1594210D01*
Y16731D01*
X1594085Y17065D01*
X1593918Y17273D01*
X1593585Y17356D01*
X1593252Y17273D01*
X1593043Y17023D01*
X1592918Y16731D01*
Y15690D01*
G01Y16731D02*
X1591710Y17356D01*
G01X1593793Y18831D02*
X1594043Y19081D01*
X1594168Y19373D01*
X1594210Y19706D01*
X1594127Y20123D01*
X1593918Y20415D01*
X1593668Y20498D01*
X1593418Y20456D01*
X1593210Y20290D01*
X1592793Y19456D01*
X1592502Y19081D01*
X1592085Y18831D01*
X1591710Y18748D01*
Y20498D01*
G01Y21890D02*
X1594210D01*
Y22890D01*
X1594085Y23223D01*
X1593793Y23473D01*
X1593460Y23556D01*
X1593127Y23473D01*
X1592877Y23265D01*
X1592752Y22890D01*
Y21890D01*
G01X1591710Y25823D02*
X1594210D01*
X1593710Y25323D01*
G01X1591710D02*
Y26323D01*
G01Y28923D02*
X1591752Y29215D01*
X1591877Y29548D01*
X1592085Y29756D01*
X1592377Y29840D01*
X1592668Y29756D01*
X1592918Y29506D01*
X1593043Y29131D01*
Y28715D01*
X1593127Y28465D01*
X1593335Y28256D01*
X1593627Y28173D01*
X1593918Y28298D01*
X1594127Y28590D01*
X1594210Y28923D01*
X1594127Y29256D01*
X1593918Y29548D01*
X1593627Y29673D01*
X1593335Y29590D01*
X1593127Y29381D01*
X1593043Y29131D01*
Y28715D01*
X1592918Y28340D01*
X1592668Y28090D01*
X1592377Y28006D01*
X1592085Y28090D01*
X1591877Y28298D01*
X1591752Y28631D01*
X1591710Y28923D01*
G01X1641530Y-2999D02*
Y-499D01*
X1640489D01*
X1640155Y-624D01*
X1639947Y-791D01*
X1639864Y-1124D01*
X1639947Y-1457D01*
X1640197Y-1666D01*
X1640489Y-1791D01*
X1641530D01*
G01X1640489D02*
X1639864Y-2999D01*
G01X1638389Y-916D02*
X1638139Y-666D01*
X1637847Y-541D01*
X1637514Y-499D01*
X1637097Y-582D01*
X1636805Y-791D01*
X1636722Y-1041D01*
X1636764Y-1291D01*
X1636930Y-1499D01*
X1637764Y-1916D01*
X1638139Y-2207D01*
X1638389Y-2624D01*
X1638472Y-2999D01*
X1636722D01*
G01X1635330D02*
Y-499D01*
X1634330D01*
X1633997Y-624D01*
X1633747Y-916D01*
X1633664Y-1249D01*
X1633747Y-1582D01*
X1633955Y-1832D01*
X1634330Y-1957D01*
X1635330D01*
G01X1632189Y-916D02*
X1631939Y-666D01*
X1631647Y-541D01*
X1631314Y-499D01*
X1630897Y-582D01*
X1630605Y-791D01*
X1630522Y-1041D01*
X1630564Y-1291D01*
X1630730Y-1499D01*
X1631564Y-1916D01*
X1631939Y-2207D01*
X1632189Y-2624D01*
X1632272Y-2999D01*
X1630522D01*
G01X1628297Y-499D02*
X1628630Y-582D01*
X1628880Y-791D01*
X1629047Y-1041D01*
X1629172Y-1374D01*
X1629214Y-1749D01*
X1629172Y-2124D01*
X1629047Y-2457D01*
X1628880Y-2707D01*
X1628630Y-2916D01*
X1628297Y-2999D01*
X1627964Y-2916D01*
X1627714Y-2707D01*
X1627547Y-2457D01*
X1627422Y-2124D01*
X1627380Y-1749D01*
X1627422Y-1374D01*
X1627547Y-1041D01*
X1627714Y-791D01*
X1627964Y-582D01*
X1628297Y-499D01*
G01X1641530Y1031D02*
Y3531D01*
X1640489D01*
X1640155Y3406D01*
X1639947Y3239D01*
X1639864Y2906D01*
X1639947Y2573D01*
X1640197Y2364D01*
X1640489Y2239D01*
X1641530D01*
G01X1640489D02*
X1639864Y1031D01*
G01X1638389Y3114D02*
X1638139Y3364D01*
X1637847Y3489D01*
X1637514Y3531D01*
X1637097Y3448D01*
X1636805Y3239D01*
X1636722Y2989D01*
X1636764Y2739D01*
X1636930Y2531D01*
X1637764Y2114D01*
X1638139Y1823D01*
X1638389Y1406D01*
X1638472Y1031D01*
X1636722D01*
G01X1635330D02*
Y3531D01*
X1634330D01*
X1633997Y3406D01*
X1633747Y3114D01*
X1633664Y2781D01*
X1633747Y2448D01*
X1633955Y2198D01*
X1634330Y2073D01*
X1635330D01*
G01X1632189Y3114D02*
X1631939Y3364D01*
X1631647Y3489D01*
X1631314Y3531D01*
X1630897Y3448D01*
X1630605Y3239D01*
X1630522Y2989D01*
X1630564Y2739D01*
X1630730Y2531D01*
X1631564Y2114D01*
X1631939Y1823D01*
X1632189Y1406D01*
X1632272Y1031D01*
X1630522D01*
G01X1628297D02*
Y3531D01*
X1628797Y3031D01*
G01Y1031D02*
X1627797D01*
G01X1653182Y-7261D02*
Y-4761D01*
X1652141D01*
X1651807Y-4886D01*
X1651599Y-5053D01*
X1651516Y-5386D01*
X1651599Y-5719D01*
X1651849Y-5928D01*
X1652141Y-6053D01*
X1653182D01*
G01X1652141D02*
X1651516Y-7261D01*
G01X1650166Y-6761D02*
X1649916Y-7053D01*
X1649582Y-7219D01*
X1649207Y-7261D01*
X1648874Y-7219D01*
X1648541Y-7011D01*
X1648332Y-6761D01*
X1648291Y-6511D01*
X1648374Y-6219D01*
X1648666Y-6011D01*
X1648957Y-5928D01*
X1649332D01*
G01X1648957D02*
X1648707Y-5803D01*
X1648499Y-5594D01*
X1648416Y-5344D01*
X1648499Y-5094D01*
X1648707Y-4886D01*
X1649082Y-4761D01*
X1649457Y-4803D01*
X1649832Y-4969D01*
G01X1646982Y-7261D02*
Y-4761D01*
X1645982D01*
X1645649Y-4886D01*
X1645399Y-5178D01*
X1645316Y-5511D01*
X1645399Y-5844D01*
X1645607Y-6094D01*
X1645982Y-6219D01*
X1646982D01*
G01X1642549Y-7261D02*
Y-4761D01*
X1644091Y-6553D01*
X1642007D01*
G01X1639949Y-7261D02*
X1639657Y-7219D01*
X1639324Y-7094D01*
X1639116Y-6886D01*
X1639032Y-6594D01*
X1639116Y-6303D01*
X1639366Y-6053D01*
X1639741Y-5928D01*
X1640157D01*
X1640407Y-5844D01*
X1640616Y-5636D01*
X1640699Y-5344D01*
X1640574Y-5053D01*
X1640282Y-4844D01*
X1639949Y-4761D01*
X1639616Y-4844D01*
X1639324Y-5053D01*
X1639199Y-5344D01*
X1639282Y-5636D01*
X1639491Y-5844D01*
X1639741Y-5928D01*
X1640157D01*
X1640532Y-6053D01*
X1640782Y-6303D01*
X1640866Y-6594D01*
X1640782Y-6886D01*
X1640574Y-7094D01*
X1640241Y-7219D01*
X1639949Y-7261D01*
G01X1604317Y-3932D02*
Y-5724D01*
X1604150Y-6099D01*
X1603817Y-6349D01*
X1603400Y-6432D01*
X1602983Y-6349D01*
X1602650Y-6099D01*
X1602483Y-5724D01*
Y-3932D01*
G01X1600300Y-6432D02*
X1600008Y-6390D01*
X1599675Y-6265D01*
X1599467Y-6057D01*
X1599383Y-5765D01*
X1599467Y-5474D01*
X1599717Y-5224D01*
X1600092Y-5099D01*
X1600508D01*
X1600758Y-5015D01*
X1600967Y-4807D01*
X1601050Y-4515D01*
X1600925Y-4224D01*
X1600633Y-4015D01*
X1600300Y-3932D01*
X1599967Y-4015D01*
X1599675Y-4224D01*
X1599550Y-4515D01*
X1599633Y-4807D01*
X1599842Y-5015D01*
X1600092Y-5099D01*
X1600508D01*
X1600883Y-5224D01*
X1601133Y-5474D01*
X1601217Y-5765D01*
X1601133Y-6057D01*
X1600925Y-6265D01*
X1600592Y-6390D01*
X1600300Y-6432D01*
G01X1596950Y-5182D02*
X1596117D01*
Y-5932D01*
X1596367Y-6182D01*
X1596658Y-6349D01*
X1597075Y-6432D01*
X1597492Y-6349D01*
X1597783Y-6182D01*
X1598033Y-5932D01*
X1598200Y-5640D01*
X1598283Y-5307D01*
Y-5015D01*
X1598200Y-4765D01*
X1598033Y-4474D01*
X1597783Y-4224D01*
X1597533Y-4057D01*
X1597200Y-3932D01*
X1596908D01*
X1596575Y-4015D01*
X1596325Y-4182D01*
G01X1595017Y-5932D02*
X1594767Y-6224D01*
X1594433Y-6390D01*
X1594058Y-6432D01*
X1593725Y-6390D01*
X1593392Y-6182D01*
X1593183Y-5932D01*
X1593142Y-5682D01*
X1593225Y-5390D01*
X1593517Y-5182D01*
X1593808Y-5099D01*
X1594183D01*
G01X1593808D02*
X1593558Y-4974D01*
X1593350Y-4765D01*
X1593267Y-4515D01*
X1593350Y-4265D01*
X1593558Y-4057D01*
X1593933Y-3932D01*
X1594308Y-3974D01*
X1594683Y-4140D01*
G01X1635755Y-4181D02*
Y-5973D01*
X1635588Y-6348D01*
X1635255Y-6598D01*
X1634838Y-6681D01*
X1634421Y-6598D01*
X1634088Y-6348D01*
X1633921Y-5973D01*
Y-4181D01*
G01X1631738Y-6681D02*
X1631446Y-6639D01*
X1631113Y-6514D01*
X1630905Y-6306D01*
X1630821Y-6014D01*
X1630905Y-5723D01*
X1631155Y-5473D01*
X1631530Y-5348D01*
X1631946D01*
X1632196Y-5264D01*
X1632405Y-5056D01*
X1632488Y-4764D01*
X1632363Y-4473D01*
X1632071Y-4264D01*
X1631738Y-4181D01*
X1631405Y-4264D01*
X1631113Y-4473D01*
X1630988Y-4764D01*
X1631071Y-5056D01*
X1631280Y-5264D01*
X1631530Y-5348D01*
X1631946D01*
X1632321Y-5473D01*
X1632571Y-5723D01*
X1632655Y-6014D01*
X1632571Y-6306D01*
X1632363Y-6514D01*
X1632030Y-6639D01*
X1631738Y-6681D01*
G01X1628388Y-5431D02*
X1627555D01*
Y-6181D01*
X1627805Y-6431D01*
X1628096Y-6598D01*
X1628513Y-6681D01*
X1628930Y-6598D01*
X1629221Y-6431D01*
X1629471Y-6181D01*
X1629638Y-5889D01*
X1629721Y-5556D01*
Y-5264D01*
X1629638Y-5014D01*
X1629471Y-4723D01*
X1629221Y-4473D01*
X1628971Y-4306D01*
X1628638Y-4181D01*
X1628346D01*
X1628013Y-4264D01*
X1627763Y-4431D01*
G01X1626330Y-4598D02*
X1626080Y-4348D01*
X1625788Y-4223D01*
X1625455Y-4181D01*
X1625038Y-4264D01*
X1624746Y-4473D01*
X1624663Y-4723D01*
X1624705Y-4973D01*
X1624871Y-5181D01*
X1625705Y-5598D01*
X1626080Y-5889D01*
X1626330Y-6306D01*
X1626413Y-6681D01*
X1624663D01*
G01X1621495Y3497D02*
X1621745Y3622D01*
X1622037Y3705D01*
X1622370D01*
X1622745Y3580D01*
X1623037Y3372D01*
X1623245Y3122D01*
X1623412Y2705D01*
X1623454Y2330D01*
X1623370Y1955D01*
X1623245Y1705D01*
X1622995Y1455D01*
X1622704Y1288D01*
X1622412Y1205D01*
X1622120D01*
X1621829Y1288D01*
X1621579Y1413D01*
X1621370Y1580D01*
G01X1620104Y3288D02*
X1619854Y3538D01*
X1619562Y3663D01*
X1619229Y3705D01*
X1618812Y3622D01*
X1618520Y3413D01*
X1618437Y3163D01*
X1618479Y2913D01*
X1618645Y2705D01*
X1619479Y2288D01*
X1619854Y1997D01*
X1620104Y1580D01*
X1620187Y1205D01*
X1618437D01*
G01X1617129Y3705D02*
Y1913D01*
X1616962Y1538D01*
X1616629Y1288D01*
X1616212Y1205D01*
X1615795Y1288D01*
X1615462Y1538D01*
X1615295Y1913D01*
Y3705D01*
G01X1613904Y3288D02*
X1613654Y3538D01*
X1613362Y3663D01*
X1613029Y3705D01*
X1612612Y3622D01*
X1612320Y3413D01*
X1612237Y3163D01*
X1612279Y2913D01*
X1612445Y2705D01*
X1613279Y2288D01*
X1613654Y1997D01*
X1613904Y1580D01*
X1613987Y1205D01*
X1612237D01*
G01X1610095D02*
X1610012Y1747D01*
X1609887Y2205D01*
X1609720Y2622D01*
X1609512Y3080D01*
X1609179Y3705D01*
X1610845D01*
G01X1646351Y21757D02*
X1650774D01*
G01X1643425Y12697D02*
X1643758Y12739D01*
X1644050Y12905D01*
X1644300Y13155D01*
X1644467Y13447D01*
X1644550Y13780D01*
Y14114D01*
X1644467Y14447D01*
X1644300Y14739D01*
X1644050Y14989D01*
X1643758Y15155D01*
X1643425Y15197D01*
X1643092Y15155D01*
X1642800Y14989D01*
X1642550Y14739D01*
X1642383Y14447D01*
X1642300Y14114D01*
Y13780D01*
X1642383Y13447D01*
X1642550Y13155D01*
X1642800Y12905D01*
X1643092Y12739D01*
X1643425Y12697D01*
G01X1643092Y13364D02*
X1642592Y12697D01*
G01X1640325D02*
Y15197D01*
X1640825Y14697D01*
G01Y12697D02*
X1639825D01*
G01X1638058D02*
Y15197D01*
X1637058D01*
X1636725Y15072D01*
X1636475Y14780D01*
X1636392Y14447D01*
X1636475Y14114D01*
X1636683Y13864D01*
X1637058Y13739D01*
X1638058D01*
G01X1634917Y14780D02*
X1634667Y15030D01*
X1634375Y15155D01*
X1634042Y15197D01*
X1633625Y15114D01*
X1633333Y14905D01*
X1633250Y14655D01*
X1633292Y14405D01*
X1633458Y14197D01*
X1634292Y13780D01*
X1634667Y13489D01*
X1634917Y13072D01*
X1635000Y12697D01*
X1633250D01*
G01X1630000Y26900D02*
Y29400D01*
G01X1632250Y22150D02*
X1635500D01*
Y25650D01*
G01X1632250Y34150D02*
X1635500D01*
Y30650D01*
G01X1630583Y96433D02*
X1630050Y96783D01*
X1629650Y97367D01*
X1629383Y98183D01*
X1629650Y98883D01*
X1630183Y99350D01*
X1631117Y99700D01*
X1634717D01*
Y92700D01*
X1630317D01*
X1629383Y93167D01*
X1628850Y93867D01*
X1628583Y94683D01*
X1628850Y95500D01*
X1629650Y96200D01*
X1630583Y96433D01*
X1634717D01*
G01X1658300Y83700D02*
Y80300D01*
X1645400D01*
G01X1640900Y80500D02*
X1634000D01*
Y90500D01*
X1628000D01*
G01X1605000Y96500D02*
Y88500D01*
X1606000D01*
G01X1644433Y69450D02*
Y71950D01*
X1643392D01*
X1643058Y71825D01*
X1642850Y71658D01*
X1642767Y71325D01*
X1642850Y70992D01*
X1643100Y70783D01*
X1643392Y70658D01*
X1644433D01*
G01X1643392D02*
X1642767Y69450D01*
G01X1641292Y71533D02*
X1641042Y71783D01*
X1640750Y71908D01*
X1640417Y71950D01*
X1640000Y71867D01*
X1639708Y71658D01*
X1639625Y71408D01*
X1639667Y71158D01*
X1639833Y70950D01*
X1640667Y70533D01*
X1641042Y70242D01*
X1641292Y69825D01*
X1641375Y69450D01*
X1639625D01*
G01X1638317Y71950D02*
Y70158D01*
X1638150Y69783D01*
X1637817Y69533D01*
X1637400Y69450D01*
X1636983Y69533D01*
X1636650Y69783D01*
X1636483Y70158D01*
Y71950D01*
G01X1633800Y69450D02*
Y71950D01*
X1635342Y70158D01*
X1633258D01*
G01X1631992Y70492D02*
X1631700Y70783D01*
X1631450Y70950D01*
X1631117Y71033D01*
X1630825Y70950D01*
X1630617Y70783D01*
X1630450Y70533D01*
X1630408Y70242D01*
X1630450Y69992D01*
X1630617Y69742D01*
X1630867Y69533D01*
X1631158Y69450D01*
X1631492Y69533D01*
X1631783Y69783D01*
X1631950Y70158D01*
X1631992Y70575D01*
X1631908Y71117D01*
X1631783Y71408D01*
X1631575Y71700D01*
X1631283Y71908D01*
X1630992Y71950D01*
X1630700Y71867D01*
X1630492Y71658D01*
G01X1622378Y65469D02*
Y67969D01*
X1621337D01*
X1621003Y67844D01*
X1620795Y67677D01*
X1620712Y67344D01*
X1620795Y67011D01*
X1621045Y66802D01*
X1621337Y66677D01*
X1622378D01*
G01X1621337D02*
X1620712Y65469D01*
G01X1618445D02*
Y67969D01*
X1618945Y67469D01*
G01Y65469D02*
X1617945D01*
G01X1616262Y67969D02*
Y66177D01*
X1616095Y65802D01*
X1615762Y65552D01*
X1615345Y65469D01*
X1614928Y65552D01*
X1614595Y65802D01*
X1614428Y66177D01*
Y67969D01*
G01X1613037Y67552D02*
X1612787Y67802D01*
X1612495Y67927D01*
X1612162Y67969D01*
X1611745Y67886D01*
X1611453Y67677D01*
X1611370Y67427D01*
X1611412Y67177D01*
X1611578Y66969D01*
X1612412Y66552D01*
X1612787Y66261D01*
X1613037Y65844D01*
X1613120Y65469D01*
X1611370D01*
G01X1609853Y65761D02*
X1609562Y65552D01*
X1609228Y65469D01*
X1608895Y65552D01*
X1608603Y65802D01*
X1608395Y66177D01*
X1608312Y66552D01*
Y67011D01*
X1608395Y67386D01*
X1608603Y67719D01*
X1608853Y67886D01*
X1609145Y67969D01*
X1609478Y67886D01*
X1609728Y67719D01*
X1609895Y67469D01*
X1609978Y67136D01*
X1609895Y66844D01*
X1609687Y66552D01*
X1609437Y66386D01*
X1609145Y66344D01*
X1608812Y66427D01*
X1608562Y66636D01*
X1608312Y67011D01*
G01X1635383Y76300D02*
Y78800D01*
X1634342D01*
X1634008Y78675D01*
X1633800Y78508D01*
X1633717Y78175D01*
X1633800Y77842D01*
X1634050Y77633D01*
X1634342Y77508D01*
X1635383D01*
G01X1634342D02*
X1633717Y76300D01*
G01X1631450D02*
Y78800D01*
X1631950Y78300D01*
G01Y76300D02*
X1630950D01*
G01X1629267Y78800D02*
Y77008D01*
X1629100Y76633D01*
X1628767Y76383D01*
X1628350Y76300D01*
X1627933Y76383D01*
X1627600Y76633D01*
X1627433Y77008D01*
Y78800D01*
G01X1625333Y76300D02*
X1625250Y76842D01*
X1625125Y77300D01*
X1624958Y77717D01*
X1624750Y78175D01*
X1624417Y78800D01*
X1626083D01*
G01X1639633Y63550D02*
Y66050D01*
X1638592D01*
X1638258Y65925D01*
X1638050Y65758D01*
X1637967Y65425D01*
X1638050Y65092D01*
X1638300Y64883D01*
X1638592Y64758D01*
X1639633D01*
G01X1638592D02*
X1637967Y63550D01*
G01X1636492Y65633D02*
X1636242Y65883D01*
X1635950Y66008D01*
X1635617Y66050D01*
X1635200Y65967D01*
X1634908Y65758D01*
X1634825Y65508D01*
X1634867Y65258D01*
X1635033Y65050D01*
X1635867Y64633D01*
X1636242Y64342D01*
X1636492Y63925D01*
X1636575Y63550D01*
X1634825D01*
G01X1633517Y66050D02*
Y64258D01*
X1633350Y63883D01*
X1633017Y63633D01*
X1632600Y63550D01*
X1632183Y63633D01*
X1631850Y63883D01*
X1631683Y64258D01*
Y66050D01*
G01X1629000Y63550D02*
Y66050D01*
X1630542Y64258D01*
X1628458D01*
G01X1627317Y63925D02*
X1627067Y63717D01*
X1626775Y63592D01*
X1626400Y63550D01*
X1626025Y63633D01*
X1625733Y63800D01*
X1625525Y64092D01*
X1625483Y64425D01*
X1625567Y64758D01*
X1625775Y64967D01*
X1626067Y65133D01*
X1626358Y65175D01*
X1626650Y65133D01*
X1627025Y64967D01*
X1626900Y66050D01*
X1625775D01*
G01X1606933Y46000D02*
Y48500D01*
X1605892D01*
X1605558Y48375D01*
X1605350Y48208D01*
X1605267Y47875D01*
X1605350Y47542D01*
X1605600Y47333D01*
X1605892Y47208D01*
X1606933D01*
G01X1605892D02*
X1605267Y46000D01*
G01X1603792Y48083D02*
X1603542Y48333D01*
X1603250Y48458D01*
X1602917Y48500D01*
X1602500Y48417D01*
X1602208Y48208D01*
X1602125Y47958D01*
X1602167Y47708D01*
X1602333Y47500D01*
X1603167Y47083D01*
X1603542Y46792D01*
X1603792Y46375D01*
X1603875Y46000D01*
X1602125D01*
G01X1600733D02*
Y48500D01*
X1599692D01*
X1599358Y48375D01*
X1599150Y48208D01*
X1599067Y47875D01*
X1599150Y47542D01*
X1599400Y47333D01*
X1599692Y47208D01*
X1600733D01*
G01X1599692D02*
X1599067Y46000D01*
G01X1597508Y46292D02*
X1597217Y46083D01*
X1596883Y46000D01*
X1596550Y46083D01*
X1596258Y46333D01*
X1596050Y46708D01*
X1595967Y47083D01*
Y47542D01*
X1596050Y47917D01*
X1596258Y48250D01*
X1596508Y48417D01*
X1596800Y48500D01*
X1597133Y48417D01*
X1597383Y48250D01*
X1597550Y48000D01*
X1597633Y47667D01*
X1597550Y47375D01*
X1597342Y47083D01*
X1597092Y46917D01*
X1596800Y46875D01*
X1596467Y46958D01*
X1596217Y47167D01*
X1595967Y47542D01*
G01X1627283Y88492D02*
X1627533Y88617D01*
X1627825Y88700D01*
X1628158D01*
X1628533Y88575D01*
X1628825Y88367D01*
X1629033Y88117D01*
X1629200Y87700D01*
X1629242Y87325D01*
X1629158Y86950D01*
X1629033Y86700D01*
X1628783Y86450D01*
X1628492Y86283D01*
X1628200Y86200D01*
X1627908D01*
X1627617Y86283D01*
X1627367Y86408D01*
X1627158Y86575D01*
G01X1625808Y86492D02*
X1625517Y86283D01*
X1625183Y86200D01*
X1624850Y86283D01*
X1624558Y86533D01*
X1624350Y86908D01*
X1624267Y87283D01*
Y87742D01*
X1624350Y88117D01*
X1624558Y88450D01*
X1624808Y88617D01*
X1625100Y88700D01*
X1625433Y88617D01*
X1625683Y88450D01*
X1625850Y88200D01*
X1625933Y87867D01*
X1625850Y87575D01*
X1625642Y87283D01*
X1625392Y87117D01*
X1625100Y87075D01*
X1624767Y87158D01*
X1624517Y87367D01*
X1624267Y87742D01*
G01X1621750Y87450D02*
X1620917D01*
Y86700D01*
X1621167Y86450D01*
X1621458Y86283D01*
X1621875Y86200D01*
X1622292Y86283D01*
X1622583Y86450D01*
X1622833Y86700D01*
X1623000Y86992D01*
X1623083Y87325D01*
Y87617D01*
X1623000Y87867D01*
X1622833Y88158D01*
X1622583Y88408D01*
X1622333Y88575D01*
X1622000Y88700D01*
X1621708D01*
X1621375Y88617D01*
X1621125Y88450D01*
G01X1618900Y86200D02*
Y88700D01*
X1619400Y88200D01*
G01Y86200D02*
X1618400D01*
G01X1616717Y86575D02*
X1616467Y86367D01*
X1616175Y86242D01*
X1615800Y86200D01*
X1615425Y86283D01*
X1615133Y86450D01*
X1614925Y86742D01*
X1614883Y87075D01*
X1614967Y87408D01*
X1615175Y87617D01*
X1615467Y87783D01*
X1615758Y87825D01*
X1616050Y87783D01*
X1616425Y87617D01*
X1616300Y88700D01*
X1615175D01*
G01X1656186Y71990D02*
X1656519Y72032D01*
X1656811Y72198D01*
X1657061Y72448D01*
X1657228Y72740D01*
X1657311Y73073D01*
Y73407D01*
X1657228Y73740D01*
X1657061Y74032D01*
X1656811Y74282D01*
X1656519Y74448D01*
X1656186Y74490D01*
X1655853Y74448D01*
X1655561Y74282D01*
X1655311Y74032D01*
X1655144Y73740D01*
X1655061Y73407D01*
Y73073D01*
X1655144Y72740D01*
X1655311Y72448D01*
X1655561Y72198D01*
X1655853Y72032D01*
X1656186Y71990D01*
G01X1655853Y72657D02*
X1655353Y71990D01*
G01X1653878Y74073D02*
X1653628Y74323D01*
X1653336Y74448D01*
X1653003Y74490D01*
X1652586Y74407D01*
X1652294Y74198D01*
X1652211Y73948D01*
X1652253Y73698D01*
X1652419Y73490D01*
X1653253Y73073D01*
X1653628Y72782D01*
X1653878Y72365D01*
X1653961Y71990D01*
X1652211D01*
G01X1649986Y74490D02*
Y71990D01*
G01X1650944Y74490D02*
X1649028D01*
G01X1647678Y74073D02*
X1647428Y74323D01*
X1647136Y74448D01*
X1646803Y74490D01*
X1646386Y74407D01*
X1646094Y74198D01*
X1646011Y73948D01*
X1646053Y73698D01*
X1646219Y73490D01*
X1647053Y73073D01*
X1647428Y72782D01*
X1647678Y72365D01*
X1647761Y71990D01*
X1646011D01*
G01X1649900Y62721D02*
Y65221D01*
G01X1642456Y45212D02*
X1642498Y44879D01*
X1642664Y44587D01*
X1642914Y44337D01*
X1643206Y44170D01*
X1643539Y44087D01*
X1643873D01*
X1644206Y44170D01*
X1644498Y44337D01*
X1644748Y44587D01*
X1644914Y44879D01*
X1644956Y45212D01*
X1644914Y45545D01*
X1644748Y45837D01*
X1644498Y46087D01*
X1644206Y46254D01*
X1643873Y46337D01*
X1643539D01*
X1643206Y46254D01*
X1642914Y46087D01*
X1642664Y45837D01*
X1642498Y45545D01*
X1642456Y45212D01*
G01X1643123Y45545D02*
X1642456Y46045D01*
G01X1644539Y47520D02*
X1644789Y47770D01*
X1644914Y48062D01*
X1644956Y48395D01*
X1644873Y48812D01*
X1644664Y49104D01*
X1644414Y49187D01*
X1644164Y49145D01*
X1643956Y48979D01*
X1643539Y48145D01*
X1643248Y47770D01*
X1642831Y47520D01*
X1642456Y47437D01*
Y49187D01*
G01X1644956Y51412D02*
X1642456D01*
G01X1644956Y50454D02*
Y52370D01*
G01X1642456Y54512D02*
X1644956D01*
X1644456Y54012D01*
G01X1642456D02*
Y55012D01*
G01X1650400Y48121D02*
Y50621D01*
G01X1619869Y73085D02*
Y75585D01*
X1618828D01*
X1618494Y75460D01*
X1618286Y75293D01*
X1618203Y74960D01*
X1618286Y74627D01*
X1618536Y74418D01*
X1618828Y74293D01*
X1619869D01*
G01X1618828D02*
X1618203Y73085D01*
G01X1615936D02*
Y75585D01*
X1616436Y75085D01*
G01Y73085D02*
X1615436D01*
G01X1613753Y75585D02*
Y73793D01*
X1613586Y73418D01*
X1613253Y73168D01*
X1612836Y73085D01*
X1612419Y73168D01*
X1612086Y73418D01*
X1611919Y73793D01*
Y75585D01*
G01X1610528Y75168D02*
X1610278Y75418D01*
X1609986Y75543D01*
X1609653Y75585D01*
X1609236Y75502D01*
X1608944Y75293D01*
X1608861Y75043D01*
X1608903Y74793D01*
X1609069Y74585D01*
X1609903Y74168D01*
X1610278Y73877D01*
X1610528Y73460D01*
X1610611Y73085D01*
X1608861D01*
G01X1606636D02*
X1606344Y73127D01*
X1606011Y73252D01*
X1605803Y73460D01*
X1605719Y73752D01*
X1605803Y74043D01*
X1606053Y74293D01*
X1606428Y74418D01*
X1606844D01*
X1607094Y74502D01*
X1607303Y74710D01*
X1607386Y75002D01*
X1607261Y75293D01*
X1606969Y75502D01*
X1606636Y75585D01*
X1606303Y75502D01*
X1606011Y75293D01*
X1605886Y75002D01*
X1605969Y74710D01*
X1606178Y74502D01*
X1606428Y74418D01*
X1606844D01*
X1607219Y74293D01*
X1607469Y74043D01*
X1607553Y73752D01*
X1607469Y73460D01*
X1607261Y73252D01*
X1606928Y73127D01*
X1606636Y73085D01*
G01X1615200Y84000D02*
Y80000D01*
X1607800D01*
G01X1634917Y62550D02*
Y60758D01*
X1634750Y60383D01*
X1634417Y60133D01*
X1634000Y60050D01*
X1633583Y60133D01*
X1633250Y60383D01*
X1633083Y60758D01*
Y62550D01*
G01X1631692Y62133D02*
X1631442Y62383D01*
X1631150Y62508D01*
X1630817Y62550D01*
X1630400Y62467D01*
X1630108Y62258D01*
X1630025Y62008D01*
X1630067Y61758D01*
X1630233Y61550D01*
X1631067Y61133D01*
X1631442Y60842D01*
X1631692Y60425D01*
X1631775Y60050D01*
X1630025D01*
G01X1628633D02*
Y62550D01*
X1627592D01*
X1627258Y62425D01*
X1627050Y62258D01*
X1626967Y61925D01*
X1627050Y61592D01*
X1627300Y61383D01*
X1627592Y61258D01*
X1628633D01*
G01X1627592D02*
X1626967Y60050D01*
G01X1624700D02*
Y62550D01*
X1625200Y62050D01*
G01Y60050D02*
X1624200D01*
G01X1622300Y61200D02*
Y49800D01*
G01X1608900Y61200D02*
X1622300D01*
G01X1608900Y49800D02*
Y61200D01*
G01X1622300Y49800D02*
X1608900D01*
G01X1655733Y134967D02*
Y141967D01*
X1650667D01*
G01X1652533Y138584D02*
X1655733D01*
G01X1592300Y98400D02*
X1594100D01*
G01X1591000Y95300D02*
Y96300D01*
G01X1621700Y139800D02*
Y132900D01*
X1624800D01*
Y124740D01*
G01X1646591Y117271D02*
Y117189D01*
G01X1624862Y121724D02*
Y117189D01*
X1646590D01*
X1646591Y117188D01*
G01X1653104Y126000D02*
Y117271D01*
X1646592D01*
X1646591Y117270D01*
Y107127D01*
X1658391D01*
Y100427D01*
G01X1605000Y96500D02*
Y98400D01*
X1597000D01*
G01X1599167Y146467D02*
X1601667D01*
Y147508D01*
X1601542Y147842D01*
X1601375Y148050D01*
X1601042Y148133D01*
X1600709Y148050D01*
X1600500Y147800D01*
X1600375Y147508D01*
Y146467D01*
G01Y147508D02*
X1599167Y148133D01*
G01X1601250Y149608D02*
X1601500Y149858D01*
X1601625Y150150D01*
X1601667Y150483D01*
X1601584Y150900D01*
X1601375Y151192D01*
X1601125Y151275D01*
X1600875Y151233D01*
X1600667Y151067D01*
X1600250Y150233D01*
X1599959Y149858D01*
X1599542Y149608D01*
X1599167Y149525D01*
Y151275D01*
G01X1601667Y153500D02*
X1599167D01*
G01X1601667Y152542D02*
Y154458D01*
G01X1599167Y157100D02*
X1601667D01*
X1599875Y155558D01*
Y157642D01*
G01X1599167Y159700D02*
X1601667D01*
X1601167Y159200D01*
G01X1599167D02*
Y160200D01*
G01X1616623Y144174D02*
X1616873Y144299D01*
X1617165Y144382D01*
X1617498D01*
X1617873Y144257D01*
X1618165Y144049D01*
X1618373Y143799D01*
X1618540Y143382D01*
X1618582Y143007D01*
X1618498Y142632D01*
X1618373Y142382D01*
X1618123Y142132D01*
X1617832Y141965D01*
X1617540Y141882D01*
X1617248D01*
X1616957Y141965D01*
X1616707Y142090D01*
X1616498Y142257D01*
G01X1615232Y143965D02*
X1614982Y144215D01*
X1614690Y144340D01*
X1614357Y144382D01*
X1613940Y144299D01*
X1613648Y144090D01*
X1613565Y143840D01*
X1613607Y143590D01*
X1613773Y143382D01*
X1614607Y142965D01*
X1614982Y142674D01*
X1615232Y142257D01*
X1615315Y141882D01*
X1613565D01*
G01X1612257Y142257D02*
X1612007Y142049D01*
X1611715Y141924D01*
X1611340Y141882D01*
X1610965Y141965D01*
X1610673Y142132D01*
X1610465Y142424D01*
X1610423Y142757D01*
X1610507Y143090D01*
X1610715Y143299D01*
X1611007Y143465D01*
X1611298Y143507D01*
X1611590Y143465D01*
X1611965Y143299D01*
X1611840Y144382D01*
X1610715D01*
G01X1609490D02*
X1608907Y141882D01*
X1608240Y144382D01*
X1607573Y141882D01*
X1606990Y144382D01*
G01X1604640Y141882D02*
Y144382D01*
X1606182Y142590D01*
X1604098D01*
G01X1602957Y142257D02*
X1602707Y142049D01*
X1602415Y141924D01*
X1602040Y141882D01*
X1601665Y141965D01*
X1601373Y142132D01*
X1601165Y142424D01*
X1601123Y142757D01*
X1601207Y143090D01*
X1601415Y143299D01*
X1601707Y143465D01*
X1601998Y143507D01*
X1602290Y143465D01*
X1602665Y143299D01*
X1602540Y144382D01*
X1601415D01*
G01X1649963Y181919D02*
X1653493D01*
Y181935D01*
G01X1643000Y182000D02*
X1635000D01*
Y174000D01*
X1660500D01*
G01X1640842Y202817D02*
X1640967Y202567D01*
X1641050Y202275D01*
Y201942D01*
X1640925Y201567D01*
X1640717Y201275D01*
X1640467Y201067D01*
X1640050Y200900D01*
X1639675Y200858D01*
X1639300Y200942D01*
X1639050Y201067D01*
X1638800Y201317D01*
X1638633Y201608D01*
X1638550Y201900D01*
Y202192D01*
X1638633Y202483D01*
X1638758Y202733D01*
X1638925Y202942D01*
G01X1640633Y204208D02*
X1640883Y204458D01*
X1641008Y204750D01*
X1641050Y205083D01*
X1640967Y205500D01*
X1640758Y205792D01*
X1640508Y205875D01*
X1640258Y205833D01*
X1640050Y205667D01*
X1639633Y204833D01*
X1639342Y204458D01*
X1638925Y204208D01*
X1638550Y204125D01*
Y205875D01*
G01X1638925Y207183D02*
X1638717Y207433D01*
X1638592Y207725D01*
X1638550Y208100D01*
X1638633Y208475D01*
X1638800Y208767D01*
X1639092Y208975D01*
X1639425Y209017D01*
X1639758Y208933D01*
X1639967Y208725D01*
X1640133Y208433D01*
X1640175Y208142D01*
X1640133Y207850D01*
X1639967Y207475D01*
X1641050Y207600D01*
Y208725D01*
G01Y209950D02*
X1638550Y210533D01*
X1641050Y211200D01*
X1638550Y211867D01*
X1641050Y212450D01*
G01X1638550Y214800D02*
X1641050D01*
X1639258Y213258D01*
Y215342D01*
G01X1639592Y216608D02*
X1639883Y216900D01*
X1640050Y217150D01*
X1640133Y217483D01*
X1640050Y217775D01*
X1639883Y217983D01*
X1639633Y218150D01*
X1639342Y218192D01*
X1639092Y218150D01*
X1638842Y217983D01*
X1638633Y217733D01*
X1638550Y217442D01*
X1638633Y217108D01*
X1638883Y216817D01*
X1639258Y216650D01*
X1639675Y216608D01*
X1640217Y216692D01*
X1640508Y216817D01*
X1640800Y217025D01*
X1641008Y217317D01*
X1641050Y217608D01*
X1640967Y217900D01*
X1640758Y218108D01*
G01X1653415Y199685D02*
Y202185D01*
X1652374D01*
X1652040Y202060D01*
X1651832Y201893D01*
X1651749Y201560D01*
X1651832Y201227D01*
X1652082Y201018D01*
X1652374Y200893D01*
X1653415D01*
G01X1652374D02*
X1651749Y199685D01*
G01X1649482D02*
Y202185D01*
X1649982Y201685D01*
G01Y199685D02*
X1648982D01*
G01X1646382Y202185D02*
Y199685D01*
G01X1647340Y202185D02*
X1645424D01*
G01X1644074Y201768D02*
X1643824Y202018D01*
X1643532Y202143D01*
X1643199Y202185D01*
X1642782Y202102D01*
X1642490Y201893D01*
X1642407Y201643D01*
X1642449Y201393D01*
X1642615Y201185D01*
X1643449Y200768D01*
X1643824Y200477D01*
X1644074Y200060D01*
X1644157Y199685D01*
X1642407D01*
G01X1653415Y203685D02*
Y206185D01*
X1652374D01*
X1652040Y206060D01*
X1651832Y205893D01*
X1651749Y205560D01*
X1651832Y205227D01*
X1652082Y205018D01*
X1652374Y204893D01*
X1653415D01*
G01X1652374D02*
X1651749Y203685D01*
G01X1649482D02*
Y206185D01*
X1649982Y205685D01*
G01Y203685D02*
X1648982D01*
G01X1646382Y206185D02*
Y203685D01*
G01X1647340Y206185D02*
X1645424D01*
G01X1643365Y203685D02*
X1643282Y204227D01*
X1643157Y204685D01*
X1642990Y205102D01*
X1642782Y205560D01*
X1642449Y206185D01*
X1644115D01*
G01X1631971Y197714D02*
Y200214D01*
X1630930D01*
X1630596Y200089D01*
X1630388Y199922D01*
X1630305Y199589D01*
X1630388Y199256D01*
X1630638Y199047D01*
X1630930Y198922D01*
X1631971D01*
G01X1630930D02*
X1630305Y197714D01*
G01X1628038D02*
X1627746Y197756D01*
X1627413Y197881D01*
X1627205Y198089D01*
X1627121Y198381D01*
X1627205Y198672D01*
X1627455Y198922D01*
X1627830Y199047D01*
X1628246D01*
X1628496Y199131D01*
X1628705Y199339D01*
X1628788Y199631D01*
X1628663Y199922D01*
X1628371Y200131D01*
X1628038Y200214D01*
X1627705Y200131D01*
X1627413Y199922D01*
X1627288Y199631D01*
X1627371Y199339D01*
X1627580Y199131D01*
X1627830Y199047D01*
X1628246D01*
X1628621Y198922D01*
X1628871Y198672D01*
X1628955Y198381D01*
X1628871Y198089D01*
X1628663Y197881D01*
X1628330Y197756D01*
X1628038Y197714D01*
G01X1625730D02*
Y200214D01*
X1624146D01*
G01X1624730Y199006D02*
X1625730D01*
G01X1622755Y198214D02*
X1622505Y197922D01*
X1622171Y197756D01*
X1621796Y197714D01*
X1621463Y197756D01*
X1621130Y197964D01*
X1620921Y198214D01*
X1620880Y198464D01*
X1620963Y198756D01*
X1621255Y198964D01*
X1621546Y199047D01*
X1621921D01*
G01X1621546D02*
X1621296Y199172D01*
X1621088Y199381D01*
X1621005Y199631D01*
X1621088Y199881D01*
X1621296Y200089D01*
X1621671Y200214D01*
X1622046Y200172D01*
X1622421Y200006D01*
G01X1618738Y197714D02*
X1618446Y197756D01*
X1618113Y197881D01*
X1617905Y198089D01*
X1617821Y198381D01*
X1617905Y198672D01*
X1618155Y198922D01*
X1618530Y199047D01*
X1618946D01*
X1619196Y199131D01*
X1619405Y199339D01*
X1619488Y199631D01*
X1619363Y199922D01*
X1619071Y200131D01*
X1618738Y200214D01*
X1618405Y200131D01*
X1618113Y199922D01*
X1617988Y199631D01*
X1618071Y199339D01*
X1618280Y199131D01*
X1618530Y199047D01*
X1618946D01*
X1619321Y198922D01*
X1619571Y198672D01*
X1619655Y198381D01*
X1619571Y198089D01*
X1619363Y197881D01*
X1619030Y197756D01*
X1618738Y197714D01*
G01X1598800Y181467D02*
X1601300D01*
Y182508D01*
X1601175Y182842D01*
X1601008Y183050D01*
X1600675Y183133D01*
X1600342Y183050D01*
X1600133Y182800D01*
X1600008Y182508D01*
Y181467D01*
G01Y182508D02*
X1598800Y183133D01*
G01X1600883Y184608D02*
X1601133Y184858D01*
X1601258Y185150D01*
X1601300Y185483D01*
X1601217Y185900D01*
X1601008Y186192D01*
X1600758Y186275D01*
X1600508Y186233D01*
X1600300Y186067D01*
X1599883Y185233D01*
X1599592Y184858D01*
X1599175Y184608D01*
X1598800Y184525D01*
Y186275D01*
G01X1599175Y187583D02*
X1598967Y187833D01*
X1598842Y188125D01*
X1598800Y188500D01*
X1598883Y188875D01*
X1599050Y189167D01*
X1599342Y189375D01*
X1599675Y189417D01*
X1600008Y189333D01*
X1600217Y189125D01*
X1600383Y188833D01*
X1600425Y188542D01*
X1600383Y188250D01*
X1600217Y187875D01*
X1601300Y188000D01*
Y189125D01*
G01Y190350D02*
X1598800Y190933D01*
X1601300Y191600D01*
X1598800Y192267D01*
X1601300Y192850D01*
G01X1598800Y194617D02*
X1599342Y194700D01*
X1599800Y194825D01*
X1600217Y194992D01*
X1600675Y195200D01*
X1601300Y195533D01*
Y193867D01*
G01X1598800Y198300D02*
X1601300D01*
X1599508Y196758D01*
Y198842D01*
G01X1606424Y194666D02*
X1608924D01*
Y195707D01*
X1608799Y196041D01*
X1608632Y196249D01*
X1608299Y196332D01*
X1607966Y196249D01*
X1607757Y195999D01*
X1607632Y195707D01*
Y194666D01*
G01Y195707D02*
X1606424Y196332D01*
G01Y198599D02*
X1608924D01*
X1608424Y198099D01*
G01X1606424D02*
Y199099D01*
G01X1608924Y201699D02*
X1606424D01*
G01X1608924Y200741D02*
Y202657D01*
G01X1607466Y204007D02*
X1607757Y204299D01*
X1607924Y204549D01*
X1608007Y204882D01*
X1607924Y205174D01*
X1607757Y205382D01*
X1607507Y205549D01*
X1607216Y205591D01*
X1606966Y205549D01*
X1606716Y205382D01*
X1606507Y205132D01*
X1606424Y204841D01*
X1606507Y204507D01*
X1606757Y204216D01*
X1607132Y204049D01*
X1607549Y204007D01*
X1608091Y204091D01*
X1608382Y204216D01*
X1608674Y204424D01*
X1608882Y204716D01*
X1608924Y205007D01*
X1608841Y205299D01*
X1608632Y205507D01*
G01X1612738Y175122D02*
Y177622D01*
X1611697D01*
X1611363Y177497D01*
X1611155Y177330D01*
X1611072Y176997D01*
X1611155Y176664D01*
X1611405Y176455D01*
X1611697Y176330D01*
X1612738D01*
G01X1611697D02*
X1611072Y175122D01*
G01X1609597Y177205D02*
X1609347Y177455D01*
X1609055Y177580D01*
X1608722Y177622D01*
X1608305Y177539D01*
X1608013Y177330D01*
X1607930Y177080D01*
X1607972Y176830D01*
X1608138Y176622D01*
X1608972Y176205D01*
X1609347Y175914D01*
X1609597Y175497D01*
X1609680Y175122D01*
X1607930D01*
G01X1606622Y175497D02*
X1606372Y175289D01*
X1606080Y175164D01*
X1605705Y175122D01*
X1605330Y175205D01*
X1605038Y175372D01*
X1604830Y175664D01*
X1604788Y175997D01*
X1604872Y176330D01*
X1605080Y176539D01*
X1605372Y176705D01*
X1605663Y176747D01*
X1605955Y176705D01*
X1606330Y176539D01*
X1606205Y177622D01*
X1605080D01*
G01X1603855D02*
X1603272Y175122D01*
X1602605Y177622D01*
X1601938Y175122D01*
X1601355Y177622D01*
G01X1599588Y175122D02*
X1599505Y175664D01*
X1599380Y176122D01*
X1599213Y176539D01*
X1599005Y176997D01*
X1598672Y177622D01*
X1600338D01*
G01X1597322Y175622D02*
X1597072Y175330D01*
X1596738Y175164D01*
X1596363Y175122D01*
X1596030Y175164D01*
X1595697Y175372D01*
X1595488Y175622D01*
X1595447Y175872D01*
X1595530Y176164D01*
X1595822Y176372D01*
X1596113Y176455D01*
X1596488D01*
G01X1596113D02*
X1595863Y176580D01*
X1595655Y176789D01*
X1595572Y177039D01*
X1595655Y177289D01*
X1595863Y177497D01*
X1596238Y177622D01*
X1596613Y177580D01*
X1596988Y177414D01*
G01X1613424Y194666D02*
X1615924D01*
Y195707D01*
X1615799Y196041D01*
X1615632Y196249D01*
X1615299Y196332D01*
X1614966Y196249D01*
X1614757Y195999D01*
X1614632Y195707D01*
Y194666D01*
G01Y195707D02*
X1613424Y196332D01*
G01Y198599D02*
X1615924D01*
X1615424Y198099D01*
G01X1613424D02*
Y199099D01*
G01X1615924Y201699D02*
X1613424D01*
G01X1615924Y200741D02*
Y202657D01*
G01X1613799Y203882D02*
X1613591Y204132D01*
X1613466Y204424D01*
X1613424Y204799D01*
X1613507Y205174D01*
X1613674Y205466D01*
X1613966Y205674D01*
X1614299Y205716D01*
X1614632Y205632D01*
X1614841Y205424D01*
X1615007Y205132D01*
X1615049Y204841D01*
X1615007Y204549D01*
X1614841Y204174D01*
X1615924Y204299D01*
Y205424D01*
G01X1609924Y194666D02*
X1612424D01*
Y195707D01*
X1612299Y196041D01*
X1612132Y196249D01*
X1611799Y196332D01*
X1611466Y196249D01*
X1611257Y195999D01*
X1611132Y195707D01*
Y194666D01*
G01Y195707D02*
X1609924Y196332D01*
G01Y198599D02*
X1612424D01*
X1611924Y198099D01*
G01X1609924D02*
Y199099D01*
G01X1612424Y201699D02*
X1609924D01*
G01X1612424Y200741D02*
Y202657D01*
G01X1609924Y205299D02*
X1612424D01*
X1610632Y203757D01*
Y205841D01*
G01X1631971Y201214D02*
Y203714D01*
X1630930D01*
X1630596Y203589D01*
X1630388Y203422D01*
X1630305Y203089D01*
X1630388Y202756D01*
X1630638Y202547D01*
X1630930Y202422D01*
X1631971D01*
G01X1630930D02*
X1630305Y201214D01*
G01X1628038D02*
X1627746Y201256D01*
X1627413Y201381D01*
X1627205Y201589D01*
X1627121Y201881D01*
X1627205Y202172D01*
X1627455Y202422D01*
X1627830Y202547D01*
X1628246D01*
X1628496Y202631D01*
X1628705Y202839D01*
X1628788Y203131D01*
X1628663Y203422D01*
X1628371Y203631D01*
X1628038Y203714D01*
X1627705Y203631D01*
X1627413Y203422D01*
X1627288Y203131D01*
X1627371Y202839D01*
X1627580Y202631D01*
X1627830Y202547D01*
X1628246D01*
X1628621Y202422D01*
X1628871Y202172D01*
X1628955Y201881D01*
X1628871Y201589D01*
X1628663Y201381D01*
X1628330Y201256D01*
X1628038Y201214D01*
G01X1625730D02*
Y203714D01*
X1624146D01*
G01X1624730Y202506D02*
X1625730D01*
G01X1622755Y201714D02*
X1622505Y201422D01*
X1622171Y201256D01*
X1621796Y201214D01*
X1621463Y201256D01*
X1621130Y201464D01*
X1620921Y201714D01*
X1620880Y201964D01*
X1620963Y202256D01*
X1621255Y202464D01*
X1621546Y202547D01*
X1621921D01*
G01X1621546D02*
X1621296Y202672D01*
X1621088Y202881D01*
X1621005Y203131D01*
X1621088Y203381D01*
X1621296Y203589D01*
X1621671Y203714D01*
X1622046Y203672D01*
X1622421Y203506D01*
G01X1618821Y201214D02*
X1618738Y201756D01*
X1618613Y202214D01*
X1618446Y202631D01*
X1618238Y203089D01*
X1617905Y203714D01*
X1619571D01*
G01X1627981Y209043D02*
Y211543D01*
X1626940D01*
X1626606Y211418D01*
X1626398Y211251D01*
X1626315Y210918D01*
X1626398Y210585D01*
X1626648Y210376D01*
X1626940Y210251D01*
X1627981D01*
G01X1626940D02*
X1626315Y209043D01*
G01X1624840Y211126D02*
X1624590Y211376D01*
X1624298Y211501D01*
X1623965Y211543D01*
X1623548Y211460D01*
X1623256Y211251D01*
X1623173Y211001D01*
X1623215Y210751D01*
X1623381Y210543D01*
X1624215Y210126D01*
X1624590Y209835D01*
X1624840Y209418D01*
X1624923Y209043D01*
X1623173D01*
G01X1621865Y209418D02*
X1621615Y209210D01*
X1621323Y209085D01*
X1620948Y209043D01*
X1620573Y209126D01*
X1620281Y209293D01*
X1620073Y209585D01*
X1620031Y209918D01*
X1620115Y210251D01*
X1620323Y210460D01*
X1620615Y210626D01*
X1620906Y210668D01*
X1621198Y210626D01*
X1621573Y210460D01*
X1621448Y211543D01*
X1620323D01*
G01X1619098D02*
X1618515Y209043D01*
X1617848Y211543D01*
X1617181Y209043D01*
X1616598Y211543D01*
G01X1614748Y209043D02*
Y211543D01*
X1615248Y211043D01*
G01Y209043D02*
X1614248D01*
G01X1611148D02*
Y211543D01*
X1612690Y209751D01*
X1610606D01*
G01X1608048Y209043D02*
Y211543D01*
X1609590Y209751D01*
X1607506D01*
G01X1632433Y185932D02*
X1632683Y186057D01*
X1632975Y186140D01*
X1633308D01*
X1633683Y186015D01*
X1633975Y185807D01*
X1634183Y185557D01*
X1634350Y185140D01*
X1634392Y184765D01*
X1634308Y184390D01*
X1634183Y184140D01*
X1633933Y183890D01*
X1633642Y183723D01*
X1633350Y183640D01*
X1633058D01*
X1632767Y183723D01*
X1632517Y183848D01*
X1632308Y184015D01*
G01X1631042Y185723D02*
X1630792Y185973D01*
X1630500Y186098D01*
X1630167Y186140D01*
X1629750Y186057D01*
X1629458Y185848D01*
X1629375Y185598D01*
X1629417Y185348D01*
X1629583Y185140D01*
X1630417Y184723D01*
X1630792Y184432D01*
X1631042Y184015D01*
X1631125Y183640D01*
X1629375D01*
G01X1628067Y184015D02*
X1627817Y183807D01*
X1627525Y183682D01*
X1627150Y183640D01*
X1626775Y183723D01*
X1626483Y183890D01*
X1626275Y184182D01*
X1626233Y184515D01*
X1626317Y184848D01*
X1626525Y185057D01*
X1626817Y185223D01*
X1627108Y185265D01*
X1627400Y185223D01*
X1627775Y185057D01*
X1627650Y186140D01*
X1626525D01*
G01X1625300D02*
X1624717Y183640D01*
X1624050Y186140D01*
X1623383Y183640D01*
X1622800Y186140D01*
G01X1620450Y183640D02*
Y186140D01*
X1621992Y184348D01*
X1619908D01*
G01X1617850Y186140D02*
X1618183Y186057D01*
X1618433Y185848D01*
X1618600Y185598D01*
X1618725Y185265D01*
X1618767Y184890D01*
X1618725Y184515D01*
X1618600Y184182D01*
X1618433Y183932D01*
X1618183Y183723D01*
X1617850Y183640D01*
X1617517Y183723D01*
X1617267Y183932D01*
X1617100Y184182D01*
X1616975Y184515D01*
X1616933Y184890D01*
X1616975Y185265D01*
X1617100Y185598D01*
X1617267Y185848D01*
X1617517Y186057D01*
X1617850Y186140D01*
G01X1617797Y162012D02*
X1618047Y162137D01*
X1618339Y162220D01*
X1618672D01*
X1619047Y162095D01*
X1619339Y161887D01*
X1619547Y161637D01*
X1619714Y161220D01*
X1619756Y160845D01*
X1619672Y160470D01*
X1619547Y160220D01*
X1619297Y159970D01*
X1619006Y159803D01*
X1618714Y159720D01*
X1618422D01*
X1618131Y159803D01*
X1617881Y159928D01*
X1617672Y160095D01*
G01X1616406Y161803D02*
X1616156Y162053D01*
X1615864Y162178D01*
X1615531Y162220D01*
X1615114Y162137D01*
X1614822Y161928D01*
X1614739Y161678D01*
X1614781Y161428D01*
X1614947Y161220D01*
X1615781Y160803D01*
X1616156Y160512D01*
X1616406Y160095D01*
X1616489Y159720D01*
X1614739D01*
G01X1613431Y160095D02*
X1613181Y159887D01*
X1612889Y159762D01*
X1612514Y159720D01*
X1612139Y159803D01*
X1611847Y159970D01*
X1611639Y160262D01*
X1611597Y160595D01*
X1611681Y160928D01*
X1611889Y161137D01*
X1612181Y161303D01*
X1612472Y161345D01*
X1612764Y161303D01*
X1613139Y161137D01*
X1613014Y162220D01*
X1611889D01*
G01X1610664D02*
X1610081Y159720D01*
X1609414Y162220D01*
X1608747Y159720D01*
X1608164Y162220D01*
G01X1605814Y159720D02*
Y162220D01*
X1607356Y160428D01*
X1605272D01*
G01X1604006Y161803D02*
X1603756Y162053D01*
X1603464Y162178D01*
X1603131Y162220D01*
X1602714Y162137D01*
X1602422Y161928D01*
X1602339Y161678D01*
X1602381Y161428D01*
X1602547Y161220D01*
X1603381Y160803D01*
X1603756Y160512D01*
X1604006Y160095D01*
X1604089Y159720D01*
X1602339D01*
G01X1628130Y212835D02*
Y215335D01*
X1627089D01*
X1626755Y215210D01*
X1626547Y215043D01*
X1626464Y214710D01*
X1626547Y214377D01*
X1626797Y214168D01*
X1627089Y214043D01*
X1628130D01*
G01X1627089D02*
X1626464Y212835D01*
G01X1624197D02*
Y215335D01*
X1624697Y214835D01*
G01Y212835D02*
X1623697D01*
G01X1622347Y215335D02*
X1621764Y212835D01*
X1621097Y215335D01*
X1620430Y212835D01*
X1619847Y215335D01*
G01X1618914Y213335D02*
X1618664Y213043D01*
X1618330Y212877D01*
X1617955Y212835D01*
X1617622Y212877D01*
X1617289Y213085D01*
X1617080Y213335D01*
X1617039Y213585D01*
X1617122Y213877D01*
X1617414Y214085D01*
X1617705Y214168D01*
X1618080D01*
G01X1617705D02*
X1617455Y214293D01*
X1617247Y214502D01*
X1617164Y214752D01*
X1617247Y215002D01*
X1617455Y215210D01*
X1617830Y215335D01*
X1618205Y215293D01*
X1618580Y215127D01*
G01X1594130Y203480D02*
Y207480D01*
X1601530D01*
G01X1631572Y163291D02*
Y165791D01*
X1630531D01*
X1630197Y165666D01*
X1629989Y165499D01*
X1629906Y165166D01*
X1629989Y164833D01*
X1630239Y164624D01*
X1630531Y164499D01*
X1631572D01*
G01X1630531D02*
X1629906Y163291D01*
G01X1628431Y165374D02*
X1628181Y165624D01*
X1627889Y165749D01*
X1627556Y165791D01*
X1627139Y165708D01*
X1626847Y165499D01*
X1626764Y165249D01*
X1626806Y164999D01*
X1626972Y164791D01*
X1627806Y164374D01*
X1628181Y164083D01*
X1628431Y163666D01*
X1628514Y163291D01*
X1626764D01*
G01X1625456Y163666D02*
X1625206Y163458D01*
X1624914Y163333D01*
X1624539Y163291D01*
X1624164Y163374D01*
X1623872Y163541D01*
X1623664Y163833D01*
X1623622Y164166D01*
X1623706Y164499D01*
X1623914Y164708D01*
X1624206Y164874D01*
X1624497Y164916D01*
X1624789Y164874D01*
X1625164Y164708D01*
X1625039Y165791D01*
X1623914D01*
G01X1622689D02*
X1622106Y163291D01*
X1621439Y165791D01*
X1620772Y163291D01*
X1620189Y165791D01*
G01X1619131Y164333D02*
X1618839Y164624D01*
X1618589Y164791D01*
X1618256Y164874D01*
X1617964Y164791D01*
X1617756Y164624D01*
X1617589Y164374D01*
X1617547Y164083D01*
X1617589Y163833D01*
X1617756Y163583D01*
X1618006Y163374D01*
X1618297Y163291D01*
X1618631Y163374D01*
X1618922Y163624D01*
X1619089Y163999D01*
X1619131Y164416D01*
X1619047Y164958D01*
X1618922Y165249D01*
X1618714Y165541D01*
X1618422Y165749D01*
X1618131Y165791D01*
X1617839Y165708D01*
X1617631Y165499D01*
G01X1615322Y163291D02*
X1615239Y163833D01*
X1615114Y164291D01*
X1614947Y164708D01*
X1614739Y165166D01*
X1614406Y165791D01*
X1616072D01*
G01X1621800Y167500D02*
Y171500D01*
X1629200D01*
G01X1604993Y227969D02*
X1607493D01*
Y229010D01*
X1607368Y229344D01*
X1607201Y229552D01*
X1606868Y229635D01*
X1606535Y229552D01*
X1606326Y229302D01*
X1606201Y229010D01*
Y227969D01*
G01Y229010D02*
X1604993Y229635D01*
G01Y231902D02*
X1607493D01*
X1606993Y231402D01*
G01X1604993D02*
Y232402D01*
G01X1607493Y233752D02*
X1604993Y234335D01*
X1607493Y235002D01*
X1604993Y235669D01*
X1607493Y236252D01*
G01X1604993Y238602D02*
X1607493D01*
X1605701Y237060D01*
Y239144D01*
G01X1590825Y278908D02*
X1593325D01*
Y279949D01*
X1593200Y280283D01*
X1593033Y280491D01*
X1592700Y280574D01*
X1592367Y280491D01*
X1592158Y280241D01*
X1592033Y279949D01*
Y278908D01*
G01Y279949D02*
X1590825Y280574D01*
G01X1592908Y282049D02*
X1593158Y282299D01*
X1593283Y282591D01*
X1593325Y282924D01*
X1593242Y283341D01*
X1593033Y283633D01*
X1592783Y283716D01*
X1592533Y283674D01*
X1592325Y283508D01*
X1591908Y282674D01*
X1591617Y282299D01*
X1591200Y282049D01*
X1590825Y281966D01*
Y283716D01*
G01X1593325Y285941D02*
X1590825D01*
G01X1593325Y284983D02*
Y286899D01*
G01X1591200Y288124D02*
X1590992Y288374D01*
X1590867Y288666D01*
X1590825Y289041D01*
X1590908Y289416D01*
X1591075Y289708D01*
X1591367Y289916D01*
X1591700Y289958D01*
X1592033Y289874D01*
X1592242Y289666D01*
X1592408Y289374D01*
X1592450Y289083D01*
X1592408Y288791D01*
X1592242Y288416D01*
X1593325Y288541D01*
Y289666D01*
G01X1590825Y292641D02*
X1593325D01*
X1591533Y291099D01*
Y293183D01*
G01X1602653Y226461D02*
X1602986Y226503D01*
X1603278Y226669D01*
X1603528Y226919D01*
X1603695Y227211D01*
X1603778Y227544D01*
Y227878D01*
X1603695Y228211D01*
X1603528Y228503D01*
X1603278Y228753D01*
X1602986Y228919D01*
X1602653Y228961D01*
X1602320Y228919D01*
X1602028Y228753D01*
X1601778Y228503D01*
X1601611Y228211D01*
X1601528Y227878D01*
Y227544D01*
X1601611Y227211D01*
X1601778Y226919D01*
X1602028Y226669D01*
X1602320Y226503D01*
X1602653Y226461D01*
G01X1602320Y227128D02*
X1601820Y226461D01*
G01X1599553D02*
Y228961D01*
X1600053Y228461D01*
G01Y226461D02*
X1599053D01*
G01X1597703Y228961D02*
X1597120Y226461D01*
X1596453Y228961D01*
X1595786Y226461D01*
X1595203Y228961D01*
G01X1594145Y228544D02*
X1593895Y228794D01*
X1593603Y228919D01*
X1593270Y228961D01*
X1592853Y228878D01*
X1592561Y228669D01*
X1592478Y228419D01*
X1592520Y228169D01*
X1592686Y227961D01*
X1593520Y227544D01*
X1593895Y227253D01*
X1594145Y226836D01*
X1594228Y226461D01*
X1592478D01*
G01X1648500Y273500D02*
X1645250D01*
Y277000D01*
G01X1644200Y319401D02*
X1646700D01*
Y320442D01*
X1646575Y320776D01*
X1646408Y320984D01*
X1646075Y321067D01*
X1645742Y320984D01*
X1645533Y320734D01*
X1645408Y320442D01*
Y319401D01*
G01Y320442D02*
X1644200Y321067D01*
G01X1646283Y322542D02*
X1646533Y322792D01*
X1646658Y323084D01*
X1646700Y323417D01*
X1646617Y323834D01*
X1646408Y324126D01*
X1646158Y324209D01*
X1645908Y324167D01*
X1645700Y324001D01*
X1645283Y323167D01*
X1644992Y322792D01*
X1644575Y322542D01*
X1644200Y322459D01*
Y324209D01*
G01Y325601D02*
X1646700D01*
Y326601D01*
X1646575Y326934D01*
X1646283Y327184D01*
X1645950Y327267D01*
X1645617Y327184D01*
X1645367Y326976D01*
X1645242Y326601D01*
Y325601D01*
G01X1644575Y328617D02*
X1644367Y328867D01*
X1644242Y329159D01*
X1644200Y329534D01*
X1644283Y329909D01*
X1644450Y330201D01*
X1644742Y330409D01*
X1645075Y330451D01*
X1645408Y330367D01*
X1645617Y330159D01*
X1645783Y329867D01*
X1645825Y329576D01*
X1645783Y329284D01*
X1645617Y328909D01*
X1646700Y329034D01*
Y330159D01*
G01X1624692Y280899D02*
X1627192D01*
Y281940D01*
X1627067Y282274D01*
X1626900Y282482D01*
X1626567Y282565D01*
X1626234Y282482D01*
X1626025Y282232D01*
X1625900Y281940D01*
Y280899D01*
G01Y281940D02*
X1624692Y282565D01*
G01X1624984Y284124D02*
X1624775Y284415D01*
X1624692Y284749D01*
X1624775Y285082D01*
X1625025Y285374D01*
X1625400Y285582D01*
X1625775Y285665D01*
X1626234D01*
X1626609Y285582D01*
X1626942Y285374D01*
X1627109Y285124D01*
X1627192Y284832D01*
X1627109Y284499D01*
X1626942Y284249D01*
X1626692Y284082D01*
X1626359Y283999D01*
X1626067Y284082D01*
X1625775Y284290D01*
X1625609Y284540D01*
X1625567Y284832D01*
X1625650Y285165D01*
X1625859Y285415D01*
X1626234Y285665D01*
G01X1624692Y287140D02*
X1627192D01*
Y288724D01*
G01X1625984Y288140D02*
Y287140D01*
G01X1625192Y290115D02*
X1624900Y290365D01*
X1624734Y290699D01*
X1624692Y291074D01*
X1624734Y291407D01*
X1624942Y291740D01*
X1625192Y291949D01*
X1625442Y291990D01*
X1625734Y291907D01*
X1625942Y291615D01*
X1626025Y291324D01*
Y290949D01*
G01Y291324D02*
X1626150Y291574D01*
X1626359Y291782D01*
X1626609Y291865D01*
X1626859Y291782D01*
X1627067Y291574D01*
X1627192Y291199D01*
X1627150Y290824D01*
X1626984Y290449D01*
G01X1632014Y280921D02*
X1634514D01*
Y281962D01*
X1634389Y282296D01*
X1634222Y282504D01*
X1633889Y282587D01*
X1633556Y282504D01*
X1633347Y282254D01*
X1633222Y281962D01*
Y280921D01*
G01Y281962D02*
X1632014Y282587D01*
G01Y284854D02*
X1634514D01*
X1634014Y284354D01*
G01X1632014D02*
Y285354D01*
G01Y287121D02*
X1634514D01*
Y288162D01*
X1634389Y288496D01*
X1634222Y288704D01*
X1633889Y288787D01*
X1633556Y288704D01*
X1633347Y288454D01*
X1633222Y288162D01*
Y287121D01*
G01Y288162D02*
X1632014Y288787D01*
G01X1632389Y290137D02*
X1632181Y290387D01*
X1632056Y290679D01*
X1632014Y291054D01*
X1632097Y291429D01*
X1632264Y291721D01*
X1632556Y291929D01*
X1632889Y291971D01*
X1633222Y291887D01*
X1633431Y291679D01*
X1633597Y291387D01*
X1633639Y291096D01*
X1633597Y290804D01*
X1633431Y290429D01*
X1634514Y290554D01*
Y291679D01*
G01X1628292Y280999D02*
X1630792D01*
Y282040D01*
X1630667Y282374D01*
X1630500Y282582D01*
X1630167Y282665D01*
X1629834Y282582D01*
X1629625Y282332D01*
X1629500Y282040D01*
Y280999D01*
G01Y282040D02*
X1628292Y282665D01*
G01X1630375Y284140D02*
X1630625Y284390D01*
X1630750Y284682D01*
X1630792Y285015D01*
X1630709Y285432D01*
X1630500Y285724D01*
X1630250Y285807D01*
X1630000Y285765D01*
X1629792Y285599D01*
X1629375Y284765D01*
X1629084Y284390D01*
X1628667Y284140D01*
X1628292Y284057D01*
Y285807D01*
G01X1630792Y288032D02*
X1628292D01*
G01X1630792Y287074D02*
Y288990D01*
G01X1628792Y290215D02*
X1628500Y290465D01*
X1628334Y290799D01*
X1628292Y291174D01*
X1628334Y291507D01*
X1628542Y291840D01*
X1628792Y292049D01*
X1629042Y292090D01*
X1629334Y292007D01*
X1629542Y291715D01*
X1629625Y291424D01*
Y291049D01*
G01Y291424D02*
X1629750Y291674D01*
X1629959Y291882D01*
X1630209Y291965D01*
X1630459Y291882D01*
X1630667Y291674D01*
X1630792Y291299D01*
X1630750Y290924D01*
X1630584Y290549D01*
G01X1590200Y335567D02*
X1592700D01*
Y336608D01*
X1592575Y336942D01*
X1592408Y337150D01*
X1592075Y337233D01*
X1591742Y337150D01*
X1591533Y336900D01*
X1591408Y336608D01*
Y335567D01*
G01Y336608D02*
X1590200Y337233D01*
G01Y339500D02*
X1590242Y339792D01*
X1590367Y340125D01*
X1590575Y340333D01*
X1590867Y340417D01*
X1591158Y340333D01*
X1591408Y340083D01*
X1591533Y339708D01*
Y339292D01*
X1591617Y339042D01*
X1591825Y338833D01*
X1592117Y338750D01*
X1592408Y338875D01*
X1592617Y339167D01*
X1592700Y339500D01*
X1592617Y339833D01*
X1592408Y340125D01*
X1592117Y340250D01*
X1591825Y340167D01*
X1591617Y339958D01*
X1591533Y339708D01*
Y339292D01*
X1591408Y338917D01*
X1591158Y338667D01*
X1590867Y338583D01*
X1590575Y338667D01*
X1590367Y338875D01*
X1590242Y339208D01*
X1590200Y339500D01*
G01Y341683D02*
X1592700D01*
Y342517D01*
X1592575Y342850D01*
X1592408Y343100D01*
X1592158Y343308D01*
X1591867Y343475D01*
X1591450Y343517D01*
X1591033Y343475D01*
X1590742Y343308D01*
X1590492Y343100D01*
X1590325Y342850D01*
X1590200Y342517D01*
Y341683D01*
G01Y346200D02*
X1592700D01*
X1590908Y344658D01*
Y346742D01*
G01X1590200Y349300D02*
X1592700D01*
X1590908Y347758D01*
Y349842D01*
G01X1642239Y307191D02*
Y305399D01*
X1642072Y305024D01*
X1641739Y304774D01*
X1641322Y304691D01*
X1640905Y304774D01*
X1640572Y305024D01*
X1640405Y305399D01*
Y307191D01*
G01X1638222Y304691D02*
Y307191D01*
X1638722Y306691D01*
G01Y304691D02*
X1637722D01*
G01X1635955D02*
Y307191D01*
X1634914D01*
X1634580Y307066D01*
X1634372Y306899D01*
X1634289Y306566D01*
X1634372Y306233D01*
X1634622Y306024D01*
X1634914Y305899D01*
X1635955D01*
G01X1634914D02*
X1634289Y304691D01*
G01X1632814Y306774D02*
X1632564Y307024D01*
X1632272Y307149D01*
X1631939Y307191D01*
X1631522Y307108D01*
X1631230Y306899D01*
X1631147Y306649D01*
X1631189Y306399D01*
X1631355Y306191D01*
X1632189Y305774D01*
X1632564Y305483D01*
X1632814Y305066D01*
X1632897Y304691D01*
X1631147D01*
G01X1650992Y330967D02*
X1651117Y330717D01*
X1651200Y330425D01*
Y330092D01*
X1651075Y329717D01*
X1650867Y329425D01*
X1650617Y329217D01*
X1650200Y329050D01*
X1649825Y329008D01*
X1649450Y329092D01*
X1649200Y329217D01*
X1648950Y329467D01*
X1648783Y329758D01*
X1648700Y330050D01*
Y330342D01*
X1648783Y330633D01*
X1648908Y330883D01*
X1649075Y331092D01*
G01X1650783Y332358D02*
X1651033Y332608D01*
X1651158Y332900D01*
X1651200Y333233D01*
X1651117Y333650D01*
X1650908Y333942D01*
X1650658Y334025D01*
X1650408Y333983D01*
X1650200Y333817D01*
X1649783Y332983D01*
X1649492Y332608D01*
X1649075Y332358D01*
X1648700Y332275D01*
Y334025D01*
G01Y335417D02*
X1651200D01*
Y336417D01*
X1651075Y336750D01*
X1650783Y337000D01*
X1650450Y337083D01*
X1650117Y337000D01*
X1649867Y336792D01*
X1649742Y336417D01*
Y335417D01*
G01X1648700Y339350D02*
X1651200D01*
X1650700Y338850D01*
G01X1648700D02*
Y339850D01*
G01X1648500Y285500D02*
X1645250D01*
Y282000D01*
G01X1641850Y309367D02*
X1642183Y309409D01*
X1642475Y309575D01*
X1642725Y309825D01*
X1642892Y310117D01*
X1642975Y310450D01*
Y310784D01*
X1642892Y311117D01*
X1642725Y311409D01*
X1642475Y311659D01*
X1642183Y311825D01*
X1641850Y311867D01*
X1641517Y311825D01*
X1641225Y311659D01*
X1640975Y311409D01*
X1640808Y311117D01*
X1640725Y310784D01*
Y310450D01*
X1640808Y310117D01*
X1640975Y309825D01*
X1641225Y309575D01*
X1641517Y309409D01*
X1641850Y309367D01*
G01X1641517Y310034D02*
X1641017Y309367D01*
G01X1639542Y311450D02*
X1639292Y311700D01*
X1639000Y311825D01*
X1638667Y311867D01*
X1638250Y311784D01*
X1637958Y311575D01*
X1637875Y311325D01*
X1637917Y311075D01*
X1638083Y310867D01*
X1638917Y310450D01*
X1639292Y310159D01*
X1639542Y309742D01*
X1639625Y309367D01*
X1637875D01*
G01X1636483D02*
Y311867D01*
X1635483D01*
X1635150Y311742D01*
X1634900Y311450D01*
X1634817Y311117D01*
X1634900Y310784D01*
X1635108Y310534D01*
X1635483Y310409D01*
X1636483D01*
G01X1632550Y309367D02*
Y311867D01*
X1633050Y311367D01*
G01Y309367D02*
X1632050D01*
G01X1651000Y317000D02*
X1647750D01*
Y313500D01*
G01X1651000Y305000D02*
X1647750D01*
Y308500D01*
G01X1652400Y398500D02*
X1632400D01*
G01X1629500D02*
X1625100D01*
Y400500D01*
G01X1613532Y387155D02*
Y389655D01*
X1612491D01*
X1612157Y389530D01*
X1611949Y389363D01*
X1611866Y389030D01*
X1611949Y388697D01*
X1612199Y388488D01*
X1612491Y388363D01*
X1613532D01*
G01X1612491D02*
X1611866Y387155D01*
G01X1610391Y389238D02*
X1610141Y389488D01*
X1609849Y389613D01*
X1609516Y389655D01*
X1609099Y389572D01*
X1608807Y389363D01*
X1608724Y389113D01*
X1608766Y388863D01*
X1608932Y388655D01*
X1609766Y388238D01*
X1610141Y387947D01*
X1610391Y387530D01*
X1610474Y387155D01*
X1608724D01*
G01X1607457D02*
Y389655D01*
X1605541Y387155D01*
Y389655D01*
G01X1603399Y387155D02*
Y389655D01*
X1603899Y389155D01*
G01Y387155D02*
X1602899D01*
G01X1599799D02*
Y389655D01*
X1601341Y387863D01*
X1599257D01*
G01X1613246Y393918D02*
Y396418D01*
X1612205D01*
X1611871Y396293D01*
X1611663Y396126D01*
X1611580Y395793D01*
X1611663Y395460D01*
X1611913Y395251D01*
X1612205Y395126D01*
X1613246D01*
G01X1612205D02*
X1611580Y393918D01*
G01X1610105Y396001D02*
X1609855Y396251D01*
X1609563Y396376D01*
X1609230Y396418D01*
X1608813Y396335D01*
X1608521Y396126D01*
X1608438Y395876D01*
X1608480Y395626D01*
X1608646Y395418D01*
X1609480Y395001D01*
X1609855Y394710D01*
X1610105Y394293D01*
X1610188Y393918D01*
X1608438D01*
G01X1607171D02*
Y396418D01*
X1605255Y393918D01*
Y396418D01*
G01X1603113Y393918D02*
Y396418D01*
X1603613Y395918D01*
G01Y393918D02*
X1602613D01*
G01X1600013Y396418D02*
X1600346Y396335D01*
X1600596Y396126D01*
X1600763Y395876D01*
X1600888Y395543D01*
X1600930Y395168D01*
X1600888Y394793D01*
X1600763Y394460D01*
X1600596Y394210D01*
X1600346Y394001D01*
X1600013Y393918D01*
X1599680Y394001D01*
X1599430Y394210D01*
X1599263Y394460D01*
X1599138Y394793D01*
X1599096Y395168D01*
X1599138Y395543D01*
X1599263Y395876D01*
X1599430Y396126D01*
X1599680Y396335D01*
X1600013Y396418D01*
G01X1613235Y390379D02*
Y392879D01*
X1612194D01*
X1611860Y392754D01*
X1611652Y392587D01*
X1611569Y392254D01*
X1611652Y391921D01*
X1611902Y391712D01*
X1612194Y391587D01*
X1613235D01*
G01X1612194D02*
X1611569Y390379D01*
G01X1610094Y392462D02*
X1609844Y392712D01*
X1609552Y392837D01*
X1609219Y392879D01*
X1608802Y392796D01*
X1608510Y392587D01*
X1608427Y392337D01*
X1608469Y392087D01*
X1608635Y391879D01*
X1609469Y391462D01*
X1609844Y391171D01*
X1610094Y390754D01*
X1610177Y390379D01*
X1608427D01*
G01X1607160D02*
Y392879D01*
X1605244Y390379D01*
Y392879D01*
G01X1603102Y390379D02*
Y392879D01*
X1603602Y392379D01*
G01Y390379D02*
X1602602D01*
G01X1600794Y391421D02*
X1600502Y391712D01*
X1600252Y391879D01*
X1599919Y391962D01*
X1599627Y391879D01*
X1599419Y391712D01*
X1599252Y391462D01*
X1599210Y391171D01*
X1599252Y390921D01*
X1599419Y390671D01*
X1599669Y390462D01*
X1599960Y390379D01*
X1600294Y390462D01*
X1600585Y390712D01*
X1600752Y391087D01*
X1600794Y391504D01*
X1600710Y392046D01*
X1600585Y392337D01*
X1600377Y392629D01*
X1600085Y392837D01*
X1599794Y392879D01*
X1599502Y392796D01*
X1599294Y392587D01*
G01X1613246Y397118D02*
Y399618D01*
X1612205D01*
X1611871Y399493D01*
X1611663Y399326D01*
X1611580Y398993D01*
X1611663Y398660D01*
X1611913Y398451D01*
X1612205Y398326D01*
X1613246D01*
G01X1612205D02*
X1611580Y397118D01*
G01X1609313D02*
X1609021Y397160D01*
X1608688Y397285D01*
X1608480Y397493D01*
X1608396Y397785D01*
X1608480Y398076D01*
X1608730Y398326D01*
X1609105Y398451D01*
X1609521D01*
X1609771Y398535D01*
X1609980Y398743D01*
X1610063Y399035D01*
X1609938Y399326D01*
X1609646Y399535D01*
X1609313Y399618D01*
X1608980Y399535D01*
X1608688Y399326D01*
X1608563Y399035D01*
X1608646Y398743D01*
X1608855Y398535D01*
X1609105Y398451D01*
X1609521D01*
X1609896Y398326D01*
X1610146Y398076D01*
X1610230Y397785D01*
X1610146Y397493D01*
X1609938Y397285D01*
X1609605Y397160D01*
X1609313Y397118D01*
G01X1605296Y399410D02*
X1605546Y399535D01*
X1605838Y399618D01*
X1606171D01*
X1606546Y399493D01*
X1606838Y399285D01*
X1607046Y399035D01*
X1607213Y398618D01*
X1607255Y398243D01*
X1607171Y397868D01*
X1607046Y397618D01*
X1606796Y397368D01*
X1606505Y397201D01*
X1606213Y397118D01*
X1605921D01*
X1605630Y397201D01*
X1605380Y397326D01*
X1605171Y397493D01*
G01X1603905Y399201D02*
X1603655Y399451D01*
X1603363Y399576D01*
X1603030Y399618D01*
X1602613Y399535D01*
X1602321Y399326D01*
X1602238Y399076D01*
X1602280Y398826D01*
X1602446Y398618D01*
X1603280Y398201D01*
X1603655Y397910D01*
X1603905Y397493D01*
X1603988Y397118D01*
X1602238D01*
G01X1600930Y397493D02*
X1600680Y397285D01*
X1600388Y397160D01*
X1600013Y397118D01*
X1599638Y397201D01*
X1599346Y397368D01*
X1599138Y397660D01*
X1599096Y397993D01*
X1599180Y398326D01*
X1599388Y398535D01*
X1599680Y398701D01*
X1599971Y398743D01*
X1600263Y398701D01*
X1600638Y398535D01*
X1600513Y399618D01*
X1599388D01*
G01X1632067Y358517D02*
X1634567D01*
Y359558D01*
X1634442Y359892D01*
X1634275Y360100D01*
X1633942Y360183D01*
X1633609Y360100D01*
X1633400Y359850D01*
X1633275Y359558D01*
Y358517D01*
G01Y359558D02*
X1632067Y360183D01*
G01X1632567Y361533D02*
X1632275Y361783D01*
X1632109Y362117D01*
X1632067Y362492D01*
X1632109Y362825D01*
X1632317Y363158D01*
X1632567Y363367D01*
X1632817Y363408D01*
X1633109Y363325D01*
X1633317Y363033D01*
X1633400Y362742D01*
Y362367D01*
G01Y362742D02*
X1633525Y362992D01*
X1633734Y363200D01*
X1633984Y363283D01*
X1634234Y363200D01*
X1634442Y362992D01*
X1634567Y362617D01*
X1634525Y362242D01*
X1634359Y361867D01*
G01X1632067Y364717D02*
X1634567D01*
Y365758D01*
X1634442Y366092D01*
X1634275Y366300D01*
X1633942Y366383D01*
X1633609Y366300D01*
X1633400Y366050D01*
X1633275Y365758D01*
Y364717D01*
G01Y365758D02*
X1632067Y366383D01*
G01Y369150D02*
X1634567D01*
X1632775Y367608D01*
Y369692D01*
G01X1638033Y347767D02*
Y350267D01*
X1636992D01*
X1636658Y350142D01*
X1636450Y349975D01*
X1636367Y349642D01*
X1636450Y349309D01*
X1636700Y349100D01*
X1636992Y348975D01*
X1638033D01*
G01X1636992D02*
X1636367Y347767D01*
G01X1635017Y348267D02*
X1634767Y347975D01*
X1634433Y347809D01*
X1634058Y347767D01*
X1633725Y347809D01*
X1633392Y348017D01*
X1633183Y348267D01*
X1633142Y348517D01*
X1633225Y348809D01*
X1633517Y349017D01*
X1633808Y349100D01*
X1634183D01*
G01X1633808D02*
X1633558Y349225D01*
X1633350Y349434D01*
X1633267Y349684D01*
X1633350Y349934D01*
X1633558Y350142D01*
X1633933Y350267D01*
X1634308Y350225D01*
X1634683Y350059D01*
G01X1631833Y347767D02*
Y350267D01*
X1630792D01*
X1630458Y350142D01*
X1630250Y349975D01*
X1630167Y349642D01*
X1630250Y349309D01*
X1630500Y349100D01*
X1630792Y348975D01*
X1631833D01*
G01X1630792D02*
X1630167Y347767D01*
G01X1627900D02*
Y350267D01*
X1628400Y349767D01*
G01Y347767D02*
X1627400D01*
G01X1624800Y350267D02*
X1625133Y350184D01*
X1625383Y349975D01*
X1625550Y349725D01*
X1625675Y349392D01*
X1625717Y349017D01*
X1625675Y348642D01*
X1625550Y348309D01*
X1625383Y348059D01*
X1625133Y347850D01*
X1624800Y347767D01*
X1624467Y347850D01*
X1624217Y348059D01*
X1624050Y348309D01*
X1623925Y348642D01*
X1623883Y349017D01*
X1623925Y349392D01*
X1624050Y349725D01*
X1624217Y349975D01*
X1624467Y350184D01*
X1624800Y350267D01*
G01X1640183Y371700D02*
Y374200D01*
X1639142D01*
X1638808Y374075D01*
X1638600Y373908D01*
X1638517Y373575D01*
X1638600Y373242D01*
X1638850Y373033D01*
X1639142Y372908D01*
X1640183D01*
G01X1639142D02*
X1638517Y371700D01*
G01X1636333D02*
X1636250Y372242D01*
X1636125Y372700D01*
X1635958Y373117D01*
X1635750Y373575D01*
X1635417Y374200D01*
X1637083D01*
G01X1632900Y372950D02*
X1632067D01*
Y372200D01*
X1632317Y371950D01*
X1632608Y371783D01*
X1633025Y371700D01*
X1633442Y371783D01*
X1633733Y371950D01*
X1633983Y372200D01*
X1634150Y372492D01*
X1634233Y372825D01*
Y373117D01*
X1634150Y373367D01*
X1633983Y373658D01*
X1633733Y373908D01*
X1633483Y374075D01*
X1633150Y374200D01*
X1632858D01*
X1632525Y374117D01*
X1632275Y373950D01*
G01X1630133Y371700D02*
X1630050Y372242D01*
X1629925Y372700D01*
X1629758Y373117D01*
X1629550Y373575D01*
X1629217Y374200D01*
X1630883D01*
G01X1643838Y399752D02*
Y402252D01*
X1642797D01*
X1642463Y402127D01*
X1642255Y401960D01*
X1642172Y401627D01*
X1642255Y401294D01*
X1642505Y401085D01*
X1642797Y400960D01*
X1643838D01*
G01X1642797D02*
X1642172Y399752D01*
G01X1639988D02*
X1639905Y400294D01*
X1639780Y400752D01*
X1639613Y401169D01*
X1639405Y401627D01*
X1639072Y402252D01*
X1640738D01*
G01X1638055D02*
X1637472Y399752D01*
X1636805Y402252D01*
X1636138Y399752D01*
X1635555Y402252D01*
G01X1634497Y401835D02*
X1634247Y402085D01*
X1633955Y402210D01*
X1633622Y402252D01*
X1633205Y402169D01*
X1632913Y401960D01*
X1632830Y401710D01*
X1632872Y401460D01*
X1633038Y401252D01*
X1633872Y400835D01*
X1634247Y400544D01*
X1634497Y400127D01*
X1634580Y399752D01*
X1632830D01*
G01X1613962Y375481D02*
Y377981D01*
X1612921D01*
X1612587Y377856D01*
X1612379Y377689D01*
X1612296Y377356D01*
X1612379Y377023D01*
X1612629Y376814D01*
X1612921Y376689D01*
X1613962D01*
G01X1612921D02*
X1612296Y375481D01*
G01X1610821Y377564D02*
X1610571Y377814D01*
X1610279Y377939D01*
X1609946Y377981D01*
X1609529Y377898D01*
X1609237Y377689D01*
X1609154Y377439D01*
X1609196Y377189D01*
X1609362Y376981D01*
X1610196Y376564D01*
X1610571Y376273D01*
X1610821Y375856D01*
X1610904Y375481D01*
X1609154D01*
G01X1607887D02*
Y377981D01*
X1605971Y375481D01*
Y377981D01*
G01X1603829Y375481D02*
Y377981D01*
X1604329Y377481D01*
G01Y375481D02*
X1603329D01*
G01X1600812D02*
X1600729Y376023D01*
X1600604Y376481D01*
X1600437Y376898D01*
X1600229Y377356D01*
X1599896Y377981D01*
X1601562D01*
G01X1604871Y356390D02*
Y358890D01*
X1603830D01*
X1603496Y358765D01*
X1603288Y358598D01*
X1603205Y358265D01*
X1603288Y357932D01*
X1603538Y357723D01*
X1603830Y357598D01*
X1604871D01*
G01X1603830D02*
X1603205Y356390D01*
G01X1601730Y358473D02*
X1601480Y358723D01*
X1601188Y358848D01*
X1600855Y358890D01*
X1600438Y358807D01*
X1600146Y358598D01*
X1600063Y358348D01*
X1600105Y358098D01*
X1600271Y357890D01*
X1601105Y357473D01*
X1601480Y357182D01*
X1601730Y356765D01*
X1601813Y356390D01*
X1600063D01*
G01X1598796D02*
Y358890D01*
X1596880Y356390D01*
Y358890D01*
G01X1594738Y356390D02*
Y358890D01*
X1595238Y358390D01*
G01Y356390D02*
X1594238D01*
G01X1591638D02*
X1591346Y356432D01*
X1591013Y356557D01*
X1590805Y356765D01*
X1590721Y357057D01*
X1590805Y357348D01*
X1591055Y357598D01*
X1591430Y357723D01*
X1591846D01*
X1592096Y357807D01*
X1592305Y358015D01*
X1592388Y358307D01*
X1592263Y358598D01*
X1591971Y358807D01*
X1591638Y358890D01*
X1591305Y358807D01*
X1591013Y358598D01*
X1590888Y358307D01*
X1590971Y358015D01*
X1591180Y357807D01*
X1591430Y357723D01*
X1591846D01*
X1592221Y357598D01*
X1592471Y357348D01*
X1592555Y357057D01*
X1592471Y356765D01*
X1592263Y356557D01*
X1591930Y356432D01*
X1591638Y356390D01*
G01X1614033Y382600D02*
Y385100D01*
X1612992D01*
X1612658Y384975D01*
X1612450Y384808D01*
X1612367Y384475D01*
X1612450Y384142D01*
X1612700Y383933D01*
X1612992Y383808D01*
X1614033D01*
G01X1612992D02*
X1612367Y382600D01*
G01X1610892Y384683D02*
X1610642Y384933D01*
X1610350Y385058D01*
X1610017Y385100D01*
X1609600Y385017D01*
X1609308Y384808D01*
X1609225Y384558D01*
X1609267Y384308D01*
X1609433Y384100D01*
X1610267Y383683D01*
X1610642Y383392D01*
X1610892Y382975D01*
X1610975Y382600D01*
X1609225D01*
G01X1607917Y385100D02*
Y383308D01*
X1607750Y382933D01*
X1607417Y382683D01*
X1607000Y382600D01*
X1606583Y382683D01*
X1606250Y382933D01*
X1606083Y383308D01*
Y385100D01*
G01X1604817Y383100D02*
X1604567Y382808D01*
X1604233Y382642D01*
X1603858Y382600D01*
X1603525Y382642D01*
X1603192Y382850D01*
X1602983Y383100D01*
X1602942Y383350D01*
X1603025Y383642D01*
X1603317Y383850D01*
X1603608Y383933D01*
X1603983D01*
G01X1603608D02*
X1603358Y384058D01*
X1603150Y384267D01*
X1603067Y384517D01*
X1603150Y384767D01*
X1603358Y384975D01*
X1603733Y385100D01*
X1604108Y385058D01*
X1604483Y384892D01*
G01X1600800Y385100D02*
X1601133Y385017D01*
X1601383Y384808D01*
X1601550Y384558D01*
X1601675Y384225D01*
X1601717Y383850D01*
X1601675Y383475D01*
X1601550Y383142D01*
X1601383Y382892D01*
X1601133Y382683D01*
X1600800Y382600D01*
X1600467Y382683D01*
X1600217Y382892D01*
X1600050Y383142D01*
X1599925Y383475D01*
X1599883Y383850D01*
X1599925Y384225D01*
X1600050Y384558D01*
X1600217Y384808D01*
X1600467Y385017D01*
X1600800Y385100D01*
G01X1603834Y360178D02*
Y362678D01*
X1602793D01*
X1602459Y362553D01*
X1602251Y362386D01*
X1602168Y362053D01*
X1602251Y361720D01*
X1602501Y361511D01*
X1602793Y361386D01*
X1603834D01*
G01X1602793D02*
X1602168Y360178D01*
G01X1600693Y362261D02*
X1600443Y362511D01*
X1600151Y362636D01*
X1599818Y362678D01*
X1599401Y362595D01*
X1599109Y362386D01*
X1599026Y362136D01*
X1599068Y361886D01*
X1599234Y361678D01*
X1600068Y361261D01*
X1600443Y360970D01*
X1600693Y360553D01*
X1600776Y360178D01*
X1599026D01*
G01X1597759D02*
Y362678D01*
X1595843Y360178D01*
Y362678D01*
G01X1594493Y362261D02*
X1594243Y362511D01*
X1593951Y362636D01*
X1593618Y362678D01*
X1593201Y362595D01*
X1592909Y362386D01*
X1592826Y362136D01*
X1592868Y361886D01*
X1593034Y361678D01*
X1593868Y361261D01*
X1594243Y360970D01*
X1594493Y360553D01*
X1594576Y360178D01*
X1592826D01*
G01X1590101D02*
Y362678D01*
X1591643Y360886D01*
X1589559D01*
G01X1613866Y378952D02*
Y381452D01*
X1612825D01*
X1612491Y381327D01*
X1612283Y381160D01*
X1612200Y380827D01*
X1612283Y380494D01*
X1612533Y380285D01*
X1612825Y380160D01*
X1613866D01*
G01X1612825D02*
X1612200Y378952D01*
G01X1610725Y381035D02*
X1610475Y381285D01*
X1610183Y381410D01*
X1609850Y381452D01*
X1609433Y381369D01*
X1609141Y381160D01*
X1609058Y380910D01*
X1609100Y380660D01*
X1609266Y380452D01*
X1610100Y380035D01*
X1610475Y379744D01*
X1610725Y379327D01*
X1610808Y378952D01*
X1609058D01*
G01X1607791D02*
Y381452D01*
X1605875Y378952D01*
Y381452D01*
G01X1604525Y381035D02*
X1604275Y381285D01*
X1603983Y381410D01*
X1603650Y381452D01*
X1603233Y381369D01*
X1602941Y381160D01*
X1602858Y380910D01*
X1602900Y380660D01*
X1603066Y380452D01*
X1603900Y380035D01*
X1604275Y379744D01*
X1604525Y379327D01*
X1604608Y378952D01*
X1602858D01*
G01X1601550Y379452D02*
X1601300Y379160D01*
X1600966Y378994D01*
X1600591Y378952D01*
X1600258Y378994D01*
X1599925Y379202D01*
X1599716Y379452D01*
X1599675Y379702D01*
X1599758Y379994D01*
X1600050Y380202D01*
X1600341Y380285D01*
X1600716D01*
G01X1600341D02*
X1600091Y380410D01*
X1599883Y380619D01*
X1599800Y380869D01*
X1599883Y381119D01*
X1600091Y381327D01*
X1600466Y381452D01*
X1600841Y381410D01*
X1601216Y381244D01*
G01X1620192Y403317D02*
X1620317Y403067D01*
X1620400Y402775D01*
Y402442D01*
X1620275Y402067D01*
X1620067Y401775D01*
X1619817Y401567D01*
X1619400Y401400D01*
X1619025Y401358D01*
X1618650Y401442D01*
X1618400Y401567D01*
X1618150Y401817D01*
X1617983Y402108D01*
X1617900Y402400D01*
Y402692D01*
X1617983Y402983D01*
X1618108Y403233D01*
X1618275Y403442D01*
G01X1619983Y404708D02*
X1620233Y404958D01*
X1620358Y405250D01*
X1620400Y405583D01*
X1620317Y406000D01*
X1620108Y406292D01*
X1619858Y406375D01*
X1619608Y406333D01*
X1619400Y406167D01*
X1618983Y405333D01*
X1618692Y404958D01*
X1618275Y404708D01*
X1617900Y404625D01*
Y406375D01*
G01Y407642D02*
X1620400D01*
X1617900Y409558D01*
X1620400D01*
G01X1619983Y410908D02*
X1620233Y411158D01*
X1620358Y411450D01*
X1620400Y411783D01*
X1620317Y412200D01*
X1620108Y412492D01*
X1619858Y412575D01*
X1619608Y412533D01*
X1619400Y412367D01*
X1618983Y411533D01*
X1618692Y411158D01*
X1618275Y410908D01*
X1617900Y410825D01*
Y412575D01*
G01Y415300D02*
X1620400D01*
X1618608Y413758D01*
Y415842D01*
G01X1594692Y399317D02*
X1594817Y399067D01*
X1594900Y398775D01*
Y398442D01*
X1594775Y398067D01*
X1594567Y397775D01*
X1594317Y397567D01*
X1593900Y397400D01*
X1593525Y397358D01*
X1593150Y397442D01*
X1592900Y397567D01*
X1592650Y397817D01*
X1592483Y398108D01*
X1592400Y398400D01*
Y398692D01*
X1592483Y398983D01*
X1592608Y399233D01*
X1592775Y399442D01*
G01X1594483Y400708D02*
X1594733Y400958D01*
X1594858Y401250D01*
X1594900Y401583D01*
X1594817Y402000D01*
X1594608Y402292D01*
X1594358Y402375D01*
X1594108Y402333D01*
X1593900Y402167D01*
X1593483Y401333D01*
X1593192Y400958D01*
X1592775Y400708D01*
X1592400Y400625D01*
Y402375D01*
G01Y403642D02*
X1594900D01*
X1592400Y405558D01*
X1594900D01*
G01X1594483Y406908D02*
X1594733Y407158D01*
X1594858Y407450D01*
X1594900Y407783D01*
X1594817Y408200D01*
X1594608Y408492D01*
X1594358Y408575D01*
X1594108Y408533D01*
X1593900Y408367D01*
X1593483Y407533D01*
X1593192Y407158D01*
X1592775Y406908D01*
X1592400Y406825D01*
Y408575D01*
G01X1592900Y409883D02*
X1592608Y410133D01*
X1592442Y410467D01*
X1592400Y410842D01*
X1592442Y411175D01*
X1592650Y411508D01*
X1592900Y411717D01*
X1593150Y411758D01*
X1593442Y411675D01*
X1593650Y411383D01*
X1593733Y411092D01*
Y410717D01*
G01Y411092D02*
X1593858Y411342D01*
X1594067Y411550D01*
X1594317Y411633D01*
X1594567Y411550D01*
X1594775Y411342D01*
X1594900Y410967D01*
X1594858Y410592D01*
X1594692Y410217D01*
G01X1626701Y393760D02*
X1626951Y393885D01*
X1627243Y393968D01*
X1627576D01*
X1627951Y393843D01*
X1628243Y393635D01*
X1628451Y393385D01*
X1628618Y392968D01*
X1628660Y392593D01*
X1628576Y392218D01*
X1628451Y391968D01*
X1628201Y391718D01*
X1627910Y391551D01*
X1627618Y391468D01*
X1627326D01*
X1627035Y391551D01*
X1626785Y391676D01*
X1626576Y391843D01*
G01X1624518Y391468D02*
X1624226Y391510D01*
X1623893Y391635D01*
X1623685Y391843D01*
X1623601Y392135D01*
X1623685Y392426D01*
X1623935Y392676D01*
X1624310Y392801D01*
X1624726D01*
X1624976Y392885D01*
X1625185Y393093D01*
X1625268Y393385D01*
X1625143Y393676D01*
X1624851Y393885D01*
X1624518Y393968D01*
X1624185Y393885D01*
X1623893Y393676D01*
X1623768Y393385D01*
X1623851Y393093D01*
X1624060Y392885D01*
X1624310Y392801D01*
X1624726D01*
X1625101Y392676D01*
X1625351Y392426D01*
X1625435Y392135D01*
X1625351Y391843D01*
X1625143Y391635D01*
X1624810Y391510D01*
X1624518Y391468D01*
G01X1620501Y393760D02*
X1620751Y393885D01*
X1621043Y393968D01*
X1621376D01*
X1621751Y393843D01*
X1622043Y393635D01*
X1622251Y393385D01*
X1622418Y392968D01*
X1622460Y392593D01*
X1622376Y392218D01*
X1622251Y391968D01*
X1622001Y391718D01*
X1621710Y391551D01*
X1621418Y391468D01*
X1621126D01*
X1620835Y391551D01*
X1620585Y391676D01*
X1620376Y391843D01*
G01X1619235Y391968D02*
X1618985Y391676D01*
X1618651Y391510D01*
X1618276Y391468D01*
X1617943Y391510D01*
X1617610Y391718D01*
X1617401Y391968D01*
X1617360Y392218D01*
X1617443Y392510D01*
X1617735Y392718D01*
X1618026Y392801D01*
X1618401D01*
G01X1618026D02*
X1617776Y392926D01*
X1617568Y393135D01*
X1617485Y393385D01*
X1617568Y393635D01*
X1617776Y393843D01*
X1618151Y393968D01*
X1618526Y393926D01*
X1618901Y393760D01*
G01X1626933Y390192D02*
X1627183Y390317D01*
X1627475Y390400D01*
X1627808D01*
X1628183Y390275D01*
X1628475Y390067D01*
X1628683Y389817D01*
X1628850Y389400D01*
X1628892Y389025D01*
X1628808Y388650D01*
X1628683Y388400D01*
X1628433Y388150D01*
X1628142Y387983D01*
X1627850Y387900D01*
X1627558D01*
X1627267Y387983D01*
X1627017Y388108D01*
X1626808Y388275D01*
G01X1624750Y387900D02*
X1624458Y387942D01*
X1624125Y388067D01*
X1623917Y388275D01*
X1623833Y388567D01*
X1623917Y388858D01*
X1624167Y389108D01*
X1624542Y389233D01*
X1624958D01*
X1625208Y389317D01*
X1625417Y389525D01*
X1625500Y389817D01*
X1625375Y390108D01*
X1625083Y390317D01*
X1624750Y390400D01*
X1624417Y390317D01*
X1624125Y390108D01*
X1624000Y389817D01*
X1624083Y389525D01*
X1624292Y389317D01*
X1624542Y389233D01*
X1624958D01*
X1625333Y389108D01*
X1625583Y388858D01*
X1625667Y388567D01*
X1625583Y388275D01*
X1625375Y388067D01*
X1625042Y387942D01*
X1624750Y387900D01*
G01X1620733Y390192D02*
X1620983Y390317D01*
X1621275Y390400D01*
X1621608D01*
X1621983Y390275D01*
X1622275Y390067D01*
X1622483Y389817D01*
X1622650Y389400D01*
X1622692Y389025D01*
X1622608Y388650D01*
X1622483Y388400D01*
X1622233Y388150D01*
X1621942Y387983D01*
X1621650Y387900D01*
X1621358D01*
X1621067Y387983D01*
X1620817Y388108D01*
X1620608Y388275D01*
G01X1618050Y387900D02*
Y390400D01*
X1619592Y388608D01*
X1617508D01*
G01X1616500Y375650D02*
X1616542Y375317D01*
X1616708Y375025D01*
X1616958Y374775D01*
X1617250Y374608D01*
X1617583Y374525D01*
X1617917D01*
X1618250Y374608D01*
X1618542Y374775D01*
X1618792Y375025D01*
X1618958Y375317D01*
X1619000Y375650D01*
X1618958Y375983D01*
X1618792Y376275D01*
X1618542Y376525D01*
X1618250Y376692D01*
X1617917Y376775D01*
X1617583D01*
X1617250Y376692D01*
X1616958Y376525D01*
X1616708Y376275D01*
X1616542Y375983D01*
X1616500Y375650D01*
G01X1617167Y375983D02*
X1616500Y376483D01*
G01X1617000Y377833D02*
X1616708Y378083D01*
X1616542Y378417D01*
X1616500Y378792D01*
X1616542Y379125D01*
X1616750Y379458D01*
X1617000Y379667D01*
X1617250Y379708D01*
X1617542Y379625D01*
X1617750Y379333D01*
X1617833Y379042D01*
Y378667D01*
G01Y379042D02*
X1617958Y379292D01*
X1618167Y379500D01*
X1618417Y379583D01*
X1618667Y379500D01*
X1618875Y379292D01*
X1619000Y378917D01*
X1618958Y378542D01*
X1618792Y378167D01*
G01X1619000Y380933D02*
X1617208D01*
X1616833Y381100D01*
X1616583Y381433D01*
X1616500Y381850D01*
X1616583Y382267D01*
X1616833Y382600D01*
X1617208Y382767D01*
X1619000D01*
G01X1616500Y384950D02*
X1619000D01*
X1618500Y384450D01*
G01X1616500D02*
Y385450D01*
G01X1607150Y345300D02*
X1607483Y345342D01*
X1607775Y345508D01*
X1608025Y345758D01*
X1608192Y346050D01*
X1608275Y346383D01*
Y346717D01*
X1608192Y347050D01*
X1608025Y347342D01*
X1607775Y347592D01*
X1607483Y347758D01*
X1607150Y347800D01*
X1606817Y347758D01*
X1606525Y347592D01*
X1606275Y347342D01*
X1606108Y347050D01*
X1606025Y346717D01*
Y346383D01*
X1606108Y346050D01*
X1606275Y345758D01*
X1606525Y345508D01*
X1606817Y345342D01*
X1607150Y345300D01*
G01X1606817Y345967D02*
X1606317Y345300D01*
G01X1604133D02*
X1604050Y345842D01*
X1603925Y346300D01*
X1603758Y346717D01*
X1603550Y347175D01*
X1603217Y347800D01*
X1604883D01*
G01X1600117Y345300D02*
X1601783D01*
Y347800D01*
X1600117D01*
G01X1600783Y346592D02*
X1601783D01*
G01X1598642Y347383D02*
X1598392Y347633D01*
X1598100Y347758D01*
X1597767Y347800D01*
X1597350Y347717D01*
X1597058Y347508D01*
X1596975Y347258D01*
X1597017Y347008D01*
X1597183Y346800D01*
X1598017Y346383D01*
X1598392Y346092D01*
X1598642Y345675D01*
X1598725Y345300D01*
X1596975D01*
G01X1607350Y352200D02*
X1607683Y352242D01*
X1607975Y352408D01*
X1608225Y352658D01*
X1608392Y352950D01*
X1608475Y353283D01*
Y353617D01*
X1608392Y353950D01*
X1608225Y354242D01*
X1607975Y354492D01*
X1607683Y354658D01*
X1607350Y354700D01*
X1607017Y354658D01*
X1606725Y354492D01*
X1606475Y354242D01*
X1606308Y353950D01*
X1606225Y353617D01*
Y353283D01*
X1606308Y352950D01*
X1606475Y352658D01*
X1606725Y352408D01*
X1607017Y352242D01*
X1607350Y352200D01*
G01X1607017Y352867D02*
X1606517Y352200D01*
G01X1604333D02*
X1604250Y352742D01*
X1604125Y353200D01*
X1603958Y353617D01*
X1603750Y354075D01*
X1603417Y354700D01*
X1605083D01*
G01X1600317Y352200D02*
X1601983D01*
Y354700D01*
X1600317D01*
G01X1600983Y353492D02*
X1601983D01*
G01X1598050Y352200D02*
Y354700D01*
X1598550Y354200D01*
G01Y352200D02*
X1597550D01*
G01X1657244Y405386D02*
Y403594D01*
X1657077Y403219D01*
X1656744Y402969D01*
X1656327Y402886D01*
X1655910Y402969D01*
X1655577Y403219D01*
X1655410Y403594D01*
Y405386D01*
G01X1653310Y402886D02*
X1653227Y403428D01*
X1653102Y403886D01*
X1652935Y404303D01*
X1652727Y404761D01*
X1652394Y405386D01*
X1654060D01*
G01X1651377D02*
X1650794Y402886D01*
X1650127Y405386D01*
X1649460Y402886D01*
X1648877Y405386D01*
G01X1647027Y402886D02*
Y405386D01*
X1647527Y404886D01*
G01Y402886D02*
X1646527D01*
G01X1648100Y443700D02*
X1650400D01*
Y448200D01*
X1664036D01*
G01X1615934Y433256D02*
X1616059Y433006D01*
X1616142Y432714D01*
Y432381D01*
X1616017Y432006D01*
X1615809Y431714D01*
X1615559Y431506D01*
X1615142Y431339D01*
X1614767Y431297D01*
X1614392Y431381D01*
X1614142Y431506D01*
X1613892Y431756D01*
X1613725Y432047D01*
X1613642Y432339D01*
Y432631D01*
X1613725Y432922D01*
X1613850Y433172D01*
X1614017Y433381D01*
G01X1615725Y434647D02*
X1615975Y434897D01*
X1616100Y435189D01*
X1616142Y435522D01*
X1616059Y435939D01*
X1615850Y436231D01*
X1615600Y436314D01*
X1615350Y436272D01*
X1615142Y436106D01*
X1614725Y435272D01*
X1614434Y434897D01*
X1614017Y434647D01*
X1613642Y434564D01*
Y436314D01*
G01Y437456D02*
X1616142D01*
X1614059Y438539D01*
X1616142Y439622D01*
X1613642D01*
G01Y441639D02*
X1616142D01*
X1615642Y441139D01*
G01X1613642D02*
Y442139D01*
G01Y444656D02*
X1614184Y444739D01*
X1614642Y444864D01*
X1615059Y445031D01*
X1615517Y445239D01*
X1616142Y445572D01*
Y443906D01*
G01X1619534Y433456D02*
X1619659Y433206D01*
X1619742Y432914D01*
Y432581D01*
X1619617Y432206D01*
X1619409Y431914D01*
X1619159Y431706D01*
X1618742Y431539D01*
X1618367Y431497D01*
X1617992Y431581D01*
X1617742Y431706D01*
X1617492Y431956D01*
X1617325Y432247D01*
X1617242Y432539D01*
Y432831D01*
X1617325Y433122D01*
X1617450Y433372D01*
X1617617Y433581D01*
G01X1619325Y434847D02*
X1619575Y435097D01*
X1619700Y435389D01*
X1619742Y435722D01*
X1619659Y436139D01*
X1619450Y436431D01*
X1619200Y436514D01*
X1618950Y436472D01*
X1618742Y436306D01*
X1618325Y435472D01*
X1618034Y435097D01*
X1617617Y434847D01*
X1617242Y434764D01*
Y436514D01*
G01Y437656D02*
X1619742D01*
X1617659Y438739D01*
X1619742Y439822D01*
X1617242D01*
G01Y441839D02*
X1619742D01*
X1619242Y441339D01*
G01X1617242D02*
Y442339D01*
G01Y444939D02*
X1619742D01*
X1619242Y444439D01*
G01X1617242D02*
Y445439D01*
G01X1610933Y432600D02*
Y435100D01*
X1609892D01*
X1609558Y434975D01*
X1609350Y434808D01*
X1609267Y434475D01*
X1609350Y434142D01*
X1609600Y433933D01*
X1609892Y433808D01*
X1610933D01*
G01X1609892D02*
X1609267Y432600D01*
G01X1607792Y433642D02*
X1607500Y433933D01*
X1607250Y434100D01*
X1606917Y434183D01*
X1606625Y434100D01*
X1606417Y433933D01*
X1606250Y433683D01*
X1606208Y433392D01*
X1606250Y433142D01*
X1606417Y432892D01*
X1606667Y432683D01*
X1606958Y432600D01*
X1607292Y432683D01*
X1607583Y432933D01*
X1607750Y433308D01*
X1607792Y433725D01*
X1607708Y434267D01*
X1607583Y434558D01*
X1607375Y434850D01*
X1607083Y435058D01*
X1606792Y435100D01*
X1606500Y435017D01*
X1606292Y434808D01*
G01X1605150Y435100D02*
X1604567Y432600D01*
X1603900Y435100D01*
X1603233Y432600D01*
X1602650Y435100D01*
G01X1601592Y434683D02*
X1601342Y434933D01*
X1601050Y435058D01*
X1600717Y435100D01*
X1600300Y435017D01*
X1600008Y434808D01*
X1599925Y434558D01*
X1599967Y434308D01*
X1600133Y434100D01*
X1600967Y433683D01*
X1601342Y433392D01*
X1601592Y432975D01*
X1601675Y432600D01*
X1599925D01*
G01X1597200D02*
Y435100D01*
X1598742Y433308D01*
X1596658D01*
G01X1641157Y425373D02*
X1643657D01*
Y426414D01*
X1643532Y426748D01*
X1643365Y426956D01*
X1643032Y427039D01*
X1642699Y426956D01*
X1642490Y426706D01*
X1642365Y426414D01*
Y425373D01*
G01Y426414D02*
X1641157Y427039D01*
G01Y429223D02*
X1641699Y429306D01*
X1642157Y429431D01*
X1642574Y429598D01*
X1643032Y429806D01*
X1643657Y430139D01*
Y428473D01*
G01X1643449Y433323D02*
X1643574Y433073D01*
X1643657Y432781D01*
Y432448D01*
X1643532Y432073D01*
X1643324Y431781D01*
X1643074Y431573D01*
X1642657Y431406D01*
X1642282Y431364D01*
X1641907Y431448D01*
X1641657Y431573D01*
X1641407Y431823D01*
X1641240Y432114D01*
X1641157Y432406D01*
Y432698D01*
X1641240Y432989D01*
X1641365Y433239D01*
X1641532Y433448D01*
G01X1641157Y435506D02*
X1643657D01*
X1643157Y435006D01*
G01X1641157D02*
Y436006D01*
G01X1641657Y437689D02*
X1641365Y437939D01*
X1641199Y438273D01*
X1641157Y438648D01*
X1641199Y438981D01*
X1641407Y439314D01*
X1641657Y439523D01*
X1641907Y439564D01*
X1642199Y439481D01*
X1642407Y439189D01*
X1642490Y438898D01*
Y438523D01*
G01Y438898D02*
X1642615Y439148D01*
X1642824Y439356D01*
X1643074Y439439D01*
X1643324Y439356D01*
X1643532Y439148D01*
X1643657Y438773D01*
X1643615Y438398D01*
X1643449Y438023D01*
G01X1635186Y425428D02*
X1637686D01*
Y426469D01*
X1637561Y426803D01*
X1637394Y427011D01*
X1637061Y427094D01*
X1636728Y427011D01*
X1636519Y426761D01*
X1636394Y426469D01*
Y425428D01*
G01Y426469D02*
X1635186Y427094D01*
G01Y429278D02*
X1635728Y429361D01*
X1636186Y429486D01*
X1636603Y429653D01*
X1637061Y429861D01*
X1637686Y430194D01*
Y428528D01*
G01X1635186Y431544D02*
X1637686D01*
Y432378D01*
X1637561Y432711D01*
X1637394Y432961D01*
X1637144Y433169D01*
X1636853Y433336D01*
X1636436Y433378D01*
X1636019Y433336D01*
X1635728Y433169D01*
X1635478Y432961D01*
X1635311Y432711D01*
X1635186Y432378D01*
Y431544D01*
G01X1635686Y434644D02*
X1635394Y434894D01*
X1635228Y435228D01*
X1635186Y435603D01*
X1635228Y435936D01*
X1635436Y436269D01*
X1635686Y436478D01*
X1635936Y436519D01*
X1636228Y436436D01*
X1636436Y436144D01*
X1636519Y435853D01*
Y435478D01*
G01Y435853D02*
X1636644Y436103D01*
X1636853Y436311D01*
X1637103Y436394D01*
X1637353Y436311D01*
X1637561Y436103D01*
X1637686Y435728D01*
X1637644Y435353D01*
X1637478Y434978D01*
G01X1631386Y425428D02*
X1633886D01*
Y426469D01*
X1633761Y426803D01*
X1633594Y427011D01*
X1633261Y427094D01*
X1632928Y427011D01*
X1632719Y426761D01*
X1632594Y426469D01*
Y425428D01*
G01Y426469D02*
X1631386Y427094D01*
G01Y429278D02*
X1631928Y429361D01*
X1632386Y429486D01*
X1632803Y429653D01*
X1633261Y429861D01*
X1633886Y430194D01*
Y428528D01*
G01X1631386Y431544D02*
X1633886D01*
Y432378D01*
X1633761Y432711D01*
X1633594Y432961D01*
X1633344Y433169D01*
X1633053Y433336D01*
X1632636Y433378D01*
X1632219Y433336D01*
X1631928Y433169D01*
X1631678Y432961D01*
X1631511Y432711D01*
X1631386Y432378D01*
Y431544D01*
G01X1631761Y434644D02*
X1631553Y434894D01*
X1631428Y435186D01*
X1631386Y435561D01*
X1631469Y435936D01*
X1631636Y436228D01*
X1631928Y436436D01*
X1632261Y436478D01*
X1632594Y436394D01*
X1632803Y436186D01*
X1632969Y435894D01*
X1633011Y435603D01*
X1632969Y435311D01*
X1632803Y434936D01*
X1633886Y435061D01*
Y436186D01*
G01X1645174Y418845D02*
Y421345D01*
X1644133D01*
X1643799Y421220D01*
X1643591Y421053D01*
X1643508Y420720D01*
X1643591Y420387D01*
X1643841Y420178D01*
X1644133Y420053D01*
X1645174D01*
G01X1644133D02*
X1643508Y418845D01*
G01X1641324D02*
X1641241Y419387D01*
X1641116Y419845D01*
X1640949Y420262D01*
X1640741Y420720D01*
X1640408Y421345D01*
X1642074D01*
G01X1637224Y421137D02*
X1637474Y421262D01*
X1637766Y421345D01*
X1638099D01*
X1638474Y421220D01*
X1638766Y421012D01*
X1638974Y420762D01*
X1639141Y420345D01*
X1639183Y419970D01*
X1639099Y419595D01*
X1638974Y419345D01*
X1638724Y419095D01*
X1638433Y418928D01*
X1638141Y418845D01*
X1637849D01*
X1637558Y418928D01*
X1637308Y419053D01*
X1637099Y419220D01*
G01X1635041Y418845D02*
Y421345D01*
X1635541Y420845D01*
G01Y418845D02*
X1634541D01*
G01X1632024D02*
X1631941Y419387D01*
X1631816Y419845D01*
X1631649Y420262D01*
X1631441Y420720D01*
X1631108Y421345D01*
X1632774D01*
G01X1648925Y425088D02*
X1651425D01*
Y426129D01*
X1651300Y426463D01*
X1651133Y426671D01*
X1650800Y426754D01*
X1650467Y426671D01*
X1650258Y426421D01*
X1650133Y426129D01*
Y425088D01*
G01Y426129D02*
X1648925Y426754D01*
G01Y428938D02*
X1649467Y429021D01*
X1649925Y429146D01*
X1650342Y429313D01*
X1650800Y429521D01*
X1651425Y429854D01*
Y428188D01*
G01X1648925Y431204D02*
X1651425D01*
Y432038D01*
X1651300Y432371D01*
X1651133Y432621D01*
X1650883Y432829D01*
X1650592Y432996D01*
X1650175Y433038D01*
X1649758Y432996D01*
X1649467Y432829D01*
X1649217Y432621D01*
X1649050Y432371D01*
X1648925Y432038D01*
Y431204D01*
G01X1649967Y434429D02*
X1650258Y434721D01*
X1650425Y434971D01*
X1650508Y435304D01*
X1650425Y435596D01*
X1650258Y435804D01*
X1650008Y435971D01*
X1649717Y436013D01*
X1649467Y435971D01*
X1649217Y435804D01*
X1649008Y435554D01*
X1648925Y435263D01*
X1649008Y434929D01*
X1649258Y434638D01*
X1649633Y434471D01*
X1650050Y434429D01*
X1650592Y434513D01*
X1650883Y434638D01*
X1651175Y434846D01*
X1651383Y435138D01*
X1651425Y435429D01*
X1651342Y435721D01*
X1651133Y435929D01*
G01X1645015Y425207D02*
X1647515D01*
Y426248D01*
X1647390Y426582D01*
X1647223Y426790D01*
X1646890Y426873D01*
X1646557Y426790D01*
X1646348Y426540D01*
X1646223Y426248D01*
Y425207D01*
G01Y426248D02*
X1645015Y426873D01*
G01Y429057D02*
X1645557Y429140D01*
X1646015Y429265D01*
X1646432Y429432D01*
X1646890Y429640D01*
X1647515Y429973D01*
Y428307D01*
G01X1645015Y431323D02*
X1647515D01*
Y432157D01*
X1647390Y432490D01*
X1647223Y432740D01*
X1646973Y432948D01*
X1646682Y433115D01*
X1646265Y433157D01*
X1645848Y433115D01*
X1645557Y432948D01*
X1645307Y432740D01*
X1645140Y432490D01*
X1645015Y432157D01*
Y431323D01*
G01Y435840D02*
X1647515D01*
X1645723Y434298D01*
Y436382D01*
G01X1646460Y408217D02*
X1648960D01*
Y409258D01*
X1648835Y409592D01*
X1648668Y409800D01*
X1648335Y409883D01*
X1648002Y409800D01*
X1647793Y409550D01*
X1647668Y409258D01*
Y408217D01*
G01Y409258D02*
X1646460Y409883D01*
G01X1646960Y411233D02*
X1646668Y411483D01*
X1646502Y411817D01*
X1646460Y412192D01*
X1646502Y412525D01*
X1646710Y412858D01*
X1646960Y413067D01*
X1647210Y413108D01*
X1647502Y413025D01*
X1647710Y412733D01*
X1647793Y412442D01*
Y412067D01*
G01Y412442D02*
X1647918Y412692D01*
X1648127Y412900D01*
X1648377Y412983D01*
X1648627Y412900D01*
X1648835Y412692D01*
X1648960Y412317D01*
X1648918Y411942D01*
X1648752Y411567D01*
G01X1646460Y414292D02*
X1648960D01*
X1646460Y416208D01*
X1648960D01*
G01X1646960Y417433D02*
X1646668Y417683D01*
X1646502Y418017D01*
X1646460Y418392D01*
X1646502Y418725D01*
X1646710Y419058D01*
X1646960Y419267D01*
X1647210Y419308D01*
X1647502Y419225D01*
X1647710Y418933D01*
X1647793Y418642D01*
Y418267D01*
G01Y418642D02*
X1647918Y418892D01*
X1648127Y419100D01*
X1648377Y419183D01*
X1648627Y419100D01*
X1648835Y418892D01*
X1648960Y418517D01*
X1648918Y418142D01*
X1648752Y417767D01*
G01X1648960Y421450D02*
X1648877Y421117D01*
X1648668Y420867D01*
X1648418Y420700D01*
X1648085Y420575D01*
X1647710Y420533D01*
X1647335Y420575D01*
X1647002Y420700D01*
X1646752Y420867D01*
X1646543Y421117D01*
X1646460Y421450D01*
X1646543Y421783D01*
X1646752Y422033D01*
X1647002Y422200D01*
X1647335Y422325D01*
X1647710Y422367D01*
X1648085Y422325D01*
X1648418Y422200D01*
X1648668Y422033D01*
X1648877Y421783D01*
X1648960Y421450D01*
G01X1643292Y414876D02*
Y417376D01*
X1642251D01*
X1641917Y417251D01*
X1641709Y417084D01*
X1641626Y416751D01*
X1641709Y416418D01*
X1641959Y416209D01*
X1642251Y416084D01*
X1643292D01*
G01X1642251D02*
X1641626Y414876D01*
G01X1639442D02*
X1639359Y415418D01*
X1639234Y415876D01*
X1639067Y416293D01*
X1638859Y416751D01*
X1638526Y417376D01*
X1640192D01*
G01X1637509D02*
X1636926Y414876D01*
X1636259Y417376D01*
X1635592Y414876D01*
X1635009Y417376D01*
G01X1634076Y415376D02*
X1633826Y415084D01*
X1633492Y414918D01*
X1633117Y414876D01*
X1632784Y414918D01*
X1632451Y415126D01*
X1632242Y415376D01*
X1632201Y415626D01*
X1632284Y415918D01*
X1632576Y416126D01*
X1632867Y416209D01*
X1633242D01*
G01X1632867D02*
X1632617Y416334D01*
X1632409Y416543D01*
X1632326Y416793D01*
X1632409Y417043D01*
X1632617Y417251D01*
X1632992Y417376D01*
X1633367Y417334D01*
X1633742Y417168D01*
G01X1623135Y422585D02*
X1625635D01*
Y423626D01*
X1625510Y423960D01*
X1625343Y424168D01*
X1625010Y424251D01*
X1624677Y424168D01*
X1624468Y423918D01*
X1624343Y423626D01*
Y422585D01*
G01Y423626D02*
X1623135Y424251D01*
G01Y426435D02*
X1623677Y426518D01*
X1624135Y426643D01*
X1624552Y426810D01*
X1625010Y427018D01*
X1625635Y427351D01*
Y425685D01*
G01Y428368D02*
X1623135Y428951D01*
X1625635Y429618D01*
X1623135Y430285D01*
X1625635Y430868D01*
G01X1625218Y431926D02*
X1625468Y432176D01*
X1625593Y432468D01*
X1625635Y432801D01*
X1625552Y433218D01*
X1625343Y433510D01*
X1625093Y433593D01*
X1624843Y433551D01*
X1624635Y433385D01*
X1624218Y432551D01*
X1623927Y432176D01*
X1623510Y431926D01*
X1623135Y431843D01*
Y433593D01*
G01X1625218Y435026D02*
X1625468Y435276D01*
X1625593Y435568D01*
X1625635Y435901D01*
X1625552Y436318D01*
X1625343Y436610D01*
X1625093Y436693D01*
X1624843Y436651D01*
X1624635Y436485D01*
X1624218Y435651D01*
X1623927Y435276D01*
X1623510Y435026D01*
X1623135Y434943D01*
Y436693D01*
G01X1615790Y448621D02*
X1615915Y448371D01*
X1615998Y448079D01*
Y447746D01*
X1615873Y447371D01*
X1615665Y447079D01*
X1615415Y446871D01*
X1614998Y446704D01*
X1614623Y446662D01*
X1614248Y446746D01*
X1613998Y446871D01*
X1613748Y447121D01*
X1613581Y447412D01*
X1613498Y447704D01*
Y447996D01*
X1613581Y448287D01*
X1613706Y448537D01*
X1613873Y448746D01*
G01X1615581Y450012D02*
X1615831Y450262D01*
X1615956Y450554D01*
X1615998Y450887D01*
X1615915Y451304D01*
X1615706Y451596D01*
X1615456Y451679D01*
X1615206Y451637D01*
X1614998Y451471D01*
X1614581Y450637D01*
X1614290Y450262D01*
X1613873Y450012D01*
X1613498Y449929D01*
Y451679D01*
G01Y452821D02*
X1615998D01*
X1613915Y453904D01*
X1615998Y454987D01*
X1613498D01*
G01Y457004D02*
X1615998D01*
X1615498Y456504D01*
G01X1613498D02*
Y457504D01*
G01X1613998Y459187D02*
X1613706Y459437D01*
X1613540Y459771D01*
X1613498Y460146D01*
X1613540Y460479D01*
X1613748Y460812D01*
X1613998Y461021D01*
X1614248Y461062D01*
X1614540Y460979D01*
X1614748Y460687D01*
X1614831Y460396D01*
Y460021D01*
G01Y460396D02*
X1614956Y460646D01*
X1615165Y460854D01*
X1615415Y460937D01*
X1615665Y460854D01*
X1615873Y460646D01*
X1615998Y460271D01*
X1615956Y459896D01*
X1615790Y459521D01*
G01X1619284Y464734D02*
X1619409Y464484D01*
X1619492Y464192D01*
Y463859D01*
X1619367Y463484D01*
X1619159Y463192D01*
X1618909Y462984D01*
X1618492Y462817D01*
X1618117Y462775D01*
X1617742Y462859D01*
X1617492Y462984D01*
X1617242Y463234D01*
X1617075Y463525D01*
X1616992Y463817D01*
Y464109D01*
X1617075Y464400D01*
X1617200Y464650D01*
X1617367Y464859D01*
G01X1619075Y466125D02*
X1619325Y466375D01*
X1619450Y466667D01*
X1619492Y467000D01*
X1619409Y467417D01*
X1619200Y467709D01*
X1618950Y467792D01*
X1618700Y467750D01*
X1618492Y467584D01*
X1618075Y466750D01*
X1617784Y466375D01*
X1617367Y466125D01*
X1616992Y466042D01*
Y467792D01*
G01Y468934D02*
X1619492D01*
X1617409Y470017D01*
X1619492Y471100D01*
X1616992D01*
G01Y473117D02*
X1619492D01*
X1618992Y472617D01*
G01X1616992D02*
Y473617D01*
G01X1619492Y476217D02*
X1619409Y475884D01*
X1619200Y475634D01*
X1618950Y475467D01*
X1618617Y475342D01*
X1618242Y475300D01*
X1617867Y475342D01*
X1617534Y475467D01*
X1617284Y475634D01*
X1617075Y475884D01*
X1616992Y476217D01*
X1617075Y476550D01*
X1617284Y476800D01*
X1617534Y476967D01*
X1617867Y477092D01*
X1618242Y477134D01*
X1618617Y477092D01*
X1618950Y476967D01*
X1619200Y476800D01*
X1619409Y476550D01*
X1619492Y476217D01*
G01X1619033Y448402D02*
X1619158Y448152D01*
X1619241Y447860D01*
Y447527D01*
X1619116Y447152D01*
X1618908Y446860D01*
X1618658Y446652D01*
X1618241Y446485D01*
X1617866Y446443D01*
X1617491Y446527D01*
X1617241Y446652D01*
X1616991Y446902D01*
X1616824Y447193D01*
X1616741Y447485D01*
Y447777D01*
X1616824Y448068D01*
X1616949Y448318D01*
X1617116Y448527D01*
G01X1618824Y449793D02*
X1619074Y450043D01*
X1619199Y450335D01*
X1619241Y450668D01*
X1619158Y451085D01*
X1618949Y451377D01*
X1618699Y451460D01*
X1618449Y451418D01*
X1618241Y451252D01*
X1617824Y450418D01*
X1617533Y450043D01*
X1617116Y449793D01*
X1616741Y449710D01*
Y451460D01*
G01Y452602D02*
X1619241D01*
X1617158Y453685D01*
X1619241Y454768D01*
X1616741D01*
G01Y456785D02*
X1619241D01*
X1618741Y456285D01*
G01X1616741D02*
Y457285D01*
G01X1618824Y459093D02*
X1619074Y459343D01*
X1619199Y459635D01*
X1619241Y459968D01*
X1619158Y460385D01*
X1618949Y460677D01*
X1618699Y460760D01*
X1618449Y460718D01*
X1618241Y460552D01*
X1617824Y459718D01*
X1617533Y459343D01*
X1617116Y459093D01*
X1616741Y459010D01*
Y460760D01*
G01X1606492Y415417D02*
X1606617Y415167D01*
X1606700Y414875D01*
Y414542D01*
X1606575Y414167D01*
X1606367Y413875D01*
X1606117Y413667D01*
X1605700Y413500D01*
X1605325Y413458D01*
X1604950Y413542D01*
X1604700Y413667D01*
X1604450Y413917D01*
X1604283Y414208D01*
X1604200Y414500D01*
Y414792D01*
X1604283Y415083D01*
X1604408Y415333D01*
X1604575Y415542D01*
G01X1606283Y416808D02*
X1606533Y417058D01*
X1606658Y417350D01*
X1606700Y417683D01*
X1606617Y418100D01*
X1606408Y418392D01*
X1606158Y418475D01*
X1605908Y418433D01*
X1605700Y418267D01*
X1605283Y417433D01*
X1604992Y417058D01*
X1604575Y416808D01*
X1604200Y416725D01*
Y418475D01*
G01Y419742D02*
X1606700D01*
X1604200Y421658D01*
X1606700D01*
G01X1604200Y423800D02*
X1606700D01*
X1606200Y423300D01*
G01X1604200D02*
Y424300D01*
G01Y426817D02*
X1604742Y426900D01*
X1605200Y427025D01*
X1605617Y427192D01*
X1606075Y427400D01*
X1606700Y427733D01*
Y426067D01*
G01X1616655Y415492D02*
X1616780Y415242D01*
X1616863Y414950D01*
Y414617D01*
X1616738Y414242D01*
X1616530Y413950D01*
X1616280Y413742D01*
X1615863Y413575D01*
X1615488Y413533D01*
X1615113Y413617D01*
X1614863Y413742D01*
X1614613Y413992D01*
X1614446Y414283D01*
X1614363Y414575D01*
Y414867D01*
X1614446Y415158D01*
X1614571Y415408D01*
X1614738Y415617D01*
G01X1616446Y416883D02*
X1616696Y417133D01*
X1616821Y417425D01*
X1616863Y417758D01*
X1616780Y418175D01*
X1616571Y418467D01*
X1616321Y418550D01*
X1616071Y418508D01*
X1615863Y418342D01*
X1615446Y417508D01*
X1615155Y417133D01*
X1614738Y416883D01*
X1614363Y416800D01*
Y418550D01*
G01Y419817D02*
X1616863D01*
X1614363Y421733D01*
X1616863D01*
G01X1616446Y423083D02*
X1616696Y423333D01*
X1616821Y423625D01*
X1616863Y423958D01*
X1616780Y424375D01*
X1616571Y424667D01*
X1616321Y424750D01*
X1616071Y424708D01*
X1615863Y424542D01*
X1615446Y423708D01*
X1615155Y423333D01*
X1614738Y423083D01*
X1614363Y423000D01*
Y424750D01*
G01Y426975D02*
X1616863D01*
X1616363Y426475D01*
G01X1614363D02*
Y427475D01*
G01X1610292Y415317D02*
X1610417Y415067D01*
X1610500Y414775D01*
Y414442D01*
X1610375Y414067D01*
X1610167Y413775D01*
X1609917Y413567D01*
X1609500Y413400D01*
X1609125Y413358D01*
X1608750Y413442D01*
X1608500Y413567D01*
X1608250Y413817D01*
X1608083Y414108D01*
X1608000Y414400D01*
Y414692D01*
X1608083Y414983D01*
X1608208Y415233D01*
X1608375Y415442D01*
G01X1610083Y416708D02*
X1610333Y416958D01*
X1610458Y417250D01*
X1610500Y417583D01*
X1610417Y418000D01*
X1610208Y418292D01*
X1609958Y418375D01*
X1609708Y418333D01*
X1609500Y418167D01*
X1609083Y417333D01*
X1608792Y416958D01*
X1608375Y416708D01*
X1608000Y416625D01*
Y418375D01*
G01Y419642D02*
X1610500D01*
X1608000Y421558D01*
X1610500D01*
G01X1610083Y422908D02*
X1610333Y423158D01*
X1610458Y423450D01*
X1610500Y423783D01*
X1610417Y424200D01*
X1610208Y424492D01*
X1609958Y424575D01*
X1609708Y424533D01*
X1609500Y424367D01*
X1609083Y423533D01*
X1608792Y423158D01*
X1608375Y422908D01*
X1608000Y422825D01*
Y424575D01*
G01X1610083Y426008D02*
X1610333Y426258D01*
X1610458Y426550D01*
X1610500Y426883D01*
X1610417Y427300D01*
X1610208Y427592D01*
X1609958Y427675D01*
X1609708Y427633D01*
X1609500Y427467D01*
X1609083Y426633D01*
X1608792Y426258D01*
X1608375Y426008D01*
X1608000Y425925D01*
Y427675D01*
G01X1641888Y406244D02*
X1642138Y406369D01*
X1642430Y406452D01*
X1642763D01*
X1643138Y406327D01*
X1643430Y406119D01*
X1643638Y405869D01*
X1643805Y405452D01*
X1643847Y405077D01*
X1643763Y404702D01*
X1643638Y404452D01*
X1643388Y404202D01*
X1643097Y404035D01*
X1642805Y403952D01*
X1642513D01*
X1642222Y404035D01*
X1641972Y404160D01*
X1641763Y404327D01*
G01X1639788Y403952D02*
X1639705Y404494D01*
X1639580Y404952D01*
X1639413Y405369D01*
X1639205Y405827D01*
X1638872Y406452D01*
X1640538D01*
G01X1637855D02*
X1637272Y403952D01*
X1636605Y406452D01*
X1635938Y403952D01*
X1635355Y406452D01*
G01X1633505Y403952D02*
Y406452D01*
X1634005Y405952D01*
G01Y403952D02*
X1633005D01*
G01X1607330Y438697D02*
X1604830D01*
Y440363D01*
G01X1606913Y441838D02*
X1607163Y442088D01*
X1607288Y442380D01*
X1607330Y442713D01*
X1607247Y443130D01*
X1607038Y443422D01*
X1606788Y443505D01*
X1606538Y443463D01*
X1606330Y443297D01*
X1605913Y442463D01*
X1605622Y442088D01*
X1605205Y441838D01*
X1604830Y441755D01*
Y443505D01*
G01Y444647D02*
X1607330D01*
X1605247Y445730D01*
X1607330Y446813D01*
X1604830D01*
G01Y448830D02*
X1607330D01*
X1606830Y448330D01*
G01X1604830D02*
Y449330D01*
G01X1634092Y481917D02*
X1634217Y481667D01*
X1634300Y481375D01*
Y481042D01*
X1634175Y480667D01*
X1633967Y480375D01*
X1633717Y480167D01*
X1633300Y480000D01*
X1632925Y479958D01*
X1632550Y480042D01*
X1632300Y480167D01*
X1632050Y480417D01*
X1631883Y480708D01*
X1631800Y481000D01*
Y481292D01*
X1631883Y481583D01*
X1632008Y481833D01*
X1632175Y482042D01*
G01X1631800Y484100D02*
X1631842Y484392D01*
X1631967Y484725D01*
X1632175Y484933D01*
X1632467Y485017D01*
X1632758Y484933D01*
X1633008Y484683D01*
X1633133Y484308D01*
Y483892D01*
X1633217Y483642D01*
X1633425Y483433D01*
X1633717Y483350D01*
X1634008Y483475D01*
X1634217Y483767D01*
X1634300Y484100D01*
X1634217Y484433D01*
X1634008Y484725D01*
X1633717Y484850D01*
X1633425Y484767D01*
X1633217Y484558D01*
X1633133Y484308D01*
Y483892D01*
X1633008Y483517D01*
X1632758Y483267D01*
X1632467Y483183D01*
X1632175Y483267D01*
X1631967Y483475D01*
X1631842Y483808D01*
X1631800Y484100D01*
G01X1633133Y487533D02*
X1633258Y487700D01*
X1633467Y487825D01*
X1633758Y487908D01*
X1634008Y487825D01*
X1634175Y487658D01*
X1634300Y487367D01*
Y486242D01*
X1631800D01*
Y487617D01*
X1631967Y487908D01*
X1632217Y488075D01*
X1632508Y488158D01*
X1632800Y488075D01*
X1633050Y487825D01*
X1633133Y487533D01*
Y486242D01*
G01X1631800Y490300D02*
X1634300D01*
X1633800Y489800D01*
G01X1631800D02*
Y490800D01*
G01X1632842Y492608D02*
X1633133Y492900D01*
X1633300Y493150D01*
X1633383Y493483D01*
X1633300Y493775D01*
X1633133Y493983D01*
X1632883Y494150D01*
X1632592Y494192D01*
X1632342Y494150D01*
X1632092Y493983D01*
X1631883Y493733D01*
X1631800Y493442D01*
X1631883Y493108D01*
X1632133Y492817D01*
X1632508Y492650D01*
X1632925Y492608D01*
X1633467Y492692D01*
X1633758Y492817D01*
X1634050Y493025D01*
X1634258Y493317D01*
X1634300Y493608D01*
X1634217Y493900D01*
X1634008Y494108D01*
G01X1637477Y482912D02*
X1637602Y482662D01*
X1637685Y482370D01*
Y482037D01*
X1637560Y481662D01*
X1637352Y481370D01*
X1637102Y481162D01*
X1636685Y480995D01*
X1636310Y480953D01*
X1635935Y481037D01*
X1635685Y481162D01*
X1635435Y481412D01*
X1635268Y481703D01*
X1635185Y481995D01*
Y482287D01*
X1635268Y482578D01*
X1635393Y482828D01*
X1635560Y483037D01*
G01X1635185Y485095D02*
X1635227Y485387D01*
X1635352Y485720D01*
X1635560Y485928D01*
X1635852Y486012D01*
X1636143Y485928D01*
X1636393Y485678D01*
X1636518Y485303D01*
Y484887D01*
X1636602Y484637D01*
X1636810Y484428D01*
X1637102Y484345D01*
X1637393Y484470D01*
X1637602Y484762D01*
X1637685Y485095D01*
X1637602Y485428D01*
X1637393Y485720D01*
X1637102Y485845D01*
X1636810Y485762D01*
X1636602Y485553D01*
X1636518Y485303D01*
Y484887D01*
X1636393Y484512D01*
X1636143Y484262D01*
X1635852Y484178D01*
X1635560Y484262D01*
X1635352Y484470D01*
X1635227Y484803D01*
X1635185Y485095D01*
G01X1636518Y488528D02*
X1636643Y488695D01*
X1636852Y488820D01*
X1637143Y488903D01*
X1637393Y488820D01*
X1637560Y488653D01*
X1637685Y488362D01*
Y487237D01*
X1635185D01*
Y488612D01*
X1635352Y488903D01*
X1635602Y489070D01*
X1635893Y489153D01*
X1636185Y489070D01*
X1636435Y488820D01*
X1636518Y488528D01*
Y487237D01*
G01X1635185Y491295D02*
X1637685D01*
X1637185Y490795D01*
G01X1635185D02*
Y491795D01*
G01X1635560Y493478D02*
X1635352Y493728D01*
X1635227Y494020D01*
X1635185Y494395D01*
X1635268Y494770D01*
X1635435Y495062D01*
X1635727Y495270D01*
X1636060Y495312D01*
X1636393Y495228D01*
X1636602Y495020D01*
X1636768Y494728D01*
X1636810Y494437D01*
X1636768Y494145D01*
X1636602Y493770D01*
X1637685Y493895D01*
Y495020D01*
G01X1604833Y493559D02*
X1605083Y493684D01*
X1605375Y493767D01*
X1605708D01*
X1606083Y493642D01*
X1606375Y493434D01*
X1606583Y493184D01*
X1606750Y492767D01*
X1606792Y492392D01*
X1606708Y492017D01*
X1606583Y491767D01*
X1606333Y491517D01*
X1606042Y491350D01*
X1605750Y491267D01*
X1605458D01*
X1605167Y491350D01*
X1604917Y491475D01*
X1604708Y491642D01*
G01X1603442Y493350D02*
X1603192Y493600D01*
X1602900Y493725D01*
X1602567Y493767D01*
X1602150Y493684D01*
X1601858Y493475D01*
X1601775Y493225D01*
X1601817Y492975D01*
X1601983Y492767D01*
X1602817Y492350D01*
X1603192Y492059D01*
X1603442Y491642D01*
X1603525Y491267D01*
X1601775D01*
G01X1600633D02*
Y493767D01*
X1599550Y491684D01*
X1598467Y493767D01*
Y491267D01*
G01X1597367Y491642D02*
X1597117Y491434D01*
X1596825Y491309D01*
X1596450Y491267D01*
X1596075Y491350D01*
X1595783Y491517D01*
X1595575Y491809D01*
X1595533Y492142D01*
X1595617Y492475D01*
X1595825Y492684D01*
X1596117Y492850D01*
X1596408Y492892D01*
X1596700Y492850D01*
X1597075Y492684D01*
X1596950Y493767D01*
X1595825D01*
G01X1608933Y514472D02*
X1609183Y514597D01*
X1609475Y514680D01*
X1609808D01*
X1610183Y514555D01*
X1610475Y514347D01*
X1610683Y514097D01*
X1610850Y513680D01*
X1610892Y513305D01*
X1610808Y512930D01*
X1610683Y512680D01*
X1610433Y512430D01*
X1610142Y512263D01*
X1609850Y512180D01*
X1609558D01*
X1609267Y512263D01*
X1609017Y512388D01*
X1608808Y512555D01*
G01X1607542Y514263D02*
X1607292Y514513D01*
X1607000Y514638D01*
X1606667Y514680D01*
X1606250Y514597D01*
X1605958Y514388D01*
X1605875Y514138D01*
X1605917Y513888D01*
X1606083Y513680D01*
X1606917Y513263D01*
X1607292Y512972D01*
X1607542Y512555D01*
X1607625Y512180D01*
X1605875D01*
G01X1604733D02*
Y514680D01*
X1603650Y512597D01*
X1602567Y514680D01*
Y512180D01*
G01X1600550D02*
Y514680D01*
X1601050Y514180D01*
G01Y512180D02*
X1600050D01*
G01X1609133Y510959D02*
X1609383Y511084D01*
X1609675Y511167D01*
X1610008D01*
X1610383Y511042D01*
X1610675Y510834D01*
X1610883Y510584D01*
X1611050Y510167D01*
X1611092Y509792D01*
X1611008Y509417D01*
X1610883Y509167D01*
X1610633Y508917D01*
X1610342Y508750D01*
X1610050Y508667D01*
X1609758D01*
X1609467Y508750D01*
X1609217Y508875D01*
X1609008Y509042D01*
G01X1607742Y510750D02*
X1607492Y511000D01*
X1607200Y511125D01*
X1606867Y511167D01*
X1606450Y511084D01*
X1606158Y510875D01*
X1606075Y510625D01*
X1606117Y510375D01*
X1606283Y510167D01*
X1607117Y509750D01*
X1607492Y509459D01*
X1607742Y509042D01*
X1607825Y508667D01*
X1606075D01*
G01X1604933D02*
Y511167D01*
X1603850Y509084D01*
X1602767Y511167D01*
Y508667D01*
G01X1601542Y510750D02*
X1601292Y511000D01*
X1601000Y511125D01*
X1600667Y511167D01*
X1600250Y511084D01*
X1599958Y510875D01*
X1599875Y510625D01*
X1599917Y510375D01*
X1600083Y510167D01*
X1600917Y509750D01*
X1601292Y509459D01*
X1601542Y509042D01*
X1601625Y508667D01*
X1599875D01*
G01X1600684Y467819D02*
X1600809Y467569D01*
X1600892Y467277D01*
Y466944D01*
X1600767Y466569D01*
X1600559Y466277D01*
X1600309Y466069D01*
X1599892Y465902D01*
X1599517Y465860D01*
X1599142Y465944D01*
X1598892Y466069D01*
X1598642Y466319D01*
X1598475Y466610D01*
X1598392Y466902D01*
Y467194D01*
X1598475Y467485D01*
X1598600Y467735D01*
X1598767Y467944D01*
G01X1600475Y469210D02*
X1600725Y469460D01*
X1600850Y469752D01*
X1600892Y470085D01*
X1600809Y470502D01*
X1600600Y470794D01*
X1600350Y470877D01*
X1600100Y470835D01*
X1599892Y470669D01*
X1599475Y469835D01*
X1599184Y469460D01*
X1598767Y469210D01*
X1598392Y469127D01*
Y470877D01*
G01Y472019D02*
X1600892D01*
X1598809Y473102D01*
X1600892Y474185D01*
X1598392D01*
G01X1598684Y475494D02*
X1598475Y475785D01*
X1598392Y476119D01*
X1598475Y476452D01*
X1598725Y476744D01*
X1599100Y476952D01*
X1599475Y477035D01*
X1599934D01*
X1600309Y476952D01*
X1600642Y476744D01*
X1600809Y476494D01*
X1600892Y476202D01*
X1600809Y475869D01*
X1600642Y475619D01*
X1600392Y475452D01*
X1600059Y475369D01*
X1599767Y475452D01*
X1599475Y475660D01*
X1599309Y475910D01*
X1599267Y476202D01*
X1599350Y476535D01*
X1599559Y476785D01*
X1599934Y477035D01*
G01X1596459Y478767D02*
X1596584Y478517D01*
X1596667Y478225D01*
Y477892D01*
X1596542Y477517D01*
X1596334Y477225D01*
X1596084Y477017D01*
X1595667Y476850D01*
X1595292Y476808D01*
X1594917Y476892D01*
X1594667Y477017D01*
X1594417Y477267D01*
X1594250Y477558D01*
X1594167Y477850D01*
Y478142D01*
X1594250Y478433D01*
X1594375Y478683D01*
X1594542Y478892D01*
G01X1596250Y480158D02*
X1596500Y480408D01*
X1596625Y480700D01*
X1596667Y481033D01*
X1596584Y481450D01*
X1596375Y481742D01*
X1596125Y481825D01*
X1595875Y481783D01*
X1595667Y481617D01*
X1595250Y480783D01*
X1594959Y480408D01*
X1594542Y480158D01*
X1594167Y480075D01*
Y481825D01*
G01Y482967D02*
X1596667D01*
X1594584Y484050D01*
X1596667Y485133D01*
X1594167D01*
G01Y487150D02*
X1594209Y487442D01*
X1594334Y487775D01*
X1594542Y487983D01*
X1594834Y488067D01*
X1595125Y487983D01*
X1595375Y487733D01*
X1595500Y487358D01*
Y486942D01*
X1595584Y486692D01*
X1595792Y486483D01*
X1596084Y486400D01*
X1596375Y486525D01*
X1596584Y486817D01*
X1596667Y487150D01*
X1596584Y487483D01*
X1596375Y487775D01*
X1596084Y487900D01*
X1595792Y487817D01*
X1595584Y487608D01*
X1595500Y487358D01*
Y486942D01*
X1595375Y486567D01*
X1595125Y486317D01*
X1594834Y486233D01*
X1594542Y486317D01*
X1594334Y486525D01*
X1594209Y486858D01*
X1594167Y487150D01*
G01X1610133Y502559D02*
X1610383Y502684D01*
X1610675Y502767D01*
X1611008D01*
X1611383Y502642D01*
X1611675Y502434D01*
X1611883Y502184D01*
X1612050Y501767D01*
X1612092Y501392D01*
X1612008Y501017D01*
X1611883Y500767D01*
X1611633Y500517D01*
X1611342Y500350D01*
X1611050Y500267D01*
X1610758D01*
X1610467Y500350D01*
X1610217Y500475D01*
X1610008Y500642D01*
G01X1608742Y502350D02*
X1608492Y502600D01*
X1608200Y502725D01*
X1607867Y502767D01*
X1607450Y502684D01*
X1607158Y502475D01*
X1607075Y502225D01*
X1607117Y501975D01*
X1607283Y501767D01*
X1608117Y501350D01*
X1608492Y501059D01*
X1608742Y500642D01*
X1608825Y500267D01*
X1607075D01*
G01X1605933D02*
Y502767D01*
X1604850Y500684D01*
X1603767Y502767D01*
Y500267D01*
G01X1602542Y501309D02*
X1602250Y501600D01*
X1602000Y501767D01*
X1601667Y501850D01*
X1601375Y501767D01*
X1601167Y501600D01*
X1601000Y501350D01*
X1600958Y501059D01*
X1601000Y500809D01*
X1601167Y500559D01*
X1601417Y500350D01*
X1601708Y500267D01*
X1602042Y500350D01*
X1602333Y500600D01*
X1602500Y500975D01*
X1602542Y501392D01*
X1602458Y501934D01*
X1602333Y502225D01*
X1602125Y502517D01*
X1601833Y502725D01*
X1601542Y502767D01*
X1601250Y502684D01*
X1601042Y502475D01*
G01X1606792Y504067D02*
Y506567D01*
X1605208D01*
G01X1605792Y505359D02*
X1606792D01*
G01X1602567Y505400D02*
X1602400Y505525D01*
X1602275Y505734D01*
X1602192Y506025D01*
X1602275Y506275D01*
X1602442Y506442D01*
X1602733Y506567D01*
X1603858D01*
Y504067D01*
X1602483D01*
X1602192Y504234D01*
X1602025Y504484D01*
X1601942Y504775D01*
X1602025Y505067D01*
X1602275Y505317D01*
X1602567Y505400D01*
X1603858D01*
G01X1600592Y506150D02*
X1600342Y506400D01*
X1600050Y506525D01*
X1599717Y506567D01*
X1599300Y506484D01*
X1599008Y506275D01*
X1598925Y506025D01*
X1598967Y505775D01*
X1599133Y505567D01*
X1599967Y505150D01*
X1600342Y504859D01*
X1600592Y504442D01*
X1600675Y504067D01*
X1598925D01*
G01X1597783D02*
Y506567D01*
X1596700Y504484D01*
X1595617Y506567D01*
Y504067D01*
G01X1593600D02*
Y506567D01*
X1594100Y506067D01*
G01Y504067D02*
X1593100D01*
G01X1590667Y477108D02*
X1593167D01*
Y478692D01*
G01X1591959Y478108D02*
Y477108D01*
G01X1592000Y481333D02*
X1592125Y481500D01*
X1592334Y481625D01*
X1592625Y481708D01*
X1592875Y481625D01*
X1593042Y481458D01*
X1593167Y481167D01*
Y480042D01*
X1590667D01*
Y481417D01*
X1590834Y481708D01*
X1591084Y481875D01*
X1591375Y481958D01*
X1591667Y481875D01*
X1591917Y481625D01*
X1592000Y481333D01*
Y480042D01*
G01X1592750Y483308D02*
X1593000Y483558D01*
X1593125Y483850D01*
X1593167Y484183D01*
X1593084Y484600D01*
X1592875Y484892D01*
X1592625Y484975D01*
X1592375Y484933D01*
X1592167Y484767D01*
X1591750Y483933D01*
X1591459Y483558D01*
X1591042Y483308D01*
X1590667Y483225D01*
Y484975D01*
G01Y486117D02*
X1593167D01*
X1591084Y487200D01*
X1593167Y488283D01*
X1590667D01*
G01X1592750Y489508D02*
X1593000Y489758D01*
X1593125Y490050D01*
X1593167Y490383D01*
X1593084Y490800D01*
X1592875Y491092D01*
X1592625Y491175D01*
X1592375Y491133D01*
X1592167Y490967D01*
X1591750Y490133D01*
X1591459Y489758D01*
X1591042Y489508D01*
X1590667Y489425D01*
Y491175D01*
G01X1622706Y527317D02*
X1625206D01*
Y528358D01*
X1625081Y528692D01*
X1624914Y528900D01*
X1624581Y528983D01*
X1624248Y528900D01*
X1624039Y528650D01*
X1623914Y528358D01*
Y527317D01*
G01Y528358D02*
X1622706Y528983D01*
G01X1624789Y530458D02*
X1625039Y530708D01*
X1625164Y531000D01*
X1625206Y531333D01*
X1625123Y531750D01*
X1624914Y532042D01*
X1624664Y532125D01*
X1624414Y532083D01*
X1624206Y531917D01*
X1623789Y531083D01*
X1623498Y530708D01*
X1623081Y530458D01*
X1622706Y530375D01*
Y532125D01*
G01X1625206Y533517D02*
X1622706D01*
Y535183D01*
G01X1624789Y536658D02*
X1625039Y536908D01*
X1625164Y537200D01*
X1625206Y537533D01*
X1625123Y537950D01*
X1624914Y538242D01*
X1624664Y538325D01*
X1624414Y538283D01*
X1624206Y538117D01*
X1623789Y537283D01*
X1623498Y536908D01*
X1623081Y536658D01*
X1622706Y536575D01*
Y538325D01*
G01X1623206Y539633D02*
X1622914Y539883D01*
X1622748Y540217D01*
X1622706Y540592D01*
X1622748Y540925D01*
X1622956Y541258D01*
X1623206Y541467D01*
X1623456Y541508D01*
X1623748Y541425D01*
X1623956Y541133D01*
X1624039Y540842D01*
Y540467D01*
G01Y540842D02*
X1624164Y541092D01*
X1624373Y541300D01*
X1624623Y541383D01*
X1624873Y541300D01*
X1625081Y541092D01*
X1625206Y540717D01*
X1625164Y540342D01*
X1624998Y539967D01*
G01X1619306Y527317D02*
X1621806D01*
Y528358D01*
X1621681Y528692D01*
X1621514Y528900D01*
X1621181Y528983D01*
X1620848Y528900D01*
X1620639Y528650D01*
X1620514Y528358D01*
Y527317D01*
G01Y528358D02*
X1619306Y528983D01*
G01X1621389Y530458D02*
X1621639Y530708D01*
X1621764Y531000D01*
X1621806Y531333D01*
X1621723Y531750D01*
X1621514Y532042D01*
X1621264Y532125D01*
X1621014Y532083D01*
X1620806Y531917D01*
X1620389Y531083D01*
X1620098Y530708D01*
X1619681Y530458D01*
X1619306Y530375D01*
Y532125D01*
G01X1621806Y533517D02*
X1619306D01*
Y535183D01*
G01X1621389Y536658D02*
X1621639Y536908D01*
X1621764Y537200D01*
X1621806Y537533D01*
X1621723Y537950D01*
X1621514Y538242D01*
X1621264Y538325D01*
X1621014Y538283D01*
X1620806Y538117D01*
X1620389Y537283D01*
X1620098Y536908D01*
X1619681Y536658D01*
X1619306Y536575D01*
Y538325D01*
G01X1621389Y539758D02*
X1621639Y540008D01*
X1621764Y540300D01*
X1621806Y540633D01*
X1621723Y541050D01*
X1621514Y541342D01*
X1621264Y541425D01*
X1621014Y541383D01*
X1620806Y541217D01*
X1620389Y540383D01*
X1620098Y540008D01*
X1619681Y539758D01*
X1619306Y539675D01*
Y541425D01*
G01X1647939Y538674D02*
X1648064Y538424D01*
X1648147Y538132D01*
Y537799D01*
X1648022Y537424D01*
X1647814Y537132D01*
X1647564Y536924D01*
X1647147Y536757D01*
X1646772Y536715D01*
X1646397Y536799D01*
X1646147Y536924D01*
X1645897Y537174D01*
X1645730Y537465D01*
X1645647Y537757D01*
Y538049D01*
X1645730Y538340D01*
X1645855Y538590D01*
X1646022Y538799D01*
G01X1647730Y540065D02*
X1647980Y540315D01*
X1648105Y540607D01*
X1648147Y540940D01*
X1648064Y541357D01*
X1647855Y541649D01*
X1647605Y541732D01*
X1647355Y541690D01*
X1647147Y541524D01*
X1646730Y540690D01*
X1646439Y540315D01*
X1646022Y540065D01*
X1645647Y539982D01*
Y541732D01*
G01X1648147Y543124D02*
X1645647D01*
Y544790D01*
G01Y547557D02*
X1648147D01*
X1646355Y546015D01*
Y548099D01*
G01X1648147Y550157D02*
X1648064Y549824D01*
X1647855Y549574D01*
X1647605Y549407D01*
X1647272Y549282D01*
X1646897Y549240D01*
X1646522Y549282D01*
X1646189Y549407D01*
X1645939Y549574D01*
X1645730Y549824D01*
X1645647Y550157D01*
X1645730Y550490D01*
X1645939Y550740D01*
X1646189Y550907D01*
X1646522Y551032D01*
X1646897Y551074D01*
X1647272Y551032D01*
X1647605Y550907D01*
X1647855Y550740D01*
X1648064Y550490D01*
X1648147Y550157D01*
G01X1643939Y538574D02*
X1644064Y538324D01*
X1644147Y538032D01*
Y537699D01*
X1644022Y537324D01*
X1643814Y537032D01*
X1643564Y536824D01*
X1643147Y536657D01*
X1642772Y536615D01*
X1642397Y536699D01*
X1642147Y536824D01*
X1641897Y537074D01*
X1641730Y537365D01*
X1641647Y537657D01*
Y537949D01*
X1641730Y538240D01*
X1641855Y538490D01*
X1642022Y538699D01*
G01X1643730Y539965D02*
X1643980Y540215D01*
X1644105Y540507D01*
X1644147Y540840D01*
X1644064Y541257D01*
X1643855Y541549D01*
X1643605Y541632D01*
X1643355Y541590D01*
X1643147Y541424D01*
X1642730Y540590D01*
X1642439Y540215D01*
X1642022Y539965D01*
X1641647Y539882D01*
Y541632D01*
G01X1644147Y543024D02*
X1641647D01*
Y544690D01*
G01Y547457D02*
X1644147D01*
X1642355Y545915D01*
Y547999D01*
G01X1641647Y550057D02*
X1644147D01*
X1643647Y549557D01*
G01X1641647D02*
Y550557D01*
G01X1640225Y538391D02*
X1640350Y538141D01*
X1640433Y537849D01*
Y537516D01*
X1640308Y537141D01*
X1640100Y536849D01*
X1639850Y536641D01*
X1639433Y536474D01*
X1639058Y536432D01*
X1638683Y536516D01*
X1638433Y536641D01*
X1638183Y536891D01*
X1638016Y537182D01*
X1637933Y537474D01*
Y537766D01*
X1638016Y538057D01*
X1638141Y538307D01*
X1638308Y538516D01*
G01X1640016Y539782D02*
X1640266Y540032D01*
X1640391Y540324D01*
X1640433Y540657D01*
X1640350Y541074D01*
X1640141Y541366D01*
X1639891Y541449D01*
X1639641Y541407D01*
X1639433Y541241D01*
X1639016Y540407D01*
X1638725Y540032D01*
X1638308Y539782D01*
X1637933Y539699D01*
Y541449D01*
G01X1640433Y542841D02*
X1637933D01*
Y544507D01*
G01Y547274D02*
X1640433D01*
X1638641Y545732D01*
Y547816D01*
G01X1640016Y549082D02*
X1640266Y549332D01*
X1640391Y549624D01*
X1640433Y549957D01*
X1640350Y550374D01*
X1640141Y550666D01*
X1639891Y550749D01*
X1639641Y550707D01*
X1639433Y550541D01*
X1639016Y549707D01*
X1638725Y549332D01*
X1638308Y549082D01*
X1637933Y548999D01*
Y550749D01*
G01X1634919Y529527D02*
X1635044Y529277D01*
X1635127Y528985D01*
Y528652D01*
X1635002Y528277D01*
X1634794Y527985D01*
X1634544Y527777D01*
X1634127Y527610D01*
X1633752Y527568D01*
X1633377Y527652D01*
X1633127Y527777D01*
X1632877Y528027D01*
X1632710Y528318D01*
X1632627Y528610D01*
Y528902D01*
X1632710Y529193D01*
X1632835Y529443D01*
X1633002Y529652D01*
G01X1634710Y530918D02*
X1634960Y531168D01*
X1635085Y531460D01*
X1635127Y531793D01*
X1635044Y532210D01*
X1634835Y532502D01*
X1634585Y532585D01*
X1634335Y532543D01*
X1634127Y532377D01*
X1633710Y531543D01*
X1633419Y531168D01*
X1633002Y530918D01*
X1632627Y530835D01*
Y532585D01*
G01X1635127Y533977D02*
X1632627D01*
Y535643D01*
G01Y538410D02*
X1635127D01*
X1633335Y536868D01*
Y538952D01*
G01X1633127Y540093D02*
X1632835Y540343D01*
X1632669Y540677D01*
X1632627Y541052D01*
X1632669Y541385D01*
X1632877Y541718D01*
X1633127Y541927D01*
X1633377Y541968D01*
X1633669Y541885D01*
X1633877Y541593D01*
X1633960Y541302D01*
Y540927D01*
G01Y541302D02*
X1634085Y541552D01*
X1634294Y541760D01*
X1634544Y541843D01*
X1634794Y541760D01*
X1635002Y541552D01*
X1635127Y541177D01*
X1635085Y540802D01*
X1634919Y540427D01*
G01X1630619Y529027D02*
X1630744Y528777D01*
X1630827Y528485D01*
Y528152D01*
X1630702Y527777D01*
X1630494Y527485D01*
X1630244Y527277D01*
X1629827Y527110D01*
X1629452Y527068D01*
X1629077Y527152D01*
X1628827Y527277D01*
X1628577Y527527D01*
X1628410Y527818D01*
X1628327Y528110D01*
Y528402D01*
X1628410Y528693D01*
X1628535Y528943D01*
X1628702Y529152D01*
G01X1630410Y530418D02*
X1630660Y530668D01*
X1630785Y530960D01*
X1630827Y531293D01*
X1630744Y531710D01*
X1630535Y532002D01*
X1630285Y532085D01*
X1630035Y532043D01*
X1629827Y531877D01*
X1629410Y531043D01*
X1629119Y530668D01*
X1628702Y530418D01*
X1628327Y530335D01*
Y532085D01*
G01X1630827Y533477D02*
X1628327D01*
Y535143D01*
G01Y537910D02*
X1630827D01*
X1629035Y536368D01*
Y538452D01*
G01X1628327Y541010D02*
X1630827D01*
X1629035Y539468D01*
Y541552D01*
G01X1651759Y538617D02*
X1651884Y538367D01*
X1651967Y538075D01*
Y537742D01*
X1651842Y537367D01*
X1651634Y537075D01*
X1651384Y536867D01*
X1650967Y536700D01*
X1650592Y536658D01*
X1650217Y536742D01*
X1649967Y536867D01*
X1649717Y537117D01*
X1649550Y537408D01*
X1649467Y537700D01*
Y537992D01*
X1649550Y538283D01*
X1649675Y538533D01*
X1649842Y538742D01*
G01X1651550Y540008D02*
X1651800Y540258D01*
X1651925Y540550D01*
X1651967Y540883D01*
X1651884Y541300D01*
X1651675Y541592D01*
X1651425Y541675D01*
X1651175Y541633D01*
X1650967Y541467D01*
X1650550Y540633D01*
X1650259Y540258D01*
X1649842Y540008D01*
X1649467Y539925D01*
Y541675D01*
G01X1651967Y543067D02*
X1649467D01*
Y544733D01*
G01X1649967Y546083D02*
X1649675Y546333D01*
X1649509Y546667D01*
X1649467Y547042D01*
X1649509Y547375D01*
X1649717Y547708D01*
X1649967Y547917D01*
X1650217Y547958D01*
X1650509Y547875D01*
X1650717Y547583D01*
X1650800Y547292D01*
Y546917D01*
G01Y547292D02*
X1650925Y547542D01*
X1651134Y547750D01*
X1651384Y547833D01*
X1651634Y547750D01*
X1651842Y547542D01*
X1651967Y547167D01*
X1651925Y546792D01*
X1651759Y546417D01*
G01X1649759Y549392D02*
X1649550Y549683D01*
X1649467Y550017D01*
X1649550Y550350D01*
X1649800Y550642D01*
X1650175Y550850D01*
X1650550Y550933D01*
X1651009D01*
X1651384Y550850D01*
X1651717Y550642D01*
X1651884Y550392D01*
X1651967Y550100D01*
X1651884Y549767D01*
X1651717Y549517D01*
X1651467Y549350D01*
X1651134Y549267D01*
X1650842Y549350D01*
X1650550Y549558D01*
X1650384Y549808D01*
X1650342Y550100D01*
X1650425Y550433D01*
X1650634Y550683D01*
X1651009Y550933D01*
G01X1657383Y588959D02*
X1657633Y589084D01*
X1657925Y589167D01*
X1658258D01*
X1658633Y589042D01*
X1658925Y588834D01*
X1659133Y588584D01*
X1659300Y588167D01*
X1659342Y587792D01*
X1659258Y587417D01*
X1659133Y587167D01*
X1658883Y586917D01*
X1658592Y586750D01*
X1658300Y586667D01*
X1658008D01*
X1657717Y586750D01*
X1657467Y586875D01*
X1657258Y587042D01*
G01X1655992Y588750D02*
X1655742Y589000D01*
X1655450Y589125D01*
X1655117Y589167D01*
X1654700Y589084D01*
X1654408Y588875D01*
X1654325Y588625D01*
X1654367Y588375D01*
X1654533Y588167D01*
X1655367Y587750D01*
X1655742Y587459D01*
X1655992Y587042D01*
X1656075Y586667D01*
X1654325D01*
G01X1652933Y589167D02*
Y586667D01*
X1651267D01*
G01X1649000D02*
Y589167D01*
X1649500Y588667D01*
G01Y586667D02*
X1648500D01*
G01X1646608Y586959D02*
X1646317Y586750D01*
X1645983Y586667D01*
X1645650Y586750D01*
X1645358Y587000D01*
X1645150Y587375D01*
X1645067Y587750D01*
Y588209D01*
X1645150Y588584D01*
X1645358Y588917D01*
X1645608Y589084D01*
X1645900Y589167D01*
X1646233Y589084D01*
X1646483Y588917D01*
X1646650Y588667D01*
X1646733Y588334D01*
X1646650Y588042D01*
X1646442Y587750D01*
X1646192Y587584D01*
X1645900Y587542D01*
X1645567Y587625D01*
X1645317Y587834D01*
X1645067Y588209D01*
G01X1626083Y551792D02*
X1626333Y551917D01*
X1626625Y552000D01*
X1626958D01*
X1627333Y551875D01*
X1627625Y551667D01*
X1627833Y551417D01*
X1628000Y551000D01*
X1628042Y550625D01*
X1627958Y550250D01*
X1627833Y550000D01*
X1627583Y549750D01*
X1627292Y549583D01*
X1627000Y549500D01*
X1626708D01*
X1626417Y549583D01*
X1626167Y549708D01*
X1625958Y549875D01*
G01X1624692Y551583D02*
X1624442Y551833D01*
X1624150Y551958D01*
X1623817Y552000D01*
X1623400Y551917D01*
X1623108Y551708D01*
X1623025Y551458D01*
X1623067Y551208D01*
X1623233Y551000D01*
X1624067Y550583D01*
X1624442Y550292D01*
X1624692Y549875D01*
X1624775Y549500D01*
X1623025D01*
G01X1621633Y552000D02*
Y549500D01*
X1619967D01*
G01X1618617Y550000D02*
X1618367Y549708D01*
X1618033Y549542D01*
X1617658Y549500D01*
X1617325Y549542D01*
X1616992Y549750D01*
X1616783Y550000D01*
X1616742Y550250D01*
X1616825Y550542D01*
X1617117Y550750D01*
X1617408Y550833D01*
X1617783D01*
G01X1617408D02*
X1617158Y550958D01*
X1616950Y551167D01*
X1616867Y551417D01*
X1616950Y551667D01*
X1617158Y551875D01*
X1617533Y552000D01*
X1617908Y551958D01*
X1618283Y551792D01*
G01X1614683Y549500D02*
X1614600Y550042D01*
X1614475Y550500D01*
X1614308Y550917D01*
X1614100Y551375D01*
X1613767Y552000D01*
X1615433D01*
G01X1608483Y549592D02*
X1608733Y549717D01*
X1609025Y549800D01*
X1609358D01*
X1609733Y549675D01*
X1610025Y549467D01*
X1610233Y549217D01*
X1610400Y548800D01*
X1610442Y548425D01*
X1610358Y548050D01*
X1610233Y547800D01*
X1609983Y547550D01*
X1609692Y547383D01*
X1609400Y547300D01*
X1609108D01*
X1608817Y547383D01*
X1608567Y547508D01*
X1608358Y547675D01*
G01X1607092Y549383D02*
X1606842Y549633D01*
X1606550Y549758D01*
X1606217Y549800D01*
X1605800Y549717D01*
X1605508Y549508D01*
X1605425Y549258D01*
X1605467Y549008D01*
X1605633Y548800D01*
X1606467Y548383D01*
X1606842Y548092D01*
X1607092Y547675D01*
X1607175Y547300D01*
X1605425D01*
G01X1604033Y549800D02*
Y547300D01*
X1602367D01*
G01X1599600D02*
Y549800D01*
X1601142Y548008D01*
X1599058D01*
G01X1597000Y547300D02*
X1596708Y547342D01*
X1596375Y547467D01*
X1596167Y547675D01*
X1596083Y547967D01*
X1596167Y548258D01*
X1596417Y548508D01*
X1596792Y548633D01*
X1597208D01*
X1597458Y548717D01*
X1597667Y548925D01*
X1597750Y549217D01*
X1597625Y549508D01*
X1597333Y549717D01*
X1597000Y549800D01*
X1596667Y549717D01*
X1596375Y549508D01*
X1596250Y549217D01*
X1596333Y548925D01*
X1596542Y548717D01*
X1596792Y548633D01*
X1597208D01*
X1597583Y548508D01*
X1597833Y548258D01*
X1597917Y547967D01*
X1597833Y547675D01*
X1597625Y547467D01*
X1597292Y547342D01*
X1597000Y547300D01*
G01X1626083Y547792D02*
X1626333Y547917D01*
X1626625Y548000D01*
X1626958D01*
X1627333Y547875D01*
X1627625Y547667D01*
X1627833Y547417D01*
X1628000Y547000D01*
X1628042Y546625D01*
X1627958Y546250D01*
X1627833Y546000D01*
X1627583Y545750D01*
X1627292Y545583D01*
X1627000Y545500D01*
X1626708D01*
X1626417Y545583D01*
X1626167Y545708D01*
X1625958Y545875D01*
G01X1624692Y547583D02*
X1624442Y547833D01*
X1624150Y547958D01*
X1623817Y548000D01*
X1623400Y547917D01*
X1623108Y547708D01*
X1623025Y547458D01*
X1623067Y547208D01*
X1623233Y547000D01*
X1624067Y546583D01*
X1624442Y546292D01*
X1624692Y545875D01*
X1624775Y545500D01*
X1623025D01*
G01X1621633Y548000D02*
Y545500D01*
X1619967D01*
G01X1617200D02*
Y548000D01*
X1618742Y546208D01*
X1616658D01*
G01X1614683Y545500D02*
X1614600Y546042D01*
X1614475Y546500D01*
X1614308Y546917D01*
X1614100Y547375D01*
X1613767Y548000D01*
X1615433D01*
G01X1608783Y586859D02*
X1609033Y586984D01*
X1609325Y587067D01*
X1609658D01*
X1610033Y586942D01*
X1610325Y586734D01*
X1610533Y586484D01*
X1610700Y586067D01*
X1610742Y585692D01*
X1610658Y585317D01*
X1610533Y585067D01*
X1610283Y584817D01*
X1609992Y584650D01*
X1609700Y584567D01*
X1609408D01*
X1609117Y584650D01*
X1608867Y584775D01*
X1608658Y584942D01*
G01X1607392Y586650D02*
X1607142Y586900D01*
X1606850Y587025D01*
X1606517Y587067D01*
X1606100Y586984D01*
X1605808Y586775D01*
X1605725Y586525D01*
X1605767Y586275D01*
X1605933Y586067D01*
X1606767Y585650D01*
X1607142Y585359D01*
X1607392Y584942D01*
X1607475Y584567D01*
X1605725D01*
G01X1604333Y587067D02*
Y584567D01*
X1602667D01*
G01X1601192Y586650D02*
X1600942Y586900D01*
X1600650Y587025D01*
X1600317Y587067D01*
X1599900Y586984D01*
X1599608Y586775D01*
X1599525Y586525D01*
X1599567Y586275D01*
X1599733Y586067D01*
X1600567Y585650D01*
X1600942Y585359D01*
X1601192Y584942D01*
X1601275Y584567D01*
X1599525D01*
G01X1597300D02*
Y587067D01*
X1597800Y586567D01*
G01Y584567D02*
X1596800D01*
G01X1612783Y576359D02*
X1613033Y576484D01*
X1613325Y576567D01*
X1613658D01*
X1614033Y576442D01*
X1614325Y576234D01*
X1614533Y575984D01*
X1614700Y575567D01*
X1614742Y575192D01*
X1614658Y574817D01*
X1614533Y574567D01*
X1614283Y574317D01*
X1613992Y574150D01*
X1613700Y574067D01*
X1613408D01*
X1613117Y574150D01*
X1612867Y574275D01*
X1612658Y574442D01*
G01X1611392Y576150D02*
X1611142Y576400D01*
X1610850Y576525D01*
X1610517Y576567D01*
X1610100Y576484D01*
X1609808Y576275D01*
X1609725Y576025D01*
X1609767Y575775D01*
X1609933Y575567D01*
X1610767Y575150D01*
X1611142Y574859D01*
X1611392Y574442D01*
X1611475Y574067D01*
X1609725D01*
G01X1608333Y576567D02*
Y574067D01*
X1606667D01*
G01X1605192Y576150D02*
X1604942Y576400D01*
X1604650Y576525D01*
X1604317Y576567D01*
X1603900Y576484D01*
X1603608Y576275D01*
X1603525Y576025D01*
X1603567Y575775D01*
X1603733Y575567D01*
X1604567Y575150D01*
X1604942Y574859D01*
X1605192Y574442D01*
X1605275Y574067D01*
X1603525D01*
G01X1600800D02*
Y576567D01*
X1602342Y574775D01*
X1600258D01*
G01X1636383Y578059D02*
X1636633Y578184D01*
X1636925Y578267D01*
X1637258D01*
X1637633Y578142D01*
X1637925Y577934D01*
X1638133Y577684D01*
X1638300Y577267D01*
X1638342Y576892D01*
X1638258Y576517D01*
X1638133Y576267D01*
X1637883Y576017D01*
X1637592Y575850D01*
X1637300Y575767D01*
X1637008D01*
X1636717Y575850D01*
X1636467Y575975D01*
X1636258Y576142D01*
G01X1634992Y577850D02*
X1634742Y578100D01*
X1634450Y578225D01*
X1634117Y578267D01*
X1633700Y578184D01*
X1633408Y577975D01*
X1633325Y577725D01*
X1633367Y577475D01*
X1633533Y577267D01*
X1634367Y576850D01*
X1634742Y576559D01*
X1634992Y576142D01*
X1635075Y575767D01*
X1633325D01*
G01X1631933Y578267D02*
Y575767D01*
X1630267D01*
G01X1628792Y577850D02*
X1628542Y578100D01*
X1628250Y578225D01*
X1627917Y578267D01*
X1627500Y578184D01*
X1627208Y577975D01*
X1627125Y577725D01*
X1627167Y577475D01*
X1627333Y577267D01*
X1628167Y576850D01*
X1628542Y576559D01*
X1628792Y576142D01*
X1628875Y575767D01*
X1627125D01*
G01X1625692Y576809D02*
X1625400Y577100D01*
X1625150Y577267D01*
X1624817Y577350D01*
X1624525Y577267D01*
X1624317Y577100D01*
X1624150Y576850D01*
X1624108Y576559D01*
X1624150Y576309D01*
X1624317Y576059D01*
X1624567Y575850D01*
X1624858Y575767D01*
X1625192Y575850D01*
X1625483Y576100D01*
X1625650Y576475D01*
X1625692Y576892D01*
X1625608Y577434D01*
X1625483Y577725D01*
X1625275Y578017D01*
X1624983Y578225D01*
X1624692Y578267D01*
X1624400Y578184D01*
X1624192Y577975D01*
G01X1636083Y574859D02*
X1636333Y574984D01*
X1636625Y575067D01*
X1636958D01*
X1637333Y574942D01*
X1637625Y574734D01*
X1637833Y574484D01*
X1638000Y574067D01*
X1638042Y573692D01*
X1637958Y573317D01*
X1637833Y573067D01*
X1637583Y572817D01*
X1637292Y572650D01*
X1637000Y572567D01*
X1636708D01*
X1636417Y572650D01*
X1636167Y572775D01*
X1635958Y572942D01*
G01X1634692Y574650D02*
X1634442Y574900D01*
X1634150Y575025D01*
X1633817Y575067D01*
X1633400Y574984D01*
X1633108Y574775D01*
X1633025Y574525D01*
X1633067Y574275D01*
X1633233Y574067D01*
X1634067Y573650D01*
X1634442Y573359D01*
X1634692Y572942D01*
X1634775Y572567D01*
X1633025D01*
G01X1631633Y575067D02*
Y572567D01*
X1629967D01*
G01X1628492Y574650D02*
X1628242Y574900D01*
X1627950Y575025D01*
X1627617Y575067D01*
X1627200Y574984D01*
X1626908Y574775D01*
X1626825Y574525D01*
X1626867Y574275D01*
X1627033Y574067D01*
X1627867Y573650D01*
X1628242Y573359D01*
X1628492Y572942D01*
X1628575Y572567D01*
X1626825D01*
G01X1624683D02*
X1624600Y573109D01*
X1624475Y573567D01*
X1624308Y573984D01*
X1624100Y574442D01*
X1623767Y575067D01*
X1625433D01*
G01X1608483Y553592D02*
X1608733Y553717D01*
X1609025Y553800D01*
X1609358D01*
X1609733Y553675D01*
X1610025Y553467D01*
X1610233Y553217D01*
X1610400Y552800D01*
X1610442Y552425D01*
X1610358Y552050D01*
X1610233Y551800D01*
X1609983Y551550D01*
X1609692Y551383D01*
X1609400Y551300D01*
X1609108D01*
X1608817Y551383D01*
X1608567Y551508D01*
X1608358Y551675D01*
G01X1607092Y553383D02*
X1606842Y553633D01*
X1606550Y553758D01*
X1606217Y553800D01*
X1605800Y553717D01*
X1605508Y553508D01*
X1605425Y553258D01*
X1605467Y553008D01*
X1605633Y552800D01*
X1606467Y552383D01*
X1606842Y552092D01*
X1607092Y551675D01*
X1607175Y551300D01*
X1605425D01*
G01X1604033Y553800D02*
Y551300D01*
X1602367D01*
G01X1601017Y551800D02*
X1600767Y551508D01*
X1600433Y551342D01*
X1600058Y551300D01*
X1599725Y551342D01*
X1599392Y551550D01*
X1599183Y551800D01*
X1599142Y552050D01*
X1599225Y552342D01*
X1599517Y552550D01*
X1599808Y552633D01*
X1600183D01*
G01X1599808D02*
X1599558Y552758D01*
X1599350Y552967D01*
X1599267Y553217D01*
X1599350Y553467D01*
X1599558Y553675D01*
X1599933Y553800D01*
X1600308Y553758D01*
X1600683Y553592D01*
G01X1597000Y551300D02*
X1596708Y551342D01*
X1596375Y551467D01*
X1596167Y551675D01*
X1596083Y551967D01*
X1596167Y552258D01*
X1596417Y552508D01*
X1596792Y552633D01*
X1597208D01*
X1597458Y552717D01*
X1597667Y552925D01*
X1597750Y553217D01*
X1597625Y553508D01*
X1597333Y553717D01*
X1597000Y553800D01*
X1596667Y553717D01*
X1596375Y553508D01*
X1596250Y553217D01*
X1596333Y552925D01*
X1596542Y552717D01*
X1596792Y552633D01*
X1597208D01*
X1597583Y552508D01*
X1597833Y552258D01*
X1597917Y551967D01*
X1597833Y551675D01*
X1597625Y551467D01*
X1597292Y551342D01*
X1597000Y551300D01*
G01X1636440Y589765D02*
X1636690Y589890D01*
X1636982Y589973D01*
X1637315D01*
X1637690Y589848D01*
X1637982Y589640D01*
X1638190Y589390D01*
X1638357Y588973D01*
X1638399Y588598D01*
X1638315Y588223D01*
X1638190Y587973D01*
X1637940Y587723D01*
X1637649Y587556D01*
X1637357Y587473D01*
X1637065D01*
X1636774Y587556D01*
X1636524Y587681D01*
X1636315Y587848D01*
G01X1635049Y589556D02*
X1634799Y589806D01*
X1634507Y589931D01*
X1634174Y589973D01*
X1633757Y589890D01*
X1633465Y589681D01*
X1633382Y589431D01*
X1633424Y589181D01*
X1633590Y588973D01*
X1634424Y588556D01*
X1634799Y588265D01*
X1635049Y587848D01*
X1635132Y587473D01*
X1633382D01*
G01X1631990Y589973D02*
Y587473D01*
X1630324D01*
G01X1628849Y589556D02*
X1628599Y589806D01*
X1628307Y589931D01*
X1627974Y589973D01*
X1627557Y589890D01*
X1627265Y589681D01*
X1627182Y589431D01*
X1627224Y589181D01*
X1627390Y588973D01*
X1628224Y588556D01*
X1628599Y588265D01*
X1628849Y587848D01*
X1628932Y587473D01*
X1627182D01*
G01X1624957Y589973D02*
X1625290Y589890D01*
X1625540Y589681D01*
X1625707Y589431D01*
X1625832Y589098D01*
X1625874Y588723D01*
X1625832Y588348D01*
X1625707Y588015D01*
X1625540Y587765D01*
X1625290Y587556D01*
X1624957Y587473D01*
X1624624Y587556D01*
X1624374Y587765D01*
X1624207Y588015D01*
X1624082Y588348D01*
X1624040Y588723D01*
X1624082Y589098D01*
X1624207Y589431D01*
X1624374Y589681D01*
X1624624Y589890D01*
X1624957Y589973D01*
G01X1623653Y557022D02*
X1623963Y557252D01*
X1624118Y557520D01*
X1624170Y557827D01*
X1624067Y558210D01*
X1623808Y558478D01*
X1623498Y558555D01*
X1623188Y558517D01*
X1622930Y558363D01*
X1622413Y557597D01*
X1622052Y557252D01*
X1621535Y557022D01*
X1621070Y556945D01*
Y558555D01*
G01Y560007D02*
X1624170D01*
Y560773D01*
X1624015Y561080D01*
X1623808Y561310D01*
X1623498Y561502D01*
X1623137Y561655D01*
X1622620Y561693D01*
X1622103Y561655D01*
X1621742Y561502D01*
X1621432Y561310D01*
X1621225Y561080D01*
X1621070Y560773D01*
Y560007D01*
G01X1621432Y563298D02*
X1621173Y563567D01*
X1621070Y563873D01*
X1621173Y564180D01*
X1621483Y564448D01*
X1621948Y564640D01*
X1622413Y564717D01*
X1622982D01*
X1623447Y564640D01*
X1623860Y564448D01*
X1624067Y564218D01*
X1624170Y563950D01*
X1624067Y563643D01*
X1623860Y563413D01*
X1623550Y563260D01*
X1623137Y563183D01*
X1622775Y563260D01*
X1622413Y563452D01*
X1622207Y563682D01*
X1622155Y563950D01*
X1622258Y564257D01*
X1622517Y564487D01*
X1622982Y564717D01*
G01X1604650Y605170D02*
Y607670D01*
X1603609D01*
X1603275Y607545D01*
X1603067Y607378D01*
X1602984Y607045D01*
X1603067Y606712D01*
X1603317Y606503D01*
X1603609Y606378D01*
X1604650D01*
G01X1603609D02*
X1602984Y605170D01*
G01X1601509Y607253D02*
X1601259Y607503D01*
X1600967Y607628D01*
X1600634Y607670D01*
X1600217Y607587D01*
X1599925Y607378D01*
X1599842Y607128D01*
X1599884Y606878D01*
X1600050Y606670D01*
X1600884Y606253D01*
X1601259Y605962D01*
X1601509Y605545D01*
X1601592Y605170D01*
X1599842D01*
G01X1598450Y607670D02*
Y605170D01*
X1596784D01*
G01X1595309Y607253D02*
X1595059Y607503D01*
X1594767Y607628D01*
X1594434Y607670D01*
X1594017Y607587D01*
X1593725Y607378D01*
X1593642Y607128D01*
X1593684Y606878D01*
X1593850Y606670D01*
X1594684Y606253D01*
X1595059Y605962D01*
X1595309Y605545D01*
X1595392Y605170D01*
X1593642D01*
G01X1592334Y605545D02*
X1592084Y605337D01*
X1591792Y605212D01*
X1591417Y605170D01*
X1591042Y605253D01*
X1590750Y605420D01*
X1590542Y605712D01*
X1590500Y606045D01*
X1590584Y606378D01*
X1590792Y606587D01*
X1591084Y606753D01*
X1591375Y606795D01*
X1591667Y606753D01*
X1592042Y606587D01*
X1591917Y607670D01*
X1590792D01*
G01X1650905Y623939D02*
X1651155Y624064D01*
X1651447Y624147D01*
X1651780D01*
X1652155Y624022D01*
X1652447Y623814D01*
X1652655Y623564D01*
X1652822Y623147D01*
X1652864Y622772D01*
X1652780Y622397D01*
X1652655Y622147D01*
X1652405Y621897D01*
X1652114Y621730D01*
X1651822Y621647D01*
X1651530D01*
X1651239Y621730D01*
X1650989Y621855D01*
X1650780Y622022D01*
G01X1649514Y623730D02*
X1649264Y623980D01*
X1648972Y624105D01*
X1648639Y624147D01*
X1648222Y624064D01*
X1647930Y623855D01*
X1647847Y623605D01*
X1647889Y623355D01*
X1648055Y623147D01*
X1648889Y622730D01*
X1649264Y622439D01*
X1649514Y622022D01*
X1649597Y621647D01*
X1647847D01*
G01X1646455Y624147D02*
Y621647D01*
X1644789D01*
G01X1642522D02*
Y624147D01*
X1643022Y623647D01*
G01Y621647D02*
X1642022D01*
G01X1640339Y622147D02*
X1640089Y621855D01*
X1639755Y621689D01*
X1639380Y621647D01*
X1639047Y621689D01*
X1638714Y621897D01*
X1638505Y622147D01*
X1638464Y622397D01*
X1638547Y622689D01*
X1638839Y622897D01*
X1639130Y622980D01*
X1639505D01*
G01X1639130D02*
X1638880Y623105D01*
X1638672Y623314D01*
X1638589Y623564D01*
X1638672Y623814D01*
X1638880Y624022D01*
X1639255Y624147D01*
X1639630Y624105D01*
X1640005Y623939D01*
G01X1651035Y620300D02*
X1651285Y620425D01*
X1651577Y620508D01*
X1651910D01*
X1652285Y620383D01*
X1652577Y620175D01*
X1652785Y619925D01*
X1652952Y619508D01*
X1652994Y619133D01*
X1652910Y618758D01*
X1652785Y618508D01*
X1652535Y618258D01*
X1652244Y618091D01*
X1651952Y618008D01*
X1651660D01*
X1651369Y618091D01*
X1651119Y618216D01*
X1650910Y618383D01*
G01X1649644Y620091D02*
X1649394Y620341D01*
X1649102Y620466D01*
X1648769Y620508D01*
X1648352Y620425D01*
X1648060Y620216D01*
X1647977Y619966D01*
X1648019Y619716D01*
X1648185Y619508D01*
X1649019Y619091D01*
X1649394Y618800D01*
X1649644Y618383D01*
X1649727Y618008D01*
X1647977D01*
G01X1646585Y620508D02*
Y618008D01*
X1644919D01*
G01X1642652D02*
Y620508D01*
X1643152Y620008D01*
G01Y618008D02*
X1642152D01*
G01X1640469Y618383D02*
X1640219Y618175D01*
X1639927Y618050D01*
X1639552Y618008D01*
X1639177Y618091D01*
X1638885Y618258D01*
X1638677Y618550D01*
X1638635Y618883D01*
X1638719Y619216D01*
X1638927Y619425D01*
X1639219Y619591D01*
X1639510Y619633D01*
X1639802Y619591D01*
X1640177Y619425D01*
X1640052Y620508D01*
X1638927D01*
G01X1652983Y592259D02*
X1653233Y592384D01*
X1653525Y592467D01*
X1653858D01*
X1654233Y592342D01*
X1654525Y592134D01*
X1654733Y591884D01*
X1654900Y591467D01*
X1654942Y591092D01*
X1654858Y590717D01*
X1654733Y590467D01*
X1654483Y590217D01*
X1654192Y590050D01*
X1653900Y589967D01*
X1653608D01*
X1653317Y590050D01*
X1653067Y590175D01*
X1652858Y590342D01*
G01X1651592Y592050D02*
X1651342Y592300D01*
X1651050Y592425D01*
X1650717Y592467D01*
X1650300Y592384D01*
X1650008Y592175D01*
X1649925Y591925D01*
X1649967Y591675D01*
X1650133Y591467D01*
X1650967Y591050D01*
X1651342Y590759D01*
X1651592Y590342D01*
X1651675Y589967D01*
X1649925D01*
G01X1648533Y592467D02*
Y589967D01*
X1646867D01*
G01X1644600D02*
Y592467D01*
X1645100Y591967D01*
G01Y589967D02*
X1644100D01*
G01X1641583D02*
X1641500Y590509D01*
X1641375Y590967D01*
X1641208Y591384D01*
X1641000Y591842D01*
X1640667Y592467D01*
X1642333D01*
G01X1609943Y600677D02*
X1610193Y600802D01*
X1610485Y600885D01*
X1610818D01*
X1611193Y600760D01*
X1611485Y600552D01*
X1611693Y600302D01*
X1611860Y599885D01*
X1611902Y599510D01*
X1611818Y599135D01*
X1611693Y598885D01*
X1611443Y598635D01*
X1611152Y598468D01*
X1610860Y598385D01*
X1610568D01*
X1610277Y598468D01*
X1610027Y598593D01*
X1609818Y598760D01*
G01X1608552Y600468D02*
X1608302Y600718D01*
X1608010Y600843D01*
X1607677Y600885D01*
X1607260Y600802D01*
X1606968Y600593D01*
X1606885Y600343D01*
X1606927Y600093D01*
X1607093Y599885D01*
X1607927Y599468D01*
X1608302Y599177D01*
X1608552Y598760D01*
X1608635Y598385D01*
X1606885D01*
G01X1605493Y600885D02*
Y598385D01*
X1603827D01*
G01X1601560D02*
Y600885D01*
X1602060Y600385D01*
G01Y598385D02*
X1601060D01*
G01X1597960D02*
Y600885D01*
X1599502Y599093D01*
X1597418D01*
G01X1634983Y605842D02*
X1635233Y605967D01*
X1635525Y606050D01*
X1635858D01*
X1636233Y605925D01*
X1636525Y605717D01*
X1636733Y605467D01*
X1636900Y605050D01*
X1636942Y604675D01*
X1636858Y604300D01*
X1636733Y604050D01*
X1636483Y603800D01*
X1636192Y603633D01*
X1635900Y603550D01*
X1635608D01*
X1635317Y603633D01*
X1635067Y603758D01*
X1634858Y603925D01*
G01X1633592Y605633D02*
X1633342Y605883D01*
X1633050Y606008D01*
X1632717Y606050D01*
X1632300Y605967D01*
X1632008Y605758D01*
X1631925Y605508D01*
X1631967Y605258D01*
X1632133Y605050D01*
X1632967Y604633D01*
X1633342Y604342D01*
X1633592Y603925D01*
X1633675Y603550D01*
X1631925D01*
G01X1630533Y606050D02*
Y603550D01*
X1628867D01*
G01X1626600D02*
Y606050D01*
X1627100Y605550D01*
G01Y603550D02*
X1626100D01*
G01X1624292Y605633D02*
X1624042Y605883D01*
X1623750Y606008D01*
X1623417Y606050D01*
X1623000Y605967D01*
X1622708Y605758D01*
X1622625Y605508D01*
X1622667Y605258D01*
X1622833Y605050D01*
X1623667Y604633D01*
X1624042Y604342D01*
X1624292Y603925D01*
X1624375Y603550D01*
X1622625D01*
G01X1624883Y609442D02*
X1625133Y609567D01*
X1625425Y609650D01*
X1625758D01*
X1626133Y609525D01*
X1626425Y609317D01*
X1626633Y609067D01*
X1626800Y608650D01*
X1626842Y608275D01*
X1626758Y607900D01*
X1626633Y607650D01*
X1626383Y607400D01*
X1626092Y607233D01*
X1625800Y607150D01*
X1625508D01*
X1625217Y607233D01*
X1624967Y607358D01*
X1624758Y607525D01*
G01X1623492Y609233D02*
X1623242Y609483D01*
X1622950Y609608D01*
X1622617Y609650D01*
X1622200Y609567D01*
X1621908Y609358D01*
X1621825Y609108D01*
X1621867Y608858D01*
X1622033Y608650D01*
X1622867Y608233D01*
X1623242Y607942D01*
X1623492Y607525D01*
X1623575Y607150D01*
X1621825D01*
G01X1620433Y609650D02*
Y607150D01*
X1618767D01*
G01X1617208Y607442D02*
X1616917Y607233D01*
X1616583Y607150D01*
X1616250Y607233D01*
X1615958Y607483D01*
X1615750Y607858D01*
X1615667Y608233D01*
Y608692D01*
X1615750Y609067D01*
X1615958Y609400D01*
X1616208Y609567D01*
X1616500Y609650D01*
X1616833Y609567D01*
X1617083Y609400D01*
X1617250Y609150D01*
X1617333Y608817D01*
X1617250Y608525D01*
X1617042Y608233D01*
X1616792Y608067D01*
X1616500Y608025D01*
X1616167Y608108D01*
X1615917Y608317D01*
X1615667Y608692D01*
G01X1601583Y617242D02*
X1601833Y617367D01*
X1602125Y617450D01*
X1602458D01*
X1602833Y617325D01*
X1603125Y617117D01*
X1603333Y616867D01*
X1603500Y616450D01*
X1603542Y616075D01*
X1603458Y615700D01*
X1603333Y615450D01*
X1603083Y615200D01*
X1602792Y615033D01*
X1602500Y614950D01*
X1602208D01*
X1601917Y615033D01*
X1601667Y615158D01*
X1601458Y615325D01*
G01X1600192Y617033D02*
X1599942Y617283D01*
X1599650Y617408D01*
X1599317Y617450D01*
X1598900Y617367D01*
X1598608Y617158D01*
X1598525Y616908D01*
X1598567Y616658D01*
X1598733Y616450D01*
X1599567Y616033D01*
X1599942Y615742D01*
X1600192Y615325D01*
X1600275Y614950D01*
X1598525D01*
G01X1597133Y617450D02*
Y614950D01*
X1595467D01*
G01X1594117Y615325D02*
X1593867Y615117D01*
X1593575Y614992D01*
X1593200Y614950D01*
X1592825Y615033D01*
X1592533Y615200D01*
X1592325Y615492D01*
X1592283Y615825D01*
X1592367Y616158D01*
X1592575Y616367D01*
X1592867Y616533D01*
X1593158Y616575D01*
X1593450Y616533D01*
X1593825Y616367D01*
X1593700Y617450D01*
X1592575D01*
G01X1601583Y613742D02*
X1601833Y613867D01*
X1602125Y613950D01*
X1602458D01*
X1602833Y613825D01*
X1603125Y613617D01*
X1603333Y613367D01*
X1603500Y612950D01*
X1603542Y612575D01*
X1603458Y612200D01*
X1603333Y611950D01*
X1603083Y611700D01*
X1602792Y611533D01*
X1602500Y611450D01*
X1602208D01*
X1601917Y611533D01*
X1601667Y611658D01*
X1601458Y611825D01*
G01X1600192Y613533D02*
X1599942Y613783D01*
X1599650Y613908D01*
X1599317Y613950D01*
X1598900Y613867D01*
X1598608Y613658D01*
X1598525Y613408D01*
X1598567Y613158D01*
X1598733Y612950D01*
X1599567Y612533D01*
X1599942Y612242D01*
X1600192Y611825D01*
X1600275Y611450D01*
X1598525D01*
G01X1597133Y613950D02*
Y611450D01*
X1595467D01*
G01X1593283D02*
X1593200Y611992D01*
X1593075Y612450D01*
X1592908Y612867D01*
X1592700Y613325D01*
X1592367Y613950D01*
X1594033D01*
G01X1635883Y593022D02*
X1636133Y593147D01*
X1636425Y593230D01*
X1636758D01*
X1637133Y593105D01*
X1637425Y592897D01*
X1637633Y592647D01*
X1637800Y592230D01*
X1637842Y591855D01*
X1637758Y591480D01*
X1637633Y591230D01*
X1637383Y590980D01*
X1637092Y590813D01*
X1636800Y590730D01*
X1636508D01*
X1636217Y590813D01*
X1635967Y590938D01*
X1635758Y591105D01*
G01X1634492Y592813D02*
X1634242Y593063D01*
X1633950Y593188D01*
X1633617Y593230D01*
X1633200Y593147D01*
X1632908Y592938D01*
X1632825Y592688D01*
X1632867Y592438D01*
X1633033Y592230D01*
X1633867Y591813D01*
X1634242Y591522D01*
X1634492Y591105D01*
X1634575Y590730D01*
X1632825D01*
G01X1631433Y593230D02*
Y590730D01*
X1629767D01*
G01X1627500D02*
Y593230D01*
X1628000Y592730D01*
G01Y590730D02*
X1627000D01*
G01X1624400D02*
X1624108Y590772D01*
X1623775Y590897D01*
X1623567Y591105D01*
X1623483Y591397D01*
X1623567Y591688D01*
X1623817Y591938D01*
X1624192Y592063D01*
X1624608D01*
X1624858Y592147D01*
X1625067Y592355D01*
X1625150Y592647D01*
X1625025Y592938D01*
X1624733Y593147D01*
X1624400Y593230D01*
X1624067Y593147D01*
X1623775Y592938D01*
X1623650Y592647D01*
X1623733Y592355D01*
X1623942Y592147D01*
X1624192Y592063D01*
X1624608D01*
X1624983Y591938D01*
X1625233Y591688D01*
X1625317Y591397D01*
X1625233Y591105D01*
X1625025Y590897D01*
X1624692Y590772D01*
X1624400Y590730D01*
G01X1621583Y616422D02*
X1621893Y616652D01*
X1622048Y616920D01*
X1622100Y617227D01*
X1621997Y617610D01*
X1621738Y617878D01*
X1621428Y617955D01*
X1621118Y617917D01*
X1620860Y617763D01*
X1620343Y616997D01*
X1619982Y616652D01*
X1619465Y616422D01*
X1619000Y616345D01*
Y617955D01*
G01Y619292D02*
X1622100Y620250D01*
X1619000Y621208D01*
G01X1620085Y620863D02*
Y619637D01*
G01X1619362Y622698D02*
X1619103Y622967D01*
X1619000Y623273D01*
X1619103Y623580D01*
X1619413Y623848D01*
X1619878Y624040D01*
X1620343Y624117D01*
X1620912D01*
X1621377Y624040D01*
X1621790Y623848D01*
X1621997Y623618D01*
X1622100Y623350D01*
X1621997Y623043D01*
X1621790Y622813D01*
X1621480Y622660D01*
X1621067Y622583D01*
X1620705Y622660D01*
X1620343Y622852D01*
X1620137Y623082D01*
X1620085Y623350D01*
X1620188Y623657D01*
X1620447Y623887D01*
X1620912Y624117D01*
G01X1690200Y71600D02*
X1705000D01*
Y66900D01*
X1724400D01*
Y64100D01*
X1731500D01*
Y42100D01*
X1735400D01*
Y14700D01*
X1669400D01*
Y26700D01*
G01Y30200D02*
Y50100D01*
G01X1681542Y-8287D02*
Y-5787D01*
X1680501D01*
X1680167Y-5912D01*
X1679959Y-6079D01*
X1679876Y-6412D01*
X1679959Y-6745D01*
X1680209Y-6954D01*
X1680501Y-7079D01*
X1681542D01*
G01X1680501D02*
X1679876Y-8287D01*
G01X1678526Y-7787D02*
X1678276Y-8079D01*
X1677942Y-8245D01*
X1677567Y-8287D01*
X1677234Y-8245D01*
X1676901Y-8037D01*
X1676692Y-7787D01*
X1676651Y-7537D01*
X1676734Y-7245D01*
X1677026Y-7037D01*
X1677317Y-6954D01*
X1677692D01*
G01X1677317D02*
X1677067Y-6829D01*
X1676859Y-6620D01*
X1676776Y-6370D01*
X1676859Y-6120D01*
X1677067Y-5912D01*
X1677442Y-5787D01*
X1677817Y-5829D01*
X1678192Y-5995D01*
G01X1675342Y-8287D02*
Y-5787D01*
X1674342D01*
X1674009Y-5912D01*
X1673759Y-6204D01*
X1673676Y-6537D01*
X1673759Y-6870D01*
X1673967Y-7120D01*
X1674342Y-7245D01*
X1675342D01*
G01X1670909Y-8287D02*
Y-5787D01*
X1672451Y-7579D01*
X1670367D01*
G01X1667809Y-8287D02*
Y-5787D01*
X1669351Y-7579D01*
X1667267D01*
G01X1685833Y33200D02*
Y35700D01*
X1684792D01*
X1684458Y35575D01*
X1684250Y35408D01*
X1684167Y35075D01*
X1684250Y34742D01*
X1684500Y34533D01*
X1684792Y34408D01*
X1685833D01*
G01X1684792D02*
X1684167Y33200D01*
G01X1682608Y33492D02*
X1682317Y33283D01*
X1681983Y33200D01*
X1681650Y33283D01*
X1681358Y33533D01*
X1681150Y33908D01*
X1681067Y34283D01*
Y34742D01*
X1681150Y35117D01*
X1681358Y35450D01*
X1681608Y35617D01*
X1681900Y35700D01*
X1682233Y35617D01*
X1682483Y35450D01*
X1682650Y35200D01*
X1682733Y34867D01*
X1682650Y34575D01*
X1682442Y34283D01*
X1682192Y34117D01*
X1681900Y34075D01*
X1681567Y34158D01*
X1681317Y34367D01*
X1681067Y34742D01*
G01X1678550Y34450D02*
X1677717D01*
Y33700D01*
X1677967Y33450D01*
X1678258Y33283D01*
X1678675Y33200D01*
X1679092Y33283D01*
X1679383Y33450D01*
X1679633Y33700D01*
X1679800Y33992D01*
X1679883Y34325D01*
Y34617D01*
X1679800Y34867D01*
X1679633Y35158D01*
X1679383Y35408D01*
X1679133Y35575D01*
X1678800Y35700D01*
X1678508D01*
X1678175Y35617D01*
X1677925Y35450D01*
G01X1676617Y33700D02*
X1676367Y33408D01*
X1676033Y33242D01*
X1675658Y33200D01*
X1675325Y33242D01*
X1674992Y33450D01*
X1674783Y33700D01*
X1674742Y33950D01*
X1674825Y34242D01*
X1675117Y34450D01*
X1675408Y34533D01*
X1675783D01*
G01X1675408D02*
X1675158Y34658D01*
X1674950Y34867D01*
X1674867Y35117D01*
X1674950Y35367D01*
X1675158Y35575D01*
X1675533Y35700D01*
X1675908Y35658D01*
X1676283Y35492D01*
G01X1672600Y35700D02*
X1672933Y35617D01*
X1673183Y35408D01*
X1673350Y35158D01*
X1673475Y34825D01*
X1673517Y34450D01*
X1673475Y34075D01*
X1673350Y33742D01*
X1673183Y33492D01*
X1672933Y33283D01*
X1672600Y33200D01*
X1672267Y33283D01*
X1672017Y33492D01*
X1671850Y33742D01*
X1671725Y34075D01*
X1671683Y34450D01*
X1671725Y34825D01*
X1671850Y35158D01*
X1672017Y35408D01*
X1672267Y35617D01*
X1672600Y35700D01*
G01X1685833Y26200D02*
Y28700D01*
X1684792D01*
X1684458Y28575D01*
X1684250Y28408D01*
X1684167Y28075D01*
X1684250Y27742D01*
X1684500Y27533D01*
X1684792Y27408D01*
X1685833D01*
G01X1684792D02*
X1684167Y26200D01*
G01X1682692Y28283D02*
X1682442Y28533D01*
X1682150Y28658D01*
X1681817Y28700D01*
X1681400Y28617D01*
X1681108Y28408D01*
X1681025Y28158D01*
X1681067Y27908D01*
X1681233Y27700D01*
X1682067Y27283D01*
X1682442Y26992D01*
X1682692Y26575D01*
X1682775Y26200D01*
X1681025D01*
G01X1679717Y28700D02*
Y26908D01*
X1679550Y26533D01*
X1679217Y26283D01*
X1678800Y26200D01*
X1678383Y26283D01*
X1678050Y26533D01*
X1677883Y26908D01*
Y28700D01*
G01X1675200Y26200D02*
Y28700D01*
X1676742Y26908D01*
X1674658D01*
G01X1672683Y26200D02*
X1672600Y26742D01*
X1672475Y27200D01*
X1672308Y27617D01*
X1672100Y28075D01*
X1671767Y28700D01*
X1673433D01*
G01X1685833Y29700D02*
Y32200D01*
X1684792D01*
X1684458Y32075D01*
X1684250Y31908D01*
X1684167Y31575D01*
X1684250Y31242D01*
X1684500Y31033D01*
X1684792Y30908D01*
X1685833D01*
G01X1684792D02*
X1684167Y29700D01*
G01X1682608Y29992D02*
X1682317Y29783D01*
X1681983Y29700D01*
X1681650Y29783D01*
X1681358Y30033D01*
X1681150Y30408D01*
X1681067Y30783D01*
Y31242D01*
X1681150Y31617D01*
X1681358Y31950D01*
X1681608Y32117D01*
X1681900Y32200D01*
X1682233Y32117D01*
X1682483Y31950D01*
X1682650Y31700D01*
X1682733Y31367D01*
X1682650Y31075D01*
X1682442Y30783D01*
X1682192Y30617D01*
X1681900Y30575D01*
X1681567Y30658D01*
X1681317Y30867D01*
X1681067Y31242D01*
G01X1678550Y30950D02*
X1677717D01*
Y30200D01*
X1677967Y29950D01*
X1678258Y29783D01*
X1678675Y29700D01*
X1679092Y29783D01*
X1679383Y29950D01*
X1679633Y30200D01*
X1679800Y30492D01*
X1679883Y30825D01*
Y31117D01*
X1679800Y31367D01*
X1679633Y31658D01*
X1679383Y31908D01*
X1679133Y32075D01*
X1678800Y32200D01*
X1678508D01*
X1678175Y32117D01*
X1677925Y31950D01*
G01X1676492Y31783D02*
X1676242Y32033D01*
X1675950Y32158D01*
X1675617Y32200D01*
X1675200Y32117D01*
X1674908Y31908D01*
X1674825Y31658D01*
X1674867Y31408D01*
X1675033Y31200D01*
X1675867Y30783D01*
X1676242Y30492D01*
X1676492Y30075D01*
X1676575Y29700D01*
X1674825D01*
G01X1673308Y29992D02*
X1673017Y29783D01*
X1672683Y29700D01*
X1672350Y29783D01*
X1672058Y30033D01*
X1671850Y30408D01*
X1671767Y30783D01*
Y31242D01*
X1671850Y31617D01*
X1672058Y31950D01*
X1672308Y32117D01*
X1672600Y32200D01*
X1672933Y32117D01*
X1673183Y31950D01*
X1673350Y31700D01*
X1673433Y31367D01*
X1673350Y31075D01*
X1673142Y30783D01*
X1672892Y30617D01*
X1672600Y30575D01*
X1672267Y30658D01*
X1672017Y30867D01*
X1671767Y31242D01*
G01X1701633Y19300D02*
Y21800D01*
X1700592D01*
X1700258Y21675D01*
X1700050Y21508D01*
X1699967Y21175D01*
X1700050Y20842D01*
X1700300Y20633D01*
X1700592Y20508D01*
X1701633D01*
G01X1700592D02*
X1699967Y19300D01*
G01X1697700D02*
Y21800D01*
X1698200Y21300D01*
G01Y19300D02*
X1697200D01*
G01X1695517Y21800D02*
Y20008D01*
X1695350Y19633D01*
X1695017Y19383D01*
X1694600Y19300D01*
X1694183Y19383D01*
X1693850Y19633D01*
X1693683Y20008D01*
Y21800D01*
G01X1691000Y19300D02*
Y21800D01*
X1692542Y20008D01*
X1690458D01*
G01X1689192Y20342D02*
X1688900Y20633D01*
X1688650Y20800D01*
X1688317Y20883D01*
X1688025Y20800D01*
X1687817Y20633D01*
X1687650Y20383D01*
X1687608Y20092D01*
X1687650Y19842D01*
X1687817Y19592D01*
X1688067Y19383D01*
X1688358Y19300D01*
X1688692Y19383D01*
X1688983Y19633D01*
X1689150Y20008D01*
X1689192Y20425D01*
X1689108Y20967D01*
X1688983Y21258D01*
X1688775Y21550D01*
X1688483Y21758D01*
X1688192Y21800D01*
X1687900Y21717D01*
X1687692Y21508D01*
G01X1701633Y15800D02*
Y18300D01*
X1700592D01*
X1700258Y18175D01*
X1700050Y18008D01*
X1699967Y17675D01*
X1700050Y17342D01*
X1700300Y17133D01*
X1700592Y17008D01*
X1701633D01*
G01X1700592D02*
X1699967Y15800D01*
G01X1698492Y17883D02*
X1698242Y18133D01*
X1697950Y18258D01*
X1697617Y18300D01*
X1697200Y18217D01*
X1696908Y18008D01*
X1696825Y17758D01*
X1696867Y17508D01*
X1697033Y17300D01*
X1697867Y16883D01*
X1698242Y16592D01*
X1698492Y16175D01*
X1698575Y15800D01*
X1696825D01*
G01X1695517Y18300D02*
Y16508D01*
X1695350Y16133D01*
X1695017Y15883D01*
X1694600Y15800D01*
X1694183Y15883D01*
X1693850Y16133D01*
X1693683Y16508D01*
Y18300D01*
G01X1691000Y15800D02*
Y18300D01*
X1692542Y16508D01*
X1690458D01*
G01X1689108Y16092D02*
X1688817Y15883D01*
X1688483Y15800D01*
X1688150Y15883D01*
X1687858Y16133D01*
X1687650Y16508D01*
X1687567Y16883D01*
Y17342D01*
X1687650Y17717D01*
X1687858Y18050D01*
X1688108Y18217D01*
X1688400Y18300D01*
X1688733Y18217D01*
X1688983Y18050D01*
X1689150Y17800D01*
X1689233Y17467D01*
X1689150Y17175D01*
X1688942Y16883D01*
X1688692Y16717D01*
X1688400Y16675D01*
X1688067Y16758D01*
X1687817Y16967D01*
X1687567Y17342D01*
G01X1701633Y29800D02*
Y32300D01*
X1700592D01*
X1700258Y32175D01*
X1700050Y32008D01*
X1699967Y31675D01*
X1700050Y31342D01*
X1700300Y31133D01*
X1700592Y31008D01*
X1701633D01*
G01X1700592D02*
X1699967Y29800D01*
G01X1697700D02*
Y32300D01*
X1698200Y31800D01*
G01Y29800D02*
X1697200D01*
G01X1695517Y32300D02*
Y30508D01*
X1695350Y30133D01*
X1695017Y29883D01*
X1694600Y29800D01*
X1694183Y29883D01*
X1693850Y30133D01*
X1693683Y30508D01*
Y32300D01*
G01X1692417Y30175D02*
X1692167Y29967D01*
X1691875Y29842D01*
X1691500Y29800D01*
X1691125Y29883D01*
X1690833Y30050D01*
X1690625Y30342D01*
X1690583Y30675D01*
X1690667Y31008D01*
X1690875Y31217D01*
X1691167Y31383D01*
X1691458Y31425D01*
X1691750Y31383D01*
X1692125Y31217D01*
X1692000Y32300D01*
X1690875D01*
G01X1688483Y29800D02*
X1688400Y30342D01*
X1688275Y30800D01*
X1688108Y31217D01*
X1687900Y31675D01*
X1687567Y32300D01*
X1689233D01*
G01X1701633Y33300D02*
Y35800D01*
X1700592D01*
X1700258Y35675D01*
X1700050Y35508D01*
X1699967Y35175D01*
X1700050Y34842D01*
X1700300Y34633D01*
X1700592Y34508D01*
X1701633D01*
G01X1700592D02*
X1699967Y33300D01*
G01X1697700D02*
Y35800D01*
X1698200Y35300D01*
G01Y33300D02*
X1697200D01*
G01X1695517Y35800D02*
Y34008D01*
X1695350Y33633D01*
X1695017Y33383D01*
X1694600Y33300D01*
X1694183Y33383D01*
X1693850Y33633D01*
X1693683Y34008D01*
Y35800D01*
G01X1692417Y33800D02*
X1692167Y33508D01*
X1691833Y33342D01*
X1691458Y33300D01*
X1691125Y33342D01*
X1690792Y33550D01*
X1690583Y33800D01*
X1690542Y34050D01*
X1690625Y34342D01*
X1690917Y34550D01*
X1691208Y34633D01*
X1691583D01*
G01X1691208D02*
X1690958Y34758D01*
X1690750Y34967D01*
X1690667Y35217D01*
X1690750Y35467D01*
X1690958Y35675D01*
X1691333Y35800D01*
X1691708Y35758D01*
X1692083Y35592D01*
G01X1689192Y34342D02*
X1688900Y34633D01*
X1688650Y34800D01*
X1688317Y34883D01*
X1688025Y34800D01*
X1687817Y34633D01*
X1687650Y34383D01*
X1687608Y34092D01*
X1687650Y33842D01*
X1687817Y33592D01*
X1688067Y33383D01*
X1688358Y33300D01*
X1688692Y33383D01*
X1688983Y33633D01*
X1689150Y34008D01*
X1689192Y34425D01*
X1689108Y34967D01*
X1688983Y35258D01*
X1688775Y35550D01*
X1688483Y35758D01*
X1688192Y35800D01*
X1687900Y35717D01*
X1687692Y35508D01*
G01X1717833Y23200D02*
Y25700D01*
X1716792D01*
X1716458Y25575D01*
X1716250Y25408D01*
X1716167Y25075D01*
X1716250Y24742D01*
X1716500Y24533D01*
X1716792Y24408D01*
X1717833D01*
G01X1716792D02*
X1716167Y23200D01*
G01X1713900D02*
Y25700D01*
X1714400Y25200D01*
G01Y23200D02*
X1713400D01*
G01X1711717Y25700D02*
Y23908D01*
X1711550Y23533D01*
X1711217Y23283D01*
X1710800Y23200D01*
X1710383Y23283D01*
X1710050Y23533D01*
X1709883Y23908D01*
Y25700D01*
G01X1708617Y23575D02*
X1708367Y23367D01*
X1708075Y23242D01*
X1707700Y23200D01*
X1707325Y23283D01*
X1707033Y23450D01*
X1706825Y23742D01*
X1706783Y24075D01*
X1706867Y24408D01*
X1707075Y24617D01*
X1707367Y24783D01*
X1707658Y24825D01*
X1707950Y24783D01*
X1708325Y24617D01*
X1708200Y25700D01*
X1707075D01*
G01X1705308Y23492D02*
X1705017Y23283D01*
X1704683Y23200D01*
X1704350Y23283D01*
X1704058Y23533D01*
X1703850Y23908D01*
X1703767Y24283D01*
Y24742D01*
X1703850Y25117D01*
X1704058Y25450D01*
X1704308Y25617D01*
X1704600Y25700D01*
X1704933Y25617D01*
X1705183Y25450D01*
X1705350Y25200D01*
X1705433Y24867D01*
X1705350Y24575D01*
X1705142Y24283D01*
X1704892Y24117D01*
X1704600Y24075D01*
X1704267Y24158D01*
X1704017Y24367D01*
X1703767Y24742D01*
G01X1717833Y26700D02*
Y29200D01*
X1716792D01*
X1716458Y29075D01*
X1716250Y28908D01*
X1716167Y28575D01*
X1716250Y28242D01*
X1716500Y28033D01*
X1716792Y27908D01*
X1717833D01*
G01X1716792D02*
X1716167Y26700D01*
G01X1714608Y26992D02*
X1714317Y26783D01*
X1713983Y26700D01*
X1713650Y26783D01*
X1713358Y27033D01*
X1713150Y27408D01*
X1713067Y27783D01*
Y28242D01*
X1713150Y28617D01*
X1713358Y28950D01*
X1713608Y29117D01*
X1713900Y29200D01*
X1714233Y29117D01*
X1714483Y28950D01*
X1714650Y28700D01*
X1714733Y28367D01*
X1714650Y28075D01*
X1714442Y27783D01*
X1714192Y27617D01*
X1713900Y27575D01*
X1713567Y27658D01*
X1713317Y27867D01*
X1713067Y28242D01*
G01X1710550Y27950D02*
X1709717D01*
Y27200D01*
X1709967Y26950D01*
X1710258Y26783D01*
X1710675Y26700D01*
X1711092Y26783D01*
X1711383Y26950D01*
X1711633Y27200D01*
X1711800Y27492D01*
X1711883Y27825D01*
Y28117D01*
X1711800Y28367D01*
X1711633Y28658D01*
X1711383Y28908D01*
X1711133Y29075D01*
X1710800Y29200D01*
X1710508D01*
X1710175Y29117D01*
X1709925Y28950D01*
G01X1708617Y27200D02*
X1708367Y26908D01*
X1708033Y26742D01*
X1707658Y26700D01*
X1707325Y26742D01*
X1706992Y26950D01*
X1706783Y27200D01*
X1706742Y27450D01*
X1706825Y27742D01*
X1707117Y27950D01*
X1707408Y28033D01*
X1707783D01*
G01X1707408D02*
X1707158Y28158D01*
X1706950Y28367D01*
X1706867Y28617D01*
X1706950Y28867D01*
X1707158Y29075D01*
X1707533Y29200D01*
X1707908Y29158D01*
X1708283Y28992D01*
G01X1705517Y27200D02*
X1705267Y26908D01*
X1704933Y26742D01*
X1704558Y26700D01*
X1704225Y26742D01*
X1703892Y26950D01*
X1703683Y27200D01*
X1703642Y27450D01*
X1703725Y27742D01*
X1704017Y27950D01*
X1704308Y28033D01*
X1704683D01*
G01X1704308D02*
X1704058Y28158D01*
X1703850Y28367D01*
X1703767Y28617D01*
X1703850Y28867D01*
X1704058Y29075D01*
X1704433Y29200D01*
X1704808Y29158D01*
X1705183Y28992D01*
G01X1717833Y30200D02*
Y32700D01*
X1716792D01*
X1716458Y32575D01*
X1716250Y32408D01*
X1716167Y32075D01*
X1716250Y31742D01*
X1716500Y31533D01*
X1716792Y31408D01*
X1717833D01*
G01X1716792D02*
X1716167Y30200D01*
G01X1714608Y30492D02*
X1714317Y30283D01*
X1713983Y30200D01*
X1713650Y30283D01*
X1713358Y30533D01*
X1713150Y30908D01*
X1713067Y31283D01*
Y31742D01*
X1713150Y32117D01*
X1713358Y32450D01*
X1713608Y32617D01*
X1713900Y32700D01*
X1714233Y32617D01*
X1714483Y32450D01*
X1714650Y32200D01*
X1714733Y31867D01*
X1714650Y31575D01*
X1714442Y31283D01*
X1714192Y31117D01*
X1713900Y31075D01*
X1713567Y31158D01*
X1713317Y31367D01*
X1713067Y31742D01*
G01X1710550Y31450D02*
X1709717D01*
Y30700D01*
X1709967Y30450D01*
X1710258Y30283D01*
X1710675Y30200D01*
X1711092Y30283D01*
X1711383Y30450D01*
X1711633Y30700D01*
X1711800Y30992D01*
X1711883Y31325D01*
Y31617D01*
X1711800Y31867D01*
X1711633Y32158D01*
X1711383Y32408D01*
X1711133Y32575D01*
X1710800Y32700D01*
X1710508D01*
X1710175Y32617D01*
X1709925Y32450D01*
G01X1708617Y30700D02*
X1708367Y30408D01*
X1708033Y30242D01*
X1707658Y30200D01*
X1707325Y30242D01*
X1706992Y30450D01*
X1706783Y30700D01*
X1706742Y30950D01*
X1706825Y31242D01*
X1707117Y31450D01*
X1707408Y31533D01*
X1707783D01*
G01X1707408D02*
X1707158Y31658D01*
X1706950Y31867D01*
X1706867Y32117D01*
X1706950Y32367D01*
X1707158Y32575D01*
X1707533Y32700D01*
X1707908Y32658D01*
X1708283Y32492D01*
G01X1705392Y32283D02*
X1705142Y32533D01*
X1704850Y32658D01*
X1704517Y32700D01*
X1704100Y32617D01*
X1703808Y32408D01*
X1703725Y32158D01*
X1703767Y31908D01*
X1703933Y31700D01*
X1704767Y31283D01*
X1705142Y30992D01*
X1705392Y30575D01*
X1705475Y30200D01*
X1703725D01*
G01X1701633Y22800D02*
Y25300D01*
X1700592D01*
X1700258Y25175D01*
X1700050Y25008D01*
X1699967Y24675D01*
X1700050Y24342D01*
X1700300Y24133D01*
X1700592Y24008D01*
X1701633D01*
G01X1700592D02*
X1699967Y22800D01*
G01X1698408Y23092D02*
X1698117Y22883D01*
X1697783Y22800D01*
X1697450Y22883D01*
X1697158Y23133D01*
X1696950Y23508D01*
X1696867Y23883D01*
Y24342D01*
X1696950Y24717D01*
X1697158Y25050D01*
X1697408Y25217D01*
X1697700Y25300D01*
X1698033Y25217D01*
X1698283Y25050D01*
X1698450Y24800D01*
X1698533Y24467D01*
X1698450Y24175D01*
X1698242Y23883D01*
X1697992Y23717D01*
X1697700Y23675D01*
X1697367Y23758D01*
X1697117Y23967D01*
X1696867Y24342D01*
G01X1694350Y24050D02*
X1693517D01*
Y23300D01*
X1693767Y23050D01*
X1694058Y22883D01*
X1694475Y22800D01*
X1694892Y22883D01*
X1695183Y23050D01*
X1695433Y23300D01*
X1695600Y23592D01*
X1695683Y23925D01*
Y24217D01*
X1695600Y24467D01*
X1695433Y24758D01*
X1695183Y25008D01*
X1694933Y25175D01*
X1694600Y25300D01*
X1694308D01*
X1693975Y25217D01*
X1693725Y25050D01*
G01X1692292Y24883D02*
X1692042Y25133D01*
X1691750Y25258D01*
X1691417Y25300D01*
X1691000Y25217D01*
X1690708Y25008D01*
X1690625Y24758D01*
X1690667Y24508D01*
X1690833Y24300D01*
X1691667Y23883D01*
X1692042Y23592D01*
X1692292Y23175D01*
X1692375Y22800D01*
X1690625D01*
G01X1688483D02*
X1688400Y23342D01*
X1688275Y23800D01*
X1688108Y24217D01*
X1687900Y24675D01*
X1687567Y25300D01*
X1689233D01*
G01X1701633Y26300D02*
Y28800D01*
X1700592D01*
X1700258Y28675D01*
X1700050Y28508D01*
X1699967Y28175D01*
X1700050Y27842D01*
X1700300Y27633D01*
X1700592Y27508D01*
X1701633D01*
G01X1700592D02*
X1699967Y26300D01*
G01X1698408Y26592D02*
X1698117Y26383D01*
X1697783Y26300D01*
X1697450Y26383D01*
X1697158Y26633D01*
X1696950Y27008D01*
X1696867Y27383D01*
Y27842D01*
X1696950Y28217D01*
X1697158Y28550D01*
X1697408Y28717D01*
X1697700Y28800D01*
X1698033Y28717D01*
X1698283Y28550D01*
X1698450Y28300D01*
X1698533Y27967D01*
X1698450Y27675D01*
X1698242Y27383D01*
X1697992Y27217D01*
X1697700Y27175D01*
X1697367Y27258D01*
X1697117Y27467D01*
X1696867Y27842D01*
G01X1694350Y27550D02*
X1693517D01*
Y26800D01*
X1693767Y26550D01*
X1694058Y26383D01*
X1694475Y26300D01*
X1694892Y26383D01*
X1695183Y26550D01*
X1695433Y26800D01*
X1695600Y27092D01*
X1695683Y27425D01*
Y27717D01*
X1695600Y27967D01*
X1695433Y28258D01*
X1695183Y28508D01*
X1694933Y28675D01*
X1694600Y28800D01*
X1694308D01*
X1693975Y28717D01*
X1693725Y28550D01*
G01X1692417Y26800D02*
X1692167Y26508D01*
X1691833Y26342D01*
X1691458Y26300D01*
X1691125Y26342D01*
X1690792Y26550D01*
X1690583Y26800D01*
X1690542Y27050D01*
X1690625Y27342D01*
X1690917Y27550D01*
X1691208Y27633D01*
X1691583D01*
G01X1691208D02*
X1690958Y27758D01*
X1690750Y27967D01*
X1690667Y28217D01*
X1690750Y28467D01*
X1690958Y28675D01*
X1691333Y28800D01*
X1691708Y28758D01*
X1692083Y28592D01*
G01X1688400Y26300D02*
Y28800D01*
X1688900Y28300D01*
G01Y26300D02*
X1687900D01*
G01X1679792Y1005D02*
X1680042Y1130D01*
X1680334Y1213D01*
X1680667D01*
X1681042Y1088D01*
X1681334Y880D01*
X1681542Y630D01*
X1681709Y213D01*
X1681751Y-162D01*
X1681667Y-537D01*
X1681542Y-787D01*
X1681292Y-1037D01*
X1681001Y-1204D01*
X1680709Y-1287D01*
X1680417D01*
X1680126Y-1204D01*
X1679876Y-1079D01*
X1679667Y-912D01*
G01X1678526Y-787D02*
X1678276Y-1079D01*
X1677942Y-1245D01*
X1677567Y-1287D01*
X1677234Y-1245D01*
X1676901Y-1037D01*
X1676692Y-787D01*
X1676651Y-537D01*
X1676734Y-245D01*
X1677026Y-37D01*
X1677317Y46D01*
X1677692D01*
G01X1677317D02*
X1677067Y171D01*
X1676859Y380D01*
X1676776Y630D01*
X1676859Y880D01*
X1677067Y1088D01*
X1677442Y1213D01*
X1677817Y1171D01*
X1678192Y1005D01*
G01X1675342Y-1287D02*
Y1213D01*
X1674342D01*
X1674009Y1088D01*
X1673759Y796D01*
X1673676Y463D01*
X1673759Y130D01*
X1673967Y-120D01*
X1674342Y-245D01*
X1675342D01*
G01X1670909Y-1287D02*
Y1213D01*
X1672451Y-579D01*
X1670367D01*
G01X1669226Y-912D02*
X1668976Y-1120D01*
X1668684Y-1245D01*
X1668309Y-1287D01*
X1667934Y-1204D01*
X1667642Y-1037D01*
X1667434Y-745D01*
X1667392Y-412D01*
X1667476Y-79D01*
X1667684Y130D01*
X1667976Y296D01*
X1668267Y338D01*
X1668559Y296D01*
X1668934Y130D01*
X1668809Y1213D01*
X1667684D01*
G01X1679792Y-2495D02*
X1680042Y-2370D01*
X1680334Y-2287D01*
X1680667D01*
X1681042Y-2412D01*
X1681334Y-2620D01*
X1681542Y-2870D01*
X1681709Y-3287D01*
X1681751Y-3662D01*
X1681667Y-4037D01*
X1681542Y-4287D01*
X1681292Y-4537D01*
X1681001Y-4704D01*
X1680709Y-4787D01*
X1680417D01*
X1680126Y-4704D01*
X1679876Y-4579D01*
X1679667Y-4412D01*
G01X1678526Y-4287D02*
X1678276Y-4579D01*
X1677942Y-4745D01*
X1677567Y-4787D01*
X1677234Y-4745D01*
X1676901Y-4537D01*
X1676692Y-4287D01*
X1676651Y-4037D01*
X1676734Y-3745D01*
X1677026Y-3537D01*
X1677317Y-3454D01*
X1677692D01*
G01X1677317D02*
X1677067Y-3329D01*
X1676859Y-3120D01*
X1676776Y-2870D01*
X1676859Y-2620D01*
X1677067Y-2412D01*
X1677442Y-2287D01*
X1677817Y-2329D01*
X1678192Y-2495D01*
G01X1675342Y-4787D02*
Y-2287D01*
X1674342D01*
X1674009Y-2412D01*
X1673759Y-2704D01*
X1673676Y-3037D01*
X1673759Y-3370D01*
X1673967Y-3620D01*
X1674342Y-3745D01*
X1675342D01*
G01X1670909Y-4787D02*
Y-2287D01*
X1672451Y-4079D01*
X1670367D01*
G01X1669101Y-3745D02*
X1668809Y-3454D01*
X1668559Y-3287D01*
X1668226Y-3204D01*
X1667934Y-3287D01*
X1667726Y-3454D01*
X1667559Y-3704D01*
X1667517Y-3995D01*
X1667559Y-4245D01*
X1667726Y-4495D01*
X1667976Y-4704D01*
X1668267Y-4787D01*
X1668601Y-4704D01*
X1668892Y-4454D01*
X1669059Y-4079D01*
X1669101Y-3662D01*
X1669017Y-3120D01*
X1668892Y-2829D01*
X1668684Y-2537D01*
X1668392Y-2329D01*
X1668101Y-2287D01*
X1667809Y-2370D01*
X1667601Y-2579D01*
G01X1664040Y-47D02*
X1664290Y78D01*
X1664582Y161D01*
X1664915D01*
X1665290Y36D01*
X1665582Y-172D01*
X1665790Y-422D01*
X1665957Y-839D01*
X1665999Y-1214D01*
X1665915Y-1589D01*
X1665790Y-1839D01*
X1665540Y-2089D01*
X1665249Y-2256D01*
X1664957Y-2339D01*
X1664665D01*
X1664374Y-2256D01*
X1664124Y-2131D01*
X1663915Y-1964D01*
G01X1662690Y-2339D02*
Y161D01*
X1661649D01*
X1661315Y36D01*
X1661107Y-131D01*
X1661024Y-464D01*
X1661107Y-797D01*
X1661357Y-1006D01*
X1661649Y-1131D01*
X1662690D01*
G01X1661649D02*
X1661024Y-2339D01*
G01X1658840D02*
X1658757Y-1797D01*
X1658632Y-1339D01*
X1658465Y-922D01*
X1658257Y-464D01*
X1657924Y161D01*
X1659590D01*
G01X1654824Y-2339D02*
X1656490D01*
Y161D01*
X1654824D01*
G01X1655490Y-1047D02*
X1656490D01*
G01X1652557Y-2339D02*
Y161D01*
X1653057Y-339D01*
G01Y-2339D02*
X1652057D01*
G01X1657642Y21757D02*
X1654053D01*
Y23650D01*
X1650774Y21757D01*
X1654053Y19864D01*
Y21757D01*
G01X1650774Y19864D02*
Y23650D01*
G01X1665874Y3661D02*
Y1869D01*
X1665707Y1494D01*
X1665374Y1244D01*
X1664957Y1161D01*
X1664540Y1244D01*
X1664207Y1494D01*
X1664040Y1869D01*
Y3661D01*
G01X1661940Y1161D02*
X1661857Y1703D01*
X1661732Y2161D01*
X1661565Y2578D01*
X1661357Y3036D01*
X1661024Y3661D01*
X1662690D01*
G01X1659674Y1161D02*
Y3661D01*
X1658840D01*
X1658507Y3536D01*
X1658257Y3369D01*
X1658049Y3119D01*
X1657882Y2828D01*
X1657840Y2411D01*
X1657882Y1994D01*
X1658049Y1703D01*
X1658257Y1453D01*
X1658507Y1286D01*
X1658840Y1161D01*
X1659674D01*
G01X1656574Y1661D02*
X1656324Y1369D01*
X1655990Y1203D01*
X1655615Y1161D01*
X1655282Y1203D01*
X1654949Y1411D01*
X1654740Y1661D01*
X1654699Y1911D01*
X1654782Y2203D01*
X1655074Y2411D01*
X1655365Y2494D01*
X1655740D01*
G01X1655365D02*
X1655115Y2619D01*
X1654907Y2828D01*
X1654824Y3078D01*
X1654907Y3328D01*
X1655115Y3536D01*
X1655490Y3661D01*
X1655865Y3619D01*
X1656240Y3453D01*
G01X1654243Y32831D02*
X1655762D01*
G01Y24169D02*
X1654243D01*
G01X1702420Y3628D02*
X1702110Y3398D01*
X1701955Y3130D01*
X1701903Y2823D01*
X1702006Y2440D01*
X1702265Y2172D01*
X1702575Y2095D01*
X1702885Y2133D01*
X1703143Y2287D01*
X1703660Y3053D01*
X1704021Y3398D01*
X1704538Y3628D01*
X1705003Y3705D01*
Y2095D01*
G01X1657800Y98100D02*
Y89100D01*
G01X1669400Y52800D02*
Y61800D01*
X1679800D01*
Y64900D01*
X1690200D01*
Y71600D01*
G01X1711833Y79700D02*
Y82200D01*
X1710792D01*
X1710458Y82075D01*
X1710250Y81908D01*
X1710167Y81575D01*
X1710250Y81242D01*
X1710500Y81033D01*
X1710792Y80908D01*
X1711833D01*
G01X1710792D02*
X1710167Y79700D01*
G01X1708608Y79992D02*
X1708317Y79783D01*
X1707983Y79700D01*
X1707650Y79783D01*
X1707358Y80033D01*
X1707150Y80408D01*
X1707067Y80783D01*
Y81242D01*
X1707150Y81617D01*
X1707358Y81950D01*
X1707608Y82117D01*
X1707900Y82200D01*
X1708233Y82117D01*
X1708483Y81950D01*
X1708650Y81700D01*
X1708733Y81367D01*
X1708650Y81075D01*
X1708442Y80783D01*
X1708192Y80617D01*
X1707900Y80575D01*
X1707567Y80658D01*
X1707317Y80867D01*
X1707067Y81242D01*
G01X1704550Y80950D02*
X1703717D01*
Y80200D01*
X1703967Y79950D01*
X1704258Y79783D01*
X1704675Y79700D01*
X1705092Y79783D01*
X1705383Y79950D01*
X1705633Y80200D01*
X1705800Y80492D01*
X1705883Y80825D01*
Y81117D01*
X1705800Y81367D01*
X1705633Y81658D01*
X1705383Y81908D01*
X1705133Y82075D01*
X1704800Y82200D01*
X1704508D01*
X1704175Y82117D01*
X1703925Y81950D01*
G01X1702492Y81783D02*
X1702242Y82033D01*
X1701950Y82158D01*
X1701617Y82200D01*
X1701200Y82117D01*
X1700908Y81908D01*
X1700825Y81658D01*
X1700867Y81408D01*
X1701033Y81200D01*
X1701867Y80783D01*
X1702242Y80492D01*
X1702492Y80075D01*
X1702575Y79700D01*
X1700825D01*
G01X1698600D02*
X1698308Y79742D01*
X1697975Y79867D01*
X1697767Y80075D01*
X1697683Y80367D01*
X1697767Y80658D01*
X1698017Y80908D01*
X1698392Y81033D01*
X1698808D01*
X1699058Y81117D01*
X1699267Y81325D01*
X1699350Y81617D01*
X1699225Y81908D01*
X1698933Y82117D01*
X1698600Y82200D01*
X1698267Y82117D01*
X1697975Y81908D01*
X1697850Y81617D01*
X1697933Y81325D01*
X1698142Y81117D01*
X1698392Y81033D01*
X1698808D01*
X1699183Y80908D01*
X1699433Y80658D01*
X1699517Y80367D01*
X1699433Y80075D01*
X1699225Y79867D01*
X1698892Y79742D01*
X1698600Y79700D01*
G01X1711833Y83200D02*
Y85700D01*
X1710792D01*
X1710458Y85575D01*
X1710250Y85408D01*
X1710167Y85075D01*
X1710250Y84742D01*
X1710500Y84533D01*
X1710792Y84408D01*
X1711833D01*
G01X1710792D02*
X1710167Y83200D01*
G01X1707900D02*
Y85700D01*
X1708400Y85200D01*
G01Y83200D02*
X1707400D01*
G01X1705717Y85700D02*
Y83908D01*
X1705550Y83533D01*
X1705217Y83283D01*
X1704800Y83200D01*
X1704383Y83283D01*
X1704050Y83533D01*
X1703883Y83908D01*
Y85700D01*
G01X1702617Y83700D02*
X1702367Y83408D01*
X1702033Y83242D01*
X1701658Y83200D01*
X1701325Y83242D01*
X1700992Y83450D01*
X1700783Y83700D01*
X1700742Y83950D01*
X1700825Y84242D01*
X1701117Y84450D01*
X1701408Y84533D01*
X1701783D01*
G01X1701408D02*
X1701158Y84658D01*
X1700950Y84867D01*
X1700867Y85117D01*
X1700950Y85367D01*
X1701158Y85575D01*
X1701533Y85700D01*
X1701908Y85658D01*
X1702283Y85492D01*
G01X1698100Y83200D02*
Y85700D01*
X1699642Y83908D01*
X1697558D01*
G01X1660500Y60917D02*
X1663000D01*
Y61958D01*
X1662875Y62292D01*
X1662708Y62500D01*
X1662375Y62583D01*
X1662042Y62500D01*
X1661833Y62250D01*
X1661708Y61958D01*
Y60917D01*
G01Y61958D02*
X1660500Y62583D01*
G01X1662583Y64058D02*
X1662833Y64308D01*
X1662958Y64600D01*
X1663000Y64933D01*
X1662917Y65350D01*
X1662708Y65642D01*
X1662458Y65725D01*
X1662208Y65683D01*
X1662000Y65517D01*
X1661583Y64683D01*
X1661292Y64308D01*
X1660875Y64058D01*
X1660500Y63975D01*
Y65725D01*
G01X1663000Y67950D02*
X1660500D01*
G01X1663000Y66992D02*
Y68908D01*
G01X1660500Y70967D02*
X1661042Y71050D01*
X1661500Y71175D01*
X1661917Y71342D01*
X1662375Y71550D01*
X1663000Y71883D01*
Y70217D01*
G01X1661200Y36117D02*
X1663700D01*
Y37158D01*
X1663575Y37492D01*
X1663408Y37700D01*
X1663075Y37783D01*
X1662742Y37700D01*
X1662533Y37450D01*
X1662408Y37158D01*
Y36117D01*
G01Y37158D02*
X1661200Y37783D01*
G01X1663283Y39258D02*
X1663533Y39508D01*
X1663658Y39800D01*
X1663700Y40133D01*
X1663617Y40550D01*
X1663408Y40842D01*
X1663158Y40925D01*
X1662908Y40883D01*
X1662700Y40717D01*
X1662283Y39883D01*
X1661992Y39508D01*
X1661575Y39258D01*
X1661200Y39175D01*
Y40925D01*
G01X1663700Y43150D02*
X1661200D01*
G01X1663700Y42192D02*
Y44108D01*
G01X1661575Y45333D02*
X1661367Y45583D01*
X1661242Y45875D01*
X1661200Y46250D01*
X1661283Y46625D01*
X1661450Y46917D01*
X1661742Y47125D01*
X1662075Y47167D01*
X1662408Y47083D01*
X1662617Y46875D01*
X1662783Y46583D01*
X1662825Y46292D01*
X1662783Y46000D01*
X1662617Y45625D01*
X1663700Y45750D01*
Y46875D01*
G01X1713683Y93020D02*
Y95520D01*
X1712642D01*
X1712308Y95395D01*
X1712100Y95228D01*
X1712017Y94895D01*
X1712100Y94562D01*
X1712350Y94353D01*
X1712642Y94228D01*
X1713683D01*
G01X1712642D02*
X1712017Y93020D01*
G01X1710667Y93520D02*
X1710417Y93228D01*
X1710083Y93062D01*
X1709708Y93020D01*
X1709375Y93062D01*
X1709042Y93270D01*
X1708833Y93520D01*
X1708792Y93770D01*
X1708875Y94062D01*
X1709167Y94270D01*
X1709458Y94353D01*
X1709833D01*
G01X1709458D02*
X1709208Y94478D01*
X1709000Y94687D01*
X1708917Y94937D01*
X1709000Y95187D01*
X1709208Y95395D01*
X1709583Y95520D01*
X1709958Y95478D01*
X1710333Y95312D01*
G01X1707900Y95520D02*
X1707317Y93020D01*
X1706650Y95520D01*
X1705983Y93020D01*
X1705400Y95520D01*
G01X1704467Y93395D02*
X1704217Y93187D01*
X1703925Y93062D01*
X1703550Y93020D01*
X1703175Y93103D01*
X1702883Y93270D01*
X1702675Y93562D01*
X1702633Y93895D01*
X1702717Y94228D01*
X1702925Y94437D01*
X1703217Y94603D01*
X1703508Y94645D01*
X1703800Y94603D01*
X1704175Y94437D01*
X1704050Y95520D01*
X1702925D01*
G01X1695333Y76000D02*
Y78500D01*
X1694292D01*
X1693958Y78375D01*
X1693750Y78208D01*
X1693667Y77875D01*
X1693750Y77542D01*
X1694000Y77333D01*
X1694292Y77208D01*
X1695333D01*
G01X1694292D02*
X1693667Y76000D01*
G01X1691400D02*
Y78500D01*
X1691900Y78000D01*
G01Y76000D02*
X1690900D01*
G01X1689217Y78500D02*
Y76708D01*
X1689050Y76333D01*
X1688717Y76083D01*
X1688300Y76000D01*
X1687883Y76083D01*
X1687550Y76333D01*
X1687383Y76708D01*
Y78500D01*
G01X1685992Y78083D02*
X1685742Y78333D01*
X1685450Y78458D01*
X1685117Y78500D01*
X1684700Y78417D01*
X1684408Y78208D01*
X1684325Y77958D01*
X1684367Y77708D01*
X1684533Y77500D01*
X1685367Y77083D01*
X1685742Y76792D01*
X1685992Y76375D01*
X1686075Y76000D01*
X1684325D01*
G01X1682892Y78083D02*
X1682642Y78333D01*
X1682350Y78458D01*
X1682017Y78500D01*
X1681600Y78417D01*
X1681308Y78208D01*
X1681225Y77958D01*
X1681267Y77708D01*
X1681433Y77500D01*
X1682267Y77083D01*
X1682642Y76792D01*
X1682892Y76375D01*
X1682975Y76000D01*
X1681225D01*
G01X1695333Y72500D02*
Y75000D01*
X1694292D01*
X1693958Y74875D01*
X1693750Y74708D01*
X1693667Y74375D01*
X1693750Y74042D01*
X1694000Y73833D01*
X1694292Y73708D01*
X1695333D01*
G01X1694292D02*
X1693667Y72500D01*
G01X1691400D02*
Y75000D01*
X1691900Y74500D01*
G01Y72500D02*
X1690900D01*
G01X1689217Y75000D02*
Y73208D01*
X1689050Y72833D01*
X1688717Y72583D01*
X1688300Y72500D01*
X1687883Y72583D01*
X1687550Y72833D01*
X1687383Y73208D01*
Y75000D01*
G01X1685200Y72500D02*
Y75000D01*
X1685700Y74500D01*
G01Y72500D02*
X1684700D01*
G01X1682892Y73542D02*
X1682600Y73833D01*
X1682350Y74000D01*
X1682017Y74083D01*
X1681725Y74000D01*
X1681517Y73833D01*
X1681350Y73583D01*
X1681308Y73292D01*
X1681350Y73042D01*
X1681517Y72792D01*
X1681767Y72583D01*
X1682058Y72500D01*
X1682392Y72583D01*
X1682683Y72833D01*
X1682850Y73208D01*
X1682892Y73625D01*
X1682808Y74167D01*
X1682683Y74458D01*
X1682475Y74750D01*
X1682183Y74958D01*
X1681892Y75000D01*
X1681600Y74917D01*
X1681392Y74708D01*
G01X1672000Y66267D02*
X1674500D01*
Y67308D01*
X1674375Y67642D01*
X1674208Y67850D01*
X1673875Y67933D01*
X1673542Y67850D01*
X1673333Y67600D01*
X1673208Y67308D01*
Y66267D01*
G01Y67308D02*
X1672000Y67933D01*
G01Y70200D02*
X1674500D01*
X1674000Y69700D01*
G01X1672000D02*
Y70700D01*
G01X1674500Y72383D02*
X1672708D01*
X1672333Y72550D01*
X1672083Y72883D01*
X1672000Y73300D01*
X1672083Y73717D01*
X1672333Y74050D01*
X1672708Y74217D01*
X1674500D01*
G01X1672375Y75483D02*
X1672167Y75733D01*
X1672042Y76025D01*
X1672000Y76400D01*
X1672083Y76775D01*
X1672250Y77067D01*
X1672542Y77275D01*
X1672875Y77317D01*
X1673208Y77233D01*
X1673417Y77025D01*
X1673583Y76733D01*
X1673625Y76442D01*
X1673583Y76150D01*
X1673417Y75775D01*
X1674500Y75900D01*
Y77025D01*
G01X1672000Y80000D02*
X1674500D01*
X1672708Y78458D01*
Y80542D01*
G01X1720700Y65200D02*
X1709300D01*
Y44860D01*
X1720700D01*
Y65200D01*
G01X1652150Y69971D02*
X1655400D01*
Y66471D01*
G01X1652150Y57971D02*
X1655400D01*
Y61471D01*
G01X1652650Y43371D02*
X1655900D01*
Y46871D01*
G01X1652650Y55371D02*
X1655900D01*
Y51871D01*
G01X1660100Y87517D02*
X1662600D01*
Y88558D01*
X1662475Y88892D01*
X1662308Y89100D01*
X1661975Y89183D01*
X1661642Y89100D01*
X1661433Y88850D01*
X1661308Y88558D01*
Y87517D01*
G01Y88558D02*
X1660100Y89183D01*
G01X1662183Y90658D02*
X1662433Y90908D01*
X1662558Y91200D01*
X1662600Y91533D01*
X1662517Y91950D01*
X1662308Y92242D01*
X1662058Y92325D01*
X1661808Y92283D01*
X1661600Y92117D01*
X1661183Y91283D01*
X1660892Y90908D01*
X1660475Y90658D01*
X1660100Y90575D01*
Y92325D01*
G01X1660475Y93633D02*
X1660267Y93883D01*
X1660142Y94175D01*
X1660100Y94550D01*
X1660183Y94925D01*
X1660350Y95217D01*
X1660642Y95425D01*
X1660975Y95467D01*
X1661308Y95383D01*
X1661517Y95175D01*
X1661683Y94883D01*
X1661725Y94592D01*
X1661683Y94300D01*
X1661517Y93925D01*
X1662600Y94050D01*
Y95175D01*
G01Y96400D02*
X1660100Y96983D01*
X1662600Y97650D01*
X1660100Y98317D01*
X1662600Y98900D01*
G01X1660475Y99833D02*
X1660267Y100083D01*
X1660142Y100375D01*
X1660100Y100750D01*
X1660183Y101125D01*
X1660350Y101417D01*
X1660642Y101625D01*
X1660975Y101667D01*
X1661308Y101583D01*
X1661517Y101375D01*
X1661683Y101083D01*
X1661725Y100792D01*
X1661683Y100500D01*
X1661517Y100125D01*
X1662600Y100250D01*
Y101375D01*
G01X1660100Y103850D02*
X1660142Y104142D01*
X1660267Y104475D01*
X1660475Y104683D01*
X1660767Y104767D01*
X1661058Y104683D01*
X1661308Y104433D01*
X1661433Y104058D01*
Y103642D01*
X1661517Y103392D01*
X1661725Y103183D01*
X1662017Y103100D01*
X1662308Y103225D01*
X1662517Y103517D01*
X1662600Y103850D01*
X1662517Y104183D01*
X1662308Y104475D01*
X1662017Y104600D01*
X1661725Y104517D01*
X1661517Y104308D01*
X1661433Y104058D01*
Y103642D01*
X1661308Y103267D01*
X1661058Y103017D01*
X1660767Y102933D01*
X1660475Y103017D01*
X1660267Y103225D01*
X1660142Y103558D01*
X1660100Y103850D01*
G01X1664300Y83000D02*
Y87000D01*
X1671700D01*
G01X1685700Y151800D02*
X1695200D01*
G01X1685700D02*
Y123200D01*
X1690600D01*
G01X1724400Y129800D02*
X1724800D01*
Y113500D01*
X1698600D01*
Y115600D01*
G01X1699500Y151800D02*
X1702000D01*
Y139000D01*
X1709400D01*
Y129800D01*
X1722000D01*
G01X1698600Y117300D02*
Y123200D01*
X1693700D01*
G01X1695283Y99500D02*
Y102000D01*
X1694242D01*
X1693908Y101875D01*
X1693700Y101708D01*
X1693617Y101375D01*
X1693700Y101042D01*
X1693950Y100833D01*
X1694242Y100708D01*
X1695283D01*
G01X1694242D02*
X1693617Y99500D01*
G01X1691350D02*
Y102000D01*
X1691850Y101500D01*
G01Y99500D02*
X1690850D01*
G01X1689167Y102000D02*
Y100208D01*
X1689000Y99833D01*
X1688667Y99583D01*
X1688250Y99500D01*
X1687833Y99583D01*
X1687500Y99833D01*
X1687333Y100208D01*
Y102000D01*
G01X1685858Y99792D02*
X1685567Y99583D01*
X1685233Y99500D01*
X1684900Y99583D01*
X1684608Y99833D01*
X1684400Y100208D01*
X1684317Y100583D01*
Y101042D01*
X1684400Y101417D01*
X1684608Y101750D01*
X1684858Y101917D01*
X1685150Y102000D01*
X1685483Y101917D01*
X1685733Y101750D01*
X1685900Y101500D01*
X1685983Y101167D01*
X1685900Y100875D01*
X1685692Y100583D01*
X1685442Y100417D01*
X1685150Y100375D01*
X1684817Y100458D01*
X1684567Y100667D01*
X1684317Y101042D01*
G01X1695133Y104100D02*
Y106600D01*
X1694092D01*
X1693758Y106475D01*
X1693550Y106308D01*
X1693467Y105975D01*
X1693550Y105642D01*
X1693800Y105433D01*
X1694092Y105308D01*
X1695133D01*
G01X1694092D02*
X1693467Y104100D01*
G01X1691200D02*
Y106600D01*
X1691700Y106100D01*
G01Y104100D02*
X1690700D01*
G01X1689017Y106600D02*
Y104808D01*
X1688850Y104433D01*
X1688517Y104183D01*
X1688100Y104100D01*
X1687683Y104183D01*
X1687350Y104433D01*
X1687183Y104808D01*
Y106600D01*
G01X1685000Y104100D02*
Y106600D01*
X1685500Y106100D01*
G01Y104100D02*
X1684500D01*
G01X1681900Y106600D02*
X1682233Y106517D01*
X1682483Y106308D01*
X1682650Y106058D01*
X1682775Y105725D01*
X1682817Y105350D01*
X1682775Y104975D01*
X1682650Y104642D01*
X1682483Y104392D01*
X1682233Y104183D01*
X1681900Y104100D01*
X1681567Y104183D01*
X1681317Y104392D01*
X1681150Y104642D01*
X1681025Y104975D01*
X1680983Y105350D01*
X1681025Y105725D01*
X1681150Y106058D01*
X1681317Y106308D01*
X1681567Y106517D01*
X1681900Y106600D01*
G01X1725433Y135500D02*
Y138000D01*
X1724392D01*
X1724058Y137875D01*
X1723850Y137708D01*
X1723767Y137375D01*
X1723850Y137042D01*
X1724100Y136833D01*
X1724392Y136708D01*
X1725433D01*
G01X1724392D02*
X1723767Y135500D01*
G01X1721500D02*
Y138000D01*
X1722000Y137500D01*
G01Y135500D02*
X1721000D01*
G01X1718400Y138000D02*
Y135500D01*
G01X1719358Y138000D02*
X1717442D01*
G01X1716092Y137583D02*
X1715842Y137833D01*
X1715550Y137958D01*
X1715217Y138000D01*
X1714800Y137917D01*
X1714508Y137708D01*
X1714425Y137458D01*
X1714467Y137208D01*
X1714633Y137000D01*
X1715467Y136583D01*
X1715842Y136292D01*
X1716092Y135875D01*
X1716175Y135500D01*
X1714425D01*
G01X1712200D02*
X1711908Y135542D01*
X1711575Y135667D01*
X1711367Y135875D01*
X1711283Y136167D01*
X1711367Y136458D01*
X1711617Y136708D01*
X1711992Y136833D01*
X1712408D01*
X1712658Y136917D01*
X1712867Y137125D01*
X1712950Y137417D01*
X1712825Y137708D01*
X1712533Y137917D01*
X1712200Y138000D01*
X1711867Y137917D01*
X1711575Y137708D01*
X1711450Y137417D01*
X1711533Y137125D01*
X1711742Y136917D01*
X1711992Y136833D01*
X1712408D01*
X1712783Y136708D01*
X1713033Y136458D01*
X1713117Y136167D01*
X1713033Y135875D01*
X1712825Y135667D01*
X1712492Y135542D01*
X1712200Y135500D01*
G01X1725433Y132000D02*
Y134500D01*
X1724392D01*
X1724058Y134375D01*
X1723850Y134208D01*
X1723767Y133875D01*
X1723850Y133542D01*
X1724100Y133333D01*
X1724392Y133208D01*
X1725433D01*
G01X1724392D02*
X1723767Y132000D01*
G01X1721500D02*
Y134500D01*
X1722000Y134000D01*
G01Y132000D02*
X1721000D01*
G01X1718400Y134500D02*
Y132000D01*
G01X1719358Y134500D02*
X1717442D01*
G01X1714800Y132000D02*
Y134500D01*
X1716342Y132708D01*
X1714258D01*
G01X1712200Y134500D02*
X1712533Y134417D01*
X1712783Y134208D01*
X1712950Y133958D01*
X1713075Y133625D01*
X1713117Y133250D01*
X1713075Y132875D01*
X1712950Y132542D01*
X1712783Y132292D01*
X1712533Y132083D01*
X1712200Y132000D01*
X1711867Y132083D01*
X1711617Y132292D01*
X1711450Y132542D01*
X1711325Y132875D01*
X1711283Y133250D01*
X1711325Y133625D01*
X1711450Y133958D01*
X1711617Y134208D01*
X1711867Y134417D01*
X1712200Y134500D01*
G01X1722283Y120600D02*
Y123100D01*
X1721242D01*
X1720908Y122975D01*
X1720700Y122808D01*
X1720617Y122475D01*
X1720700Y122142D01*
X1720950Y121933D01*
X1721242Y121808D01*
X1722283D01*
G01X1721242D02*
X1720617Y120600D01*
G01X1718350D02*
X1718058Y120642D01*
X1717725Y120767D01*
X1717517Y120975D01*
X1717433Y121267D01*
X1717517Y121558D01*
X1717767Y121808D01*
X1718142Y121933D01*
X1718558D01*
X1718808Y122017D01*
X1719017Y122225D01*
X1719100Y122517D01*
X1718975Y122808D01*
X1718683Y123017D01*
X1718350Y123100D01*
X1718017Y123017D01*
X1717725Y122808D01*
X1717600Y122517D01*
X1717683Y122225D01*
X1717892Y122017D01*
X1718142Y121933D01*
X1718558D01*
X1718933Y121808D01*
X1719183Y121558D01*
X1719267Y121267D01*
X1719183Y120975D01*
X1718975Y120767D01*
X1718642Y120642D01*
X1718350Y120600D01*
G01X1716500Y123100D02*
X1715917Y120600D01*
X1715250Y123100D01*
X1714583Y120600D01*
X1714000Y123100D01*
G01X1711650Y120600D02*
Y123100D01*
X1713192Y121308D01*
X1711108D01*
G01X1722283Y124100D02*
Y126600D01*
X1721242D01*
X1720908Y126475D01*
X1720700Y126308D01*
X1720617Y125975D01*
X1720700Y125642D01*
X1720950Y125433D01*
X1721242Y125308D01*
X1722283D01*
G01X1721242D02*
X1720617Y124100D01*
G01X1718350D02*
X1718058Y124142D01*
X1717725Y124267D01*
X1717517Y124475D01*
X1717433Y124767D01*
X1717517Y125058D01*
X1717767Y125308D01*
X1718142Y125433D01*
X1718558D01*
X1718808Y125517D01*
X1719017Y125725D01*
X1719100Y126017D01*
X1718975Y126308D01*
X1718683Y126517D01*
X1718350Y126600D01*
X1718017Y126517D01*
X1717725Y126308D01*
X1717600Y126017D01*
X1717683Y125725D01*
X1717892Y125517D01*
X1718142Y125433D01*
X1718558D01*
X1718933Y125308D01*
X1719183Y125058D01*
X1719267Y124767D01*
X1719183Y124475D01*
X1718975Y124267D01*
X1718642Y124142D01*
X1718350Y124100D01*
G01X1716500Y126600D02*
X1715917Y124100D01*
X1715250Y126600D01*
X1714583Y124100D01*
X1714000Y126600D01*
G01X1713067Y124475D02*
X1712817Y124267D01*
X1712525Y124142D01*
X1712150Y124100D01*
X1711775Y124183D01*
X1711483Y124350D01*
X1711275Y124642D01*
X1711233Y124975D01*
X1711317Y125308D01*
X1711525Y125517D01*
X1711817Y125683D01*
X1712108Y125725D01*
X1712400Y125683D01*
X1712775Y125517D01*
X1712650Y126600D01*
X1711525D01*
G01X1667500Y108217D02*
X1670000D01*
Y109258D01*
X1669875Y109592D01*
X1669708Y109800D01*
X1669375Y109883D01*
X1669042Y109800D01*
X1668833Y109550D01*
X1668708Y109258D01*
Y108217D01*
G01Y109258D02*
X1667500Y109883D01*
G01X1669583Y111358D02*
X1669833Y111608D01*
X1669958Y111900D01*
X1670000Y112233D01*
X1669917Y112650D01*
X1669708Y112942D01*
X1669458Y113025D01*
X1669208Y112983D01*
X1669000Y112817D01*
X1668583Y111983D01*
X1668292Y111608D01*
X1667875Y111358D01*
X1667500Y111275D01*
Y113025D01*
G01X1670000Y114000D02*
X1667500Y114583D01*
X1670000Y115250D01*
X1667500Y115917D01*
X1670000Y116500D01*
G01X1667875Y117433D02*
X1667667Y117683D01*
X1667542Y117975D01*
X1667500Y118350D01*
X1667583Y118725D01*
X1667750Y119017D01*
X1668042Y119225D01*
X1668375Y119267D01*
X1668708Y119183D01*
X1668917Y118975D01*
X1669083Y118683D01*
X1669125Y118392D01*
X1669083Y118100D01*
X1668917Y117725D01*
X1670000Y117850D01*
Y118975D01*
G01X1695133Y107600D02*
Y110100D01*
X1694092D01*
X1693758Y109975D01*
X1693550Y109808D01*
X1693467Y109475D01*
X1693550Y109142D01*
X1693800Y108933D01*
X1694092Y108808D01*
X1695133D01*
G01X1694092D02*
X1693467Y107600D01*
G01X1691992Y109683D02*
X1691742Y109933D01*
X1691450Y110058D01*
X1691117Y110100D01*
X1690700Y110017D01*
X1690408Y109808D01*
X1690325Y109558D01*
X1690367Y109308D01*
X1690533Y109100D01*
X1691367Y108683D01*
X1691742Y108392D01*
X1691992Y107975D01*
X1692075Y107600D01*
X1690325D01*
G01X1689017Y107975D02*
X1688767Y107767D01*
X1688475Y107642D01*
X1688100Y107600D01*
X1687725Y107683D01*
X1687433Y107850D01*
X1687225Y108142D01*
X1687183Y108475D01*
X1687267Y108808D01*
X1687475Y109017D01*
X1687767Y109183D01*
X1688058Y109225D01*
X1688350Y109183D01*
X1688725Y109017D01*
X1688600Y110100D01*
X1687475D01*
G01X1686250D02*
X1685667Y107600D01*
X1685000Y110100D01*
X1684333Y107600D01*
X1683750Y110100D01*
G01X1681900Y107600D02*
Y110100D01*
X1682400Y109600D01*
G01Y107600D02*
X1681400D01*
G01X1679592Y109683D02*
X1679342Y109933D01*
X1679050Y110058D01*
X1678717Y110100D01*
X1678300Y110017D01*
X1678008Y109808D01*
X1677925Y109558D01*
X1677967Y109308D01*
X1678133Y109100D01*
X1678967Y108683D01*
X1679342Y108392D01*
X1679592Y107975D01*
X1679675Y107600D01*
X1677925D01*
G01X1676408Y107892D02*
X1676117Y107683D01*
X1675783Y107600D01*
X1675450Y107683D01*
X1675158Y107933D01*
X1674950Y108308D01*
X1674867Y108683D01*
Y109142D01*
X1674950Y109517D01*
X1675158Y109850D01*
X1675408Y110017D01*
X1675700Y110100D01*
X1676033Y110017D01*
X1676283Y109850D01*
X1676450Y109600D01*
X1676533Y109267D01*
X1676450Y108975D01*
X1676242Y108683D01*
X1675992Y108517D01*
X1675700Y108475D01*
X1675367Y108558D01*
X1675117Y108767D01*
X1674867Y109142D01*
G01X1695133Y111400D02*
Y113900D01*
X1694092D01*
X1693758Y113775D01*
X1693550Y113608D01*
X1693467Y113275D01*
X1693550Y112942D01*
X1693800Y112733D01*
X1694092Y112608D01*
X1695133D01*
G01X1694092D02*
X1693467Y111400D01*
G01X1691992Y113483D02*
X1691742Y113733D01*
X1691450Y113858D01*
X1691117Y113900D01*
X1690700Y113817D01*
X1690408Y113608D01*
X1690325Y113358D01*
X1690367Y113108D01*
X1690533Y112900D01*
X1691367Y112483D01*
X1691742Y112192D01*
X1691992Y111775D01*
X1692075Y111400D01*
X1690325D01*
G01X1689017Y111775D02*
X1688767Y111567D01*
X1688475Y111442D01*
X1688100Y111400D01*
X1687725Y111483D01*
X1687433Y111650D01*
X1687225Y111942D01*
X1687183Y112275D01*
X1687267Y112608D01*
X1687475Y112817D01*
X1687767Y112983D01*
X1688058Y113025D01*
X1688350Y112983D01*
X1688725Y112817D01*
X1688600Y113900D01*
X1687475D01*
G01X1686250D02*
X1685667Y111400D01*
X1685000Y113900D01*
X1684333Y111400D01*
X1683750Y113900D01*
G01X1681900Y111400D02*
Y113900D01*
X1682400Y113400D01*
G01Y111400D02*
X1681400D01*
G01X1679717Y111900D02*
X1679467Y111608D01*
X1679133Y111442D01*
X1678758Y111400D01*
X1678425Y111442D01*
X1678092Y111650D01*
X1677883Y111900D01*
X1677842Y112150D01*
X1677925Y112442D01*
X1678217Y112650D01*
X1678508Y112733D01*
X1678883D01*
G01X1678508D02*
X1678258Y112858D01*
X1678050Y113067D01*
X1677967Y113317D01*
X1678050Y113567D01*
X1678258Y113775D01*
X1678633Y113900D01*
X1679008Y113858D01*
X1679383Y113692D01*
G01X1675700Y113900D02*
X1676033Y113817D01*
X1676283Y113608D01*
X1676450Y113358D01*
X1676575Y113025D01*
X1676617Y112650D01*
X1676575Y112275D01*
X1676450Y111942D01*
X1676283Y111692D01*
X1676033Y111483D01*
X1675700Y111400D01*
X1675367Y111483D01*
X1675117Y111692D01*
X1674950Y111942D01*
X1674825Y112275D01*
X1674783Y112650D01*
X1674825Y113025D01*
X1674950Y113358D01*
X1675117Y113608D01*
X1675367Y113817D01*
X1675700Y113900D01*
G01X1695133Y114900D02*
Y117400D01*
X1694092D01*
X1693758Y117275D01*
X1693550Y117108D01*
X1693467Y116775D01*
X1693550Y116442D01*
X1693800Y116233D01*
X1694092Y116108D01*
X1695133D01*
G01X1694092D02*
X1693467Y114900D01*
G01X1691200D02*
Y117400D01*
X1691700Y116900D01*
G01Y114900D02*
X1690700D01*
G01X1689017Y117400D02*
Y115608D01*
X1688850Y115233D01*
X1688517Y114983D01*
X1688100Y114900D01*
X1687683Y114983D01*
X1687350Y115233D01*
X1687183Y115608D01*
Y117400D01*
G01X1684500Y114900D02*
Y117400D01*
X1686042Y115608D01*
X1683958D01*
G01X1695133Y118400D02*
Y120900D01*
X1694092D01*
X1693758Y120775D01*
X1693550Y120608D01*
X1693467Y120275D01*
X1693550Y119942D01*
X1693800Y119733D01*
X1694092Y119608D01*
X1695133D01*
G01X1694092D02*
X1693467Y118400D01*
G01X1691992Y120483D02*
X1691742Y120733D01*
X1691450Y120858D01*
X1691117Y120900D01*
X1690700Y120817D01*
X1690408Y120608D01*
X1690325Y120358D01*
X1690367Y120108D01*
X1690533Y119900D01*
X1691367Y119483D01*
X1691742Y119192D01*
X1691992Y118775D01*
X1692075Y118400D01*
X1690325D01*
G01X1689058D02*
Y120900D01*
X1687142Y118400D01*
Y120900D01*
G01X1685000Y118400D02*
Y120900D01*
X1685500Y120400D01*
G01Y118400D02*
X1684500D01*
G01X1682817Y118900D02*
X1682567Y118608D01*
X1682233Y118442D01*
X1681858Y118400D01*
X1681525Y118442D01*
X1681192Y118650D01*
X1680983Y118900D01*
X1680942Y119150D01*
X1681025Y119442D01*
X1681317Y119650D01*
X1681608Y119733D01*
X1681983D01*
G01X1681608D02*
X1681358Y119858D01*
X1681150Y120067D01*
X1681067Y120317D01*
X1681150Y120567D01*
X1681358Y120775D01*
X1681733Y120900D01*
X1682108Y120858D01*
X1682483Y120692D01*
G01X1697000Y96867D02*
X1699500D01*
Y97908D01*
X1699375Y98242D01*
X1699208Y98450D01*
X1698875Y98533D01*
X1698542Y98450D01*
X1698333Y98200D01*
X1698208Y97908D01*
Y96867D01*
G01Y97908D02*
X1697000Y98533D01*
G01Y100800D02*
X1699500D01*
X1699000Y100300D01*
G01X1697000D02*
Y101300D01*
G01X1699500Y102983D02*
X1697708D01*
X1697333Y103150D01*
X1697083Y103483D01*
X1697000Y103900D01*
X1697083Y104317D01*
X1697333Y104650D01*
X1697708Y104817D01*
X1699500D01*
G01X1697000Y107000D02*
X1699500D01*
X1699000Y106500D01*
G01X1697000D02*
Y107500D01*
G01Y110100D02*
X1697042Y110392D01*
X1697167Y110725D01*
X1697375Y110933D01*
X1697667Y111017D01*
X1697958Y110933D01*
X1698208Y110683D01*
X1698333Y110308D01*
Y109892D01*
X1698417Y109642D01*
X1698625Y109433D01*
X1698917Y109350D01*
X1699208Y109475D01*
X1699417Y109767D01*
X1699500Y110100D01*
X1699417Y110433D01*
X1699208Y110725D01*
X1698917Y110850D01*
X1698625Y110767D01*
X1698417Y110558D01*
X1698333Y110308D01*
Y109892D01*
X1698208Y109517D01*
X1697958Y109267D01*
X1697667Y109183D01*
X1697375Y109267D01*
X1697167Y109475D01*
X1697042Y109808D01*
X1697000Y110100D01*
G01X1700500Y96867D02*
X1703000D01*
Y97908D01*
X1702875Y98242D01*
X1702708Y98450D01*
X1702375Y98533D01*
X1702042Y98450D01*
X1701833Y98200D01*
X1701708Y97908D01*
Y96867D01*
G01Y97908D02*
X1700500Y98533D01*
G01Y100800D02*
X1703000D01*
X1702500Y100300D01*
G01X1700500D02*
Y101300D01*
G01X1703000Y102983D02*
X1701208D01*
X1700833Y103150D01*
X1700583Y103483D01*
X1700500Y103900D01*
X1700583Y104317D01*
X1700833Y104650D01*
X1701208Y104817D01*
X1703000D01*
G01X1702583Y106208D02*
X1702833Y106458D01*
X1702958Y106750D01*
X1703000Y107083D01*
X1702917Y107500D01*
X1702708Y107792D01*
X1702458Y107875D01*
X1702208Y107833D01*
X1702000Y107667D01*
X1701583Y106833D01*
X1701292Y106458D01*
X1700875Y106208D01*
X1700500Y106125D01*
Y107875D01*
G01X1701000Y109183D02*
X1700708Y109433D01*
X1700542Y109767D01*
X1700500Y110142D01*
X1700542Y110475D01*
X1700750Y110808D01*
X1701000Y111017D01*
X1701250Y111058D01*
X1701542Y110975D01*
X1701750Y110683D01*
X1701833Y110392D01*
Y110017D01*
G01Y110392D02*
X1701958Y110642D01*
X1702167Y110850D01*
X1702417Y110933D01*
X1702667Y110850D01*
X1702875Y110642D01*
X1703000Y110267D01*
X1702958Y109892D01*
X1702792Y109517D01*
G01X1704000Y96867D02*
X1706500D01*
Y97908D01*
X1706375Y98242D01*
X1706208Y98450D01*
X1705875Y98533D01*
X1705542Y98450D01*
X1705333Y98200D01*
X1705208Y97908D01*
Y96867D01*
G01Y97908D02*
X1704000Y98533D01*
G01Y100800D02*
X1706500D01*
X1706000Y100300D01*
G01X1704000D02*
Y101300D01*
G01X1706500Y102983D02*
X1704708D01*
X1704333Y103150D01*
X1704083Y103483D01*
X1704000Y103900D01*
X1704083Y104317D01*
X1704333Y104650D01*
X1704708Y104817D01*
X1706500D01*
G01X1706083Y106208D02*
X1706333Y106458D01*
X1706458Y106750D01*
X1706500Y107083D01*
X1706417Y107500D01*
X1706208Y107792D01*
X1705958Y107875D01*
X1705708Y107833D01*
X1705500Y107667D01*
X1705083Y106833D01*
X1704792Y106458D01*
X1704375Y106208D01*
X1704000Y106125D01*
Y107875D01*
G01Y110600D02*
X1706500D01*
X1704708Y109058D01*
Y111142D01*
G01X1707500Y96867D02*
X1710000D01*
Y97908D01*
X1709875Y98242D01*
X1709708Y98450D01*
X1709375Y98533D01*
X1709042Y98450D01*
X1708833Y98200D01*
X1708708Y97908D01*
Y96867D01*
G01Y97908D02*
X1707500Y98533D01*
G01Y100800D02*
X1710000D01*
X1709500Y100300D01*
G01X1707500D02*
Y101300D01*
G01X1710000Y102983D02*
X1708208D01*
X1707833Y103150D01*
X1707583Y103483D01*
X1707500Y103900D01*
X1707583Y104317D01*
X1707833Y104650D01*
X1708208Y104817D01*
X1710000D01*
G01X1707500Y107000D02*
X1710000D01*
X1709500Y106500D01*
G01X1707500D02*
Y107500D01*
G01Y110017D02*
X1708042Y110100D01*
X1708500Y110225D01*
X1708917Y110392D01*
X1709375Y110600D01*
X1710000Y110933D01*
Y109267D01*
G01X1682592Y142467D02*
X1682717Y142217D01*
X1682800Y141925D01*
Y141592D01*
X1682675Y141217D01*
X1682467Y140925D01*
X1682217Y140717D01*
X1681800Y140550D01*
X1681425Y140508D01*
X1681050Y140592D01*
X1680800Y140717D01*
X1680550Y140967D01*
X1680383Y141258D01*
X1680300Y141550D01*
Y141842D01*
X1680383Y142133D01*
X1680508Y142383D01*
X1680675Y142592D01*
G01X1682383Y143858D02*
X1682633Y144108D01*
X1682758Y144400D01*
X1682800Y144733D01*
X1682717Y145150D01*
X1682508Y145442D01*
X1682258Y145525D01*
X1682008Y145483D01*
X1681800Y145317D01*
X1681383Y144483D01*
X1681092Y144108D01*
X1680675Y143858D01*
X1680300Y143775D01*
Y145525D01*
G01X1680675Y146833D02*
X1680467Y147083D01*
X1680342Y147375D01*
X1680300Y147750D01*
X1680383Y148125D01*
X1680550Y148417D01*
X1680842Y148625D01*
X1681175Y148667D01*
X1681508Y148583D01*
X1681717Y148375D01*
X1681883Y148083D01*
X1681925Y147792D01*
X1681883Y147500D01*
X1681717Y147125D01*
X1682800Y147250D01*
Y148375D01*
G01Y149600D02*
X1680300Y150183D01*
X1682800Y150850D01*
X1680300Y151517D01*
X1682800Y152100D01*
G01X1680675Y153033D02*
X1680467Y153283D01*
X1680342Y153575D01*
X1680300Y153950D01*
X1680383Y154325D01*
X1680550Y154617D01*
X1680842Y154825D01*
X1681175Y154867D01*
X1681508Y154783D01*
X1681717Y154575D01*
X1681883Y154283D01*
X1681925Y153992D01*
X1681883Y153700D01*
X1681717Y153325D01*
X1682800Y153450D01*
Y154575D01*
G01X1680592Y156342D02*
X1680383Y156633D01*
X1680300Y156967D01*
X1680383Y157300D01*
X1680633Y157592D01*
X1681008Y157800D01*
X1681383Y157883D01*
X1681842D01*
X1682217Y157800D01*
X1682550Y157592D01*
X1682717Y157342D01*
X1682800Y157050D01*
X1682717Y156717D01*
X1682550Y156467D01*
X1682300Y156300D01*
X1681967Y156217D01*
X1681675Y156300D01*
X1681383Y156508D01*
X1681217Y156758D01*
X1681175Y157050D01*
X1681258Y157383D01*
X1681467Y157633D01*
X1681842Y157883D01*
G01X1674033Y125892D02*
X1674283Y126017D01*
X1674575Y126100D01*
X1674908D01*
X1675283Y125975D01*
X1675575Y125767D01*
X1675783Y125517D01*
X1675950Y125100D01*
X1675992Y124725D01*
X1675908Y124350D01*
X1675783Y124100D01*
X1675533Y123850D01*
X1675242Y123683D01*
X1674950Y123600D01*
X1674658D01*
X1674367Y123683D01*
X1674117Y123808D01*
X1673908Y123975D01*
G01X1672642Y125683D02*
X1672392Y125933D01*
X1672100Y126058D01*
X1671767Y126100D01*
X1671350Y126017D01*
X1671058Y125808D01*
X1670975Y125558D01*
X1671017Y125308D01*
X1671183Y125100D01*
X1672017Y124683D01*
X1672392Y124392D01*
X1672642Y123975D01*
X1672725Y123600D01*
X1670975D01*
G01X1669667Y123975D02*
X1669417Y123767D01*
X1669125Y123642D01*
X1668750Y123600D01*
X1668375Y123683D01*
X1668083Y123850D01*
X1667875Y124142D01*
X1667833Y124475D01*
X1667917Y124808D01*
X1668125Y125017D01*
X1668417Y125183D01*
X1668708Y125225D01*
X1669000Y125183D01*
X1669375Y125017D01*
X1669250Y126100D01*
X1668125D01*
G01X1666900D02*
X1666317Y123600D01*
X1665650Y126100D01*
X1664983Y123600D01*
X1664400Y126100D01*
G01X1663342Y125683D02*
X1663092Y125933D01*
X1662800Y126058D01*
X1662467Y126100D01*
X1662050Y126017D01*
X1661758Y125808D01*
X1661675Y125558D01*
X1661717Y125308D01*
X1661883Y125100D01*
X1662717Y124683D01*
X1663092Y124392D01*
X1663342Y123975D01*
X1663425Y123600D01*
X1661675D01*
G01X1660242Y125683D02*
X1659992Y125933D01*
X1659700Y126058D01*
X1659367Y126100D01*
X1658950Y126017D01*
X1658658Y125808D01*
X1658575Y125558D01*
X1658617Y125308D01*
X1658783Y125100D01*
X1659617Y124683D01*
X1659992Y124392D01*
X1660242Y123975D01*
X1660325Y123600D01*
X1658575D01*
G01X1698692Y134867D02*
X1698817Y134617D01*
X1698900Y134325D01*
Y133992D01*
X1698775Y133617D01*
X1698567Y133325D01*
X1698317Y133117D01*
X1697900Y132950D01*
X1697525Y132908D01*
X1697150Y132992D01*
X1696900Y133117D01*
X1696650Y133367D01*
X1696483Y133658D01*
X1696400Y133950D01*
Y134242D01*
X1696483Y134533D01*
X1696608Y134783D01*
X1696775Y134992D01*
G01X1698483Y136258D02*
X1698733Y136508D01*
X1698858Y136800D01*
X1698900Y137133D01*
X1698817Y137550D01*
X1698608Y137842D01*
X1698358Y137925D01*
X1698108Y137883D01*
X1697900Y137717D01*
X1697483Y136883D01*
X1697192Y136508D01*
X1696775Y136258D01*
X1696400Y136175D01*
Y137925D01*
G01X1696775Y139233D02*
X1696567Y139483D01*
X1696442Y139775D01*
X1696400Y140150D01*
X1696483Y140525D01*
X1696650Y140817D01*
X1696942Y141025D01*
X1697275Y141067D01*
X1697608Y140983D01*
X1697817Y140775D01*
X1697983Y140483D01*
X1698025Y140192D01*
X1697983Y139900D01*
X1697817Y139525D01*
X1698900Y139650D01*
Y140775D01*
G01Y142000D02*
X1696400Y142583D01*
X1698900Y143250D01*
X1696400Y143917D01*
X1698900Y144500D01*
G01X1696400Y146350D02*
X1698900D01*
X1698400Y145850D01*
G01X1696400D02*
Y146850D01*
G01X1697442Y148658D02*
X1697733Y148950D01*
X1697900Y149200D01*
X1697983Y149533D01*
X1697900Y149825D01*
X1697733Y150033D01*
X1697483Y150200D01*
X1697192Y150242D01*
X1696942Y150200D01*
X1696692Y150033D01*
X1696483Y149783D01*
X1696400Y149492D01*
X1696483Y149158D01*
X1696733Y148867D01*
X1697108Y148700D01*
X1697525Y148658D01*
X1698067Y148742D01*
X1698358Y148867D01*
X1698650Y149075D01*
X1698858Y149367D01*
X1698900Y149658D01*
X1698817Y149950D01*
X1698608Y150158D01*
G01X1707592Y125717D02*
X1707717Y125467D01*
X1707800Y125175D01*
Y124842D01*
X1707675Y124467D01*
X1707467Y124175D01*
X1707217Y123967D01*
X1706800Y123800D01*
X1706425Y123758D01*
X1706050Y123842D01*
X1705800Y123967D01*
X1705550Y124217D01*
X1705383Y124508D01*
X1705300Y124800D01*
Y125092D01*
X1705383Y125383D01*
X1705508Y125633D01*
X1705675Y125842D01*
G01X1707383Y127108D02*
X1707633Y127358D01*
X1707758Y127650D01*
X1707800Y127983D01*
X1707717Y128400D01*
X1707508Y128692D01*
X1707258Y128775D01*
X1707008Y128733D01*
X1706800Y128567D01*
X1706383Y127733D01*
X1706092Y127358D01*
X1705675Y127108D01*
X1705300Y127025D01*
Y128775D01*
G01X1705675Y130083D02*
X1705467Y130333D01*
X1705342Y130625D01*
X1705300Y131000D01*
X1705383Y131375D01*
X1705550Y131667D01*
X1705842Y131875D01*
X1706175Y131917D01*
X1706508Y131833D01*
X1706717Y131625D01*
X1706883Y131333D01*
X1706925Y131042D01*
X1706883Y130750D01*
X1706717Y130375D01*
X1707800Y130500D01*
Y131625D01*
G01Y132850D02*
X1705300Y133433D01*
X1707800Y134100D01*
X1705300Y134767D01*
X1707800Y135350D01*
G01X1705300Y137200D02*
X1707800D01*
X1707300Y136700D01*
G01X1705300D02*
Y137700D01*
G01X1703692Y117667D02*
X1703817Y117417D01*
X1703900Y117125D01*
Y116792D01*
X1703775Y116417D01*
X1703567Y116125D01*
X1703317Y115917D01*
X1702900Y115750D01*
X1702525Y115708D01*
X1702150Y115792D01*
X1701900Y115917D01*
X1701650Y116167D01*
X1701483Y116458D01*
X1701400Y116750D01*
Y117042D01*
X1701483Y117333D01*
X1701608Y117583D01*
X1701775Y117792D01*
G01X1701400Y119850D02*
X1701442Y120142D01*
X1701567Y120475D01*
X1701775Y120683D01*
X1702067Y120767D01*
X1702358Y120683D01*
X1702608Y120433D01*
X1702733Y120058D01*
Y119642D01*
X1702817Y119392D01*
X1703025Y119183D01*
X1703317Y119100D01*
X1703608Y119225D01*
X1703817Y119517D01*
X1703900Y119850D01*
X1703817Y120183D01*
X1703608Y120475D01*
X1703317Y120600D01*
X1703025Y120517D01*
X1702817Y120308D01*
X1702733Y120058D01*
Y119642D01*
X1702608Y119267D01*
X1702358Y119017D01*
X1702067Y118933D01*
X1701775Y119017D01*
X1701567Y119225D01*
X1701442Y119558D01*
X1701400Y119850D01*
G01X1703900Y121700D02*
X1701400Y122283D01*
X1703900Y122950D01*
X1701400Y123617D01*
X1703900Y124200D01*
G01X1703483Y125258D02*
X1703733Y125508D01*
X1703858Y125800D01*
X1703900Y126133D01*
X1703817Y126550D01*
X1703608Y126842D01*
X1703358Y126925D01*
X1703108Y126883D01*
X1702900Y126717D01*
X1702483Y125883D01*
X1702192Y125508D01*
X1701775Y125258D01*
X1701400Y125175D01*
Y126925D01*
G01X1670292Y143967D02*
X1670417Y143717D01*
X1670500Y143425D01*
Y143092D01*
X1670375Y142717D01*
X1670167Y142425D01*
X1669917Y142217D01*
X1669500Y142050D01*
X1669125Y142008D01*
X1668750Y142092D01*
X1668500Y142217D01*
X1668250Y142467D01*
X1668083Y142758D01*
X1668000Y143050D01*
Y143342D01*
X1668083Y143633D01*
X1668208Y143883D01*
X1668375Y144092D01*
G01X1670083Y145358D02*
X1670333Y145608D01*
X1670458Y145900D01*
X1670500Y146233D01*
X1670417Y146650D01*
X1670208Y146942D01*
X1669958Y147025D01*
X1669708Y146983D01*
X1669500Y146817D01*
X1669083Y145983D01*
X1668792Y145608D01*
X1668375Y145358D01*
X1668000Y145275D01*
Y147025D01*
G01X1668375Y148333D02*
X1668167Y148583D01*
X1668042Y148875D01*
X1668000Y149250D01*
X1668083Y149625D01*
X1668250Y149917D01*
X1668542Y150125D01*
X1668875Y150167D01*
X1669208Y150083D01*
X1669417Y149875D01*
X1669583Y149583D01*
X1669625Y149292D01*
X1669583Y149000D01*
X1669417Y148625D01*
X1670500Y148750D01*
Y149875D01*
G01Y151100D02*
X1668000Y151683D01*
X1670500Y152350D01*
X1668000Y153017D01*
X1670500Y153600D01*
G01X1668375Y154533D02*
X1668167Y154783D01*
X1668042Y155075D01*
X1668000Y155450D01*
X1668083Y155825D01*
X1668250Y156117D01*
X1668542Y156325D01*
X1668875Y156367D01*
X1669208Y156283D01*
X1669417Y156075D01*
X1669583Y155783D01*
X1669625Y155492D01*
X1669583Y155200D01*
X1669417Y154825D01*
X1670500Y154950D01*
Y156075D01*
G01X1669042Y157758D02*
X1669333Y158050D01*
X1669500Y158300D01*
X1669583Y158633D01*
X1669500Y158925D01*
X1669333Y159133D01*
X1669083Y159300D01*
X1668792Y159342D01*
X1668542Y159300D01*
X1668292Y159133D01*
X1668083Y158883D01*
X1668000Y158592D01*
X1668083Y158258D01*
X1668333Y157967D01*
X1668708Y157800D01*
X1669125Y157758D01*
X1669667Y157842D01*
X1669958Y157967D01*
X1670250Y158175D01*
X1670458Y158467D01*
X1670500Y158758D01*
X1670417Y159050D01*
X1670208Y159258D01*
G01X1662492Y142967D02*
X1662617Y142717D01*
X1662700Y142425D01*
Y142092D01*
X1662575Y141717D01*
X1662367Y141425D01*
X1662117Y141217D01*
X1661700Y141050D01*
X1661325Y141008D01*
X1660950Y141092D01*
X1660700Y141217D01*
X1660450Y141467D01*
X1660283Y141758D01*
X1660200Y142050D01*
Y142342D01*
X1660283Y142633D01*
X1660408Y142883D01*
X1660575Y143092D01*
G01X1662283Y144358D02*
X1662533Y144608D01*
X1662658Y144900D01*
X1662700Y145233D01*
X1662617Y145650D01*
X1662408Y145942D01*
X1662158Y146025D01*
X1661908Y145983D01*
X1661700Y145817D01*
X1661283Y144983D01*
X1660992Y144608D01*
X1660575Y144358D01*
X1660200Y144275D01*
Y146025D01*
G01X1660575Y147333D02*
X1660367Y147583D01*
X1660242Y147875D01*
X1660200Y148250D01*
X1660283Y148625D01*
X1660450Y148917D01*
X1660742Y149125D01*
X1661075Y149167D01*
X1661408Y149083D01*
X1661617Y148875D01*
X1661783Y148583D01*
X1661825Y148292D01*
X1661783Y148000D01*
X1661617Y147625D01*
X1662700Y147750D01*
Y148875D01*
G01Y150100D02*
X1660200Y150683D01*
X1662700Y151350D01*
X1660200Y152017D01*
X1662700Y152600D01*
G01X1660575Y153533D02*
X1660367Y153783D01*
X1660242Y154075D01*
X1660200Y154450D01*
X1660283Y154825D01*
X1660450Y155117D01*
X1660742Y155325D01*
X1661075Y155367D01*
X1661408Y155283D01*
X1661617Y155075D01*
X1661783Y154783D01*
X1661825Y154492D01*
X1661783Y154200D01*
X1661617Y153825D01*
X1662700Y153950D01*
Y155075D01*
G01X1660200Y157467D02*
X1660742Y157550D01*
X1661200Y157675D01*
X1661617Y157842D01*
X1662075Y158050D01*
X1662700Y158383D01*
Y156717D01*
G01X1666692Y143167D02*
X1666817Y142917D01*
X1666900Y142625D01*
Y142292D01*
X1666775Y141917D01*
X1666567Y141625D01*
X1666317Y141417D01*
X1665900Y141250D01*
X1665525Y141208D01*
X1665150Y141292D01*
X1664900Y141417D01*
X1664650Y141667D01*
X1664483Y141958D01*
X1664400Y142250D01*
Y142542D01*
X1664483Y142833D01*
X1664608Y143083D01*
X1664775Y143292D01*
G01X1666483Y144558D02*
X1666733Y144808D01*
X1666858Y145100D01*
X1666900Y145433D01*
X1666817Y145850D01*
X1666608Y146142D01*
X1666358Y146225D01*
X1666108Y146183D01*
X1665900Y146017D01*
X1665483Y145183D01*
X1665192Y144808D01*
X1664775Y144558D01*
X1664400Y144475D01*
Y146225D01*
G01X1664775Y147533D02*
X1664567Y147783D01*
X1664442Y148075D01*
X1664400Y148450D01*
X1664483Y148825D01*
X1664650Y149117D01*
X1664942Y149325D01*
X1665275Y149367D01*
X1665608Y149283D01*
X1665817Y149075D01*
X1665983Y148783D01*
X1666025Y148492D01*
X1665983Y148200D01*
X1665817Y147825D01*
X1666900Y147950D01*
Y149075D01*
G01Y150300D02*
X1664400Y150883D01*
X1666900Y151550D01*
X1664400Y152217D01*
X1666900Y152800D01*
G01X1664775Y153733D02*
X1664567Y153983D01*
X1664442Y154275D01*
X1664400Y154650D01*
X1664483Y155025D01*
X1664650Y155317D01*
X1664942Y155525D01*
X1665275Y155567D01*
X1665608Y155483D01*
X1665817Y155275D01*
X1665983Y154983D01*
X1666025Y154692D01*
X1665983Y154400D01*
X1665817Y154025D01*
X1666900Y154150D01*
Y155275D01*
G01X1664400Y157750D02*
X1664442Y158042D01*
X1664567Y158375D01*
X1664775Y158583D01*
X1665067Y158667D01*
X1665358Y158583D01*
X1665608Y158333D01*
X1665733Y157958D01*
Y157542D01*
X1665817Y157292D01*
X1666025Y157083D01*
X1666317Y157000D01*
X1666608Y157125D01*
X1666817Y157417D01*
X1666900Y157750D01*
X1666817Y158083D01*
X1666608Y158375D01*
X1666317Y158500D01*
X1666025Y158417D01*
X1665817Y158208D01*
X1665733Y157958D01*
Y157542D01*
X1665608Y157167D01*
X1665358Y156917D01*
X1665067Y156833D01*
X1664775Y156917D01*
X1664567Y157125D01*
X1664442Y157458D01*
X1664400Y157750D01*
G01X1697250Y126100D02*
X1697583Y126142D01*
X1697875Y126308D01*
X1698125Y126558D01*
X1698292Y126850D01*
X1698375Y127183D01*
Y127517D01*
X1698292Y127850D01*
X1698125Y128142D01*
X1697875Y128392D01*
X1697583Y128558D01*
X1697250Y128600D01*
X1696917Y128558D01*
X1696625Y128392D01*
X1696375Y128142D01*
X1696208Y127850D01*
X1696125Y127517D01*
Y127183D01*
X1696208Y126850D01*
X1696375Y126558D01*
X1696625Y126308D01*
X1696917Y126142D01*
X1697250Y126100D01*
G01X1696917Y126767D02*
X1696417Y126100D01*
G01X1694858Y126392D02*
X1694567Y126183D01*
X1694233Y126100D01*
X1693900Y126183D01*
X1693608Y126433D01*
X1693400Y126808D01*
X1693317Y127183D01*
Y127642D01*
X1693400Y128017D01*
X1693608Y128350D01*
X1693858Y128517D01*
X1694150Y128600D01*
X1694483Y128517D01*
X1694733Y128350D01*
X1694900Y128100D01*
X1694983Y127767D01*
X1694900Y127475D01*
X1694692Y127183D01*
X1694442Y127017D01*
X1694150Y126975D01*
X1693817Y127058D01*
X1693567Y127267D01*
X1693317Y127642D01*
G01X1692300Y128600D02*
X1691717Y126100D01*
X1691050Y128600D01*
X1690383Y126100D01*
X1689800Y128600D01*
G01X1688742Y128183D02*
X1688492Y128433D01*
X1688200Y128558D01*
X1687867Y128600D01*
X1687450Y128517D01*
X1687158Y128308D01*
X1687075Y128058D01*
X1687117Y127808D01*
X1687283Y127600D01*
X1688117Y127183D01*
X1688492Y126892D01*
X1688742Y126475D01*
X1688825Y126100D01*
X1687075D01*
G01X1703683Y129500D02*
Y132000D01*
X1702642D01*
X1702308Y131875D01*
X1702100Y131708D01*
X1702017Y131375D01*
X1702100Y131042D01*
X1702350Y130833D01*
X1702642Y130708D01*
X1703683D01*
G01X1702642D02*
X1702017Y129500D01*
G01X1700667Y130000D02*
X1700417Y129708D01*
X1700083Y129542D01*
X1699708Y129500D01*
X1699375Y129542D01*
X1699042Y129750D01*
X1698833Y130000D01*
X1698792Y130250D01*
X1698875Y130542D01*
X1699167Y130750D01*
X1699458Y130833D01*
X1699833D01*
G01X1699458D02*
X1699208Y130958D01*
X1699000Y131167D01*
X1698917Y131417D01*
X1699000Y131667D01*
X1699208Y131875D01*
X1699583Y132000D01*
X1699958Y131958D01*
X1700333Y131792D01*
G01X1697900Y132000D02*
X1697317Y129500D01*
X1696650Y132000D01*
X1695983Y129500D01*
X1695400Y132000D01*
G01X1693050Y129500D02*
Y132000D01*
X1694592Y130208D01*
X1692508D01*
G01X1657084Y183721D02*
X1664951D01*
Y177316D01*
G01X1667547Y184266D02*
Y186387D01*
X1669668Y184266D01*
X1667547D01*
G01D02*
X1671500Y188219D01*
Y194100D01*
X1697800D01*
Y195100D01*
X1705700D01*
Y196100D01*
G01X1705592Y201200D02*
Y219500D01*
X1656500D01*
Y203500D01*
X1654500D01*
Y196000D01*
X1671500D01*
Y194100D01*
G01X1667700Y197517D02*
X1670200D01*
Y198558D01*
X1670075Y198892D01*
X1669908Y199100D01*
X1669575Y199183D01*
X1669242Y199100D01*
X1669033Y198850D01*
X1668908Y198558D01*
Y197517D01*
G01Y198558D02*
X1667700Y199183D01*
G01X1667992Y200742D02*
X1667783Y201033D01*
X1667700Y201367D01*
X1667783Y201700D01*
X1668033Y201992D01*
X1668408Y202200D01*
X1668783Y202283D01*
X1669242D01*
X1669617Y202200D01*
X1669950Y201992D01*
X1670117Y201742D01*
X1670200Y201450D01*
X1670117Y201117D01*
X1669950Y200867D01*
X1669700Y200700D01*
X1669367Y200617D01*
X1669075Y200700D01*
X1668783Y200908D01*
X1668617Y201158D01*
X1668575Y201450D01*
X1668658Y201783D01*
X1668867Y202033D01*
X1669242Y202283D01*
G01X1667700Y203758D02*
X1670200D01*
Y205342D01*
G01X1668992Y204758D02*
Y203758D01*
G01X1669783Y206858D02*
X1670033Y207108D01*
X1670158Y207400D01*
X1670200Y207733D01*
X1670117Y208150D01*
X1669908Y208442D01*
X1669658Y208525D01*
X1669408Y208483D01*
X1669200Y208317D01*
X1668783Y207483D01*
X1668492Y207108D01*
X1668075Y206858D01*
X1667700Y206775D01*
Y208525D01*
G01X1668200Y209833D02*
X1667908Y210083D01*
X1667742Y210417D01*
X1667700Y210792D01*
X1667742Y211125D01*
X1667950Y211458D01*
X1668200Y211667D01*
X1668450Y211708D01*
X1668742Y211625D01*
X1668950Y211333D01*
X1669033Y211042D01*
Y210667D01*
G01Y211042D02*
X1669158Y211292D01*
X1669367Y211500D01*
X1669617Y211583D01*
X1669867Y211500D01*
X1670075Y211292D01*
X1670200Y210917D01*
X1670158Y210542D01*
X1669992Y210167D01*
G01X1676000Y200967D02*
X1678500D01*
Y202008D01*
X1678375Y202342D01*
X1678208Y202550D01*
X1677875Y202633D01*
X1677542Y202550D01*
X1677333Y202300D01*
X1677208Y202008D01*
Y200967D01*
G01Y202008D02*
X1676000Y202633D01*
G01X1678083Y204108D02*
X1678333Y204358D01*
X1678458Y204650D01*
X1678500Y204983D01*
X1678417Y205400D01*
X1678208Y205692D01*
X1677958Y205775D01*
X1677708Y205733D01*
X1677500Y205567D01*
X1677083Y204733D01*
X1676792Y204358D01*
X1676375Y204108D01*
X1676000Y204025D01*
Y205775D01*
G01X1676375Y207083D02*
X1676167Y207333D01*
X1676042Y207625D01*
X1676000Y208000D01*
X1676083Y208375D01*
X1676250Y208667D01*
X1676542Y208875D01*
X1676875Y208917D01*
X1677208Y208833D01*
X1677417Y208625D01*
X1677583Y208333D01*
X1677625Y208042D01*
X1677583Y207750D01*
X1677417Y207375D01*
X1678500Y207500D01*
Y208625D01*
G01Y209850D02*
X1676000Y210433D01*
X1678500Y211100D01*
X1676000Y211767D01*
X1678500Y212350D01*
G01X1677042Y213408D02*
X1677333Y213700D01*
X1677500Y213950D01*
X1677583Y214283D01*
X1677500Y214575D01*
X1677333Y214783D01*
X1677083Y214950D01*
X1676792Y214992D01*
X1676542Y214950D01*
X1676292Y214783D01*
X1676083Y214533D01*
X1676000Y214242D01*
X1676083Y213908D01*
X1676333Y213617D01*
X1676708Y213450D01*
X1677125Y213408D01*
X1677667Y213492D01*
X1677958Y213617D01*
X1678250Y213825D01*
X1678458Y214117D01*
X1678500Y214408D01*
X1678417Y214700D01*
X1678208Y214908D01*
G01X1676500Y216383D02*
X1676208Y216633D01*
X1676042Y216967D01*
X1676000Y217342D01*
X1676042Y217675D01*
X1676250Y218008D01*
X1676500Y218217D01*
X1676750Y218258D01*
X1677042Y218175D01*
X1677250Y217883D01*
X1677333Y217592D01*
Y217217D01*
G01Y217592D02*
X1677458Y217842D01*
X1677667Y218050D01*
X1677917Y218133D01*
X1678167Y218050D01*
X1678375Y217842D01*
X1678500Y217467D01*
X1678458Y217092D01*
X1678292Y216717D01*
G01X1683108Y198881D02*
X1685608D01*
Y199922D01*
X1685483Y200256D01*
X1685316Y200464D01*
X1684983Y200547D01*
X1684650Y200464D01*
X1684441Y200214D01*
X1684316Y199922D01*
Y198881D01*
G01Y199922D02*
X1683108Y200547D01*
G01X1685191Y202022D02*
X1685441Y202272D01*
X1685566Y202564D01*
X1685608Y202897D01*
X1685525Y203314D01*
X1685316Y203606D01*
X1685066Y203689D01*
X1684816Y203647D01*
X1684608Y203481D01*
X1684191Y202647D01*
X1683900Y202272D01*
X1683483Y202022D01*
X1683108Y201939D01*
Y203689D01*
G01X1683483Y204997D02*
X1683275Y205247D01*
X1683150Y205539D01*
X1683108Y205914D01*
X1683191Y206289D01*
X1683358Y206581D01*
X1683650Y206789D01*
X1683983Y206831D01*
X1684316Y206747D01*
X1684525Y206539D01*
X1684691Y206247D01*
X1684733Y205956D01*
X1684691Y205664D01*
X1684525Y205289D01*
X1685608Y205414D01*
Y206539D01*
G01Y207764D02*
X1683108Y208347D01*
X1685608Y209014D01*
X1683108Y209681D01*
X1685608Y210264D01*
G01X1683400Y211406D02*
X1683191Y211697D01*
X1683108Y212031D01*
X1683191Y212364D01*
X1683441Y212656D01*
X1683816Y212864D01*
X1684191Y212947D01*
X1684650D01*
X1685025Y212864D01*
X1685358Y212656D01*
X1685525Y212406D01*
X1685608Y212114D01*
X1685525Y211781D01*
X1685358Y211531D01*
X1685108Y211364D01*
X1684775Y211281D01*
X1684483Y211364D01*
X1684191Y211572D01*
X1684025Y211822D01*
X1683983Y212114D01*
X1684066Y212447D01*
X1684275Y212697D01*
X1684650Y212947D01*
G01X1683108Y215131D02*
X1683650Y215214D01*
X1684108Y215339D01*
X1684525Y215506D01*
X1684983Y215714D01*
X1685608Y216047D01*
Y214381D01*
G01X1679320Y198878D02*
X1681820D01*
Y199919D01*
X1681695Y200253D01*
X1681528Y200461D01*
X1681195Y200544D01*
X1680862Y200461D01*
X1680653Y200211D01*
X1680528Y199919D01*
Y198878D01*
G01Y199919D02*
X1679320Y200544D01*
G01X1681403Y202019D02*
X1681653Y202269D01*
X1681778Y202561D01*
X1681820Y202894D01*
X1681737Y203311D01*
X1681528Y203603D01*
X1681278Y203686D01*
X1681028Y203644D01*
X1680820Y203478D01*
X1680403Y202644D01*
X1680112Y202269D01*
X1679695Y202019D01*
X1679320Y201936D01*
Y203686D01*
G01X1679695Y204994D02*
X1679487Y205244D01*
X1679362Y205536D01*
X1679320Y205911D01*
X1679403Y206286D01*
X1679570Y206578D01*
X1679862Y206786D01*
X1680195Y206828D01*
X1680528Y206744D01*
X1680737Y206536D01*
X1680903Y206244D01*
X1680945Y205953D01*
X1680903Y205661D01*
X1680737Y205286D01*
X1681820Y205411D01*
Y206536D01*
G01Y207761D02*
X1679320Y208344D01*
X1681820Y209011D01*
X1679320Y209678D01*
X1681820Y210261D01*
G01X1679612Y211403D02*
X1679403Y211694D01*
X1679320Y212028D01*
X1679403Y212361D01*
X1679653Y212653D01*
X1680028Y212861D01*
X1680403Y212944D01*
X1680862D01*
X1681237Y212861D01*
X1681570Y212653D01*
X1681737Y212403D01*
X1681820Y212111D01*
X1681737Y211778D01*
X1681570Y211528D01*
X1681320Y211361D01*
X1680987Y211278D01*
X1680695Y211361D01*
X1680403Y211569D01*
X1680237Y211819D01*
X1680195Y212111D01*
X1680278Y212444D01*
X1680487Y212694D01*
X1680862Y212944D01*
G01X1679320Y215211D02*
X1679362Y215503D01*
X1679487Y215836D01*
X1679695Y216044D01*
X1679987Y216128D01*
X1680278Y216044D01*
X1680528Y215794D01*
X1680653Y215419D01*
Y215003D01*
X1680737Y214753D01*
X1680945Y214544D01*
X1681237Y214461D01*
X1681528Y214586D01*
X1681737Y214878D01*
X1681820Y215211D01*
X1681737Y215544D01*
X1681528Y215836D01*
X1681237Y215961D01*
X1680945Y215878D01*
X1680737Y215669D01*
X1680653Y215419D01*
Y215003D01*
X1680528Y214628D01*
X1680278Y214378D01*
X1679987Y214294D01*
X1679695Y214378D01*
X1679487Y214586D01*
X1679362Y214919D01*
X1679320Y215211D01*
G01X1669127Y187914D02*
Y190414D01*
X1668086D01*
X1667752Y190289D01*
X1667544Y190122D01*
X1667461Y189789D01*
X1667544Y189456D01*
X1667794Y189247D01*
X1668086Y189122D01*
X1669127D01*
G01X1668086D02*
X1667461Y187914D01*
G01X1665194D02*
Y190414D01*
X1665694Y189914D01*
G01Y187914D02*
X1664694D01*
G01X1662094Y190414D02*
Y187914D01*
G01X1663052Y190414D02*
X1661136D01*
G01X1659911Y188414D02*
X1659661Y188122D01*
X1659327Y187956D01*
X1658952Y187914D01*
X1658619Y187956D01*
X1658286Y188164D01*
X1658077Y188414D01*
X1658036Y188664D01*
X1658119Y188956D01*
X1658411Y189164D01*
X1658702Y189247D01*
X1659077D01*
G01X1658702D02*
X1658452Y189372D01*
X1658244Y189581D01*
X1658161Y189831D01*
X1658244Y190081D01*
X1658452Y190289D01*
X1658827Y190414D01*
X1659202Y190372D01*
X1659577Y190206D01*
G01X1703919Y203004D02*
Y205504D01*
X1702878D01*
X1702544Y205379D01*
X1702336Y205212D01*
X1702253Y204879D01*
X1702336Y204546D01*
X1702586Y204337D01*
X1702878Y204212D01*
X1703919D01*
G01X1702878D02*
X1702253Y203004D01*
G01X1700778Y205087D02*
X1700528Y205337D01*
X1700236Y205462D01*
X1699903Y205504D01*
X1699486Y205421D01*
X1699194Y205212D01*
X1699111Y204962D01*
X1699153Y204712D01*
X1699319Y204504D01*
X1700153Y204087D01*
X1700528Y203796D01*
X1700778Y203379D01*
X1700861Y203004D01*
X1699111D01*
G01X1697803Y203379D02*
X1697553Y203171D01*
X1697261Y203046D01*
X1696886Y203004D01*
X1696511Y203087D01*
X1696219Y203254D01*
X1696011Y203546D01*
X1695969Y203879D01*
X1696053Y204212D01*
X1696261Y204421D01*
X1696553Y204587D01*
X1696844Y204629D01*
X1697136Y204587D01*
X1697511Y204421D01*
X1697386Y205504D01*
X1696261D01*
G01X1695036D02*
X1694453Y203004D01*
X1693786Y205504D01*
X1693119Y203004D01*
X1692536Y205504D01*
G01X1691394Y203296D02*
X1691103Y203087D01*
X1690769Y203004D01*
X1690436Y203087D01*
X1690144Y203337D01*
X1689936Y203712D01*
X1689853Y204087D01*
Y204546D01*
X1689936Y204921D01*
X1690144Y205254D01*
X1690394Y205421D01*
X1690686Y205504D01*
X1691019Y205421D01*
X1691269Y205254D01*
X1691436Y205004D01*
X1691519Y204671D01*
X1691436Y204379D01*
X1691228Y204087D01*
X1690978Y203921D01*
X1690686Y203879D01*
X1690353Y203962D01*
X1690103Y204171D01*
X1689853Y204546D01*
G01X1688378Y204046D02*
X1688086Y204337D01*
X1687836Y204504D01*
X1687503Y204587D01*
X1687211Y204504D01*
X1687003Y204337D01*
X1686836Y204087D01*
X1686794Y203796D01*
X1686836Y203546D01*
X1687003Y203296D01*
X1687253Y203087D01*
X1687544Y203004D01*
X1687878Y203087D01*
X1688169Y203337D01*
X1688336Y203712D01*
X1688378Y204129D01*
X1688294Y204671D01*
X1688169Y204962D01*
X1687961Y205254D01*
X1687669Y205462D01*
X1687378Y205504D01*
X1687086Y205421D01*
X1686878Y205212D01*
G01X1703939Y199291D02*
Y201791D01*
X1702898D01*
X1702564Y201666D01*
X1702356Y201499D01*
X1702273Y201166D01*
X1702356Y200833D01*
X1702606Y200624D01*
X1702898Y200499D01*
X1703939D01*
G01X1702898D02*
X1702273Y199291D01*
G01X1700798Y201374D02*
X1700548Y201624D01*
X1700256Y201749D01*
X1699923Y201791D01*
X1699506Y201708D01*
X1699214Y201499D01*
X1699131Y201249D01*
X1699173Y200999D01*
X1699339Y200791D01*
X1700173Y200374D01*
X1700548Y200083D01*
X1700798Y199666D01*
X1700881Y199291D01*
X1699131D01*
G01X1697823Y199666D02*
X1697573Y199458D01*
X1697281Y199333D01*
X1696906Y199291D01*
X1696531Y199374D01*
X1696239Y199541D01*
X1696031Y199833D01*
X1695989Y200166D01*
X1696073Y200499D01*
X1696281Y200708D01*
X1696573Y200874D01*
X1696864Y200916D01*
X1697156Y200874D01*
X1697531Y200708D01*
X1697406Y201791D01*
X1696281D01*
G01X1695056D02*
X1694473Y199291D01*
X1693806Y201791D01*
X1693139Y199291D01*
X1692556Y201791D01*
G01X1690706Y199291D02*
X1690414Y199333D01*
X1690081Y199458D01*
X1689873Y199666D01*
X1689789Y199958D01*
X1689873Y200249D01*
X1690123Y200499D01*
X1690498Y200624D01*
X1690914D01*
X1691164Y200708D01*
X1691373Y200916D01*
X1691456Y201208D01*
X1691331Y201499D01*
X1691039Y201708D01*
X1690706Y201791D01*
X1690373Y201708D01*
X1690081Y201499D01*
X1689956Y201208D01*
X1690039Y200916D01*
X1690248Y200708D01*
X1690498Y200624D01*
X1690914D01*
X1691289Y200499D01*
X1691539Y200249D01*
X1691623Y199958D01*
X1691539Y199666D01*
X1691331Y199458D01*
X1690998Y199333D01*
X1690706Y199291D01*
G01X1688398Y201374D02*
X1688148Y201624D01*
X1687856Y201749D01*
X1687523Y201791D01*
X1687106Y201708D01*
X1686814Y201499D01*
X1686731Y201249D01*
X1686773Y200999D01*
X1686939Y200791D01*
X1687773Y200374D01*
X1688148Y200083D01*
X1688398Y199666D01*
X1688481Y199291D01*
X1686731D01*
G01X1669127Y191914D02*
Y194414D01*
X1668086D01*
X1667752Y194289D01*
X1667544Y194122D01*
X1667461Y193789D01*
X1667544Y193456D01*
X1667794Y193247D01*
X1668086Y193122D01*
X1669127D01*
G01X1668086D02*
X1667461Y191914D01*
G01X1665194D02*
Y194414D01*
X1665694Y193914D01*
G01Y191914D02*
X1664694D01*
G01X1662094Y194414D02*
Y191914D01*
G01X1663052Y194414D02*
X1661136D01*
G01X1658994Y191914D02*
X1658702Y191956D01*
X1658369Y192081D01*
X1658161Y192289D01*
X1658077Y192581D01*
X1658161Y192872D01*
X1658411Y193122D01*
X1658786Y193247D01*
X1659202D01*
X1659452Y193331D01*
X1659661Y193539D01*
X1659744Y193831D01*
X1659619Y194122D01*
X1659327Y194331D01*
X1658994Y194414D01*
X1658661Y194331D01*
X1658369Y194122D01*
X1658244Y193831D01*
X1658327Y193539D01*
X1658536Y193331D01*
X1658786Y193247D01*
X1659202D01*
X1659577Y193122D01*
X1659827Y192872D01*
X1659911Y192581D01*
X1659827Y192289D01*
X1659619Y192081D01*
X1659286Y191956D01*
X1658994Y191914D01*
G01X1659000Y197167D02*
X1661500D01*
Y198208D01*
X1661375Y198542D01*
X1661208Y198750D01*
X1660875Y198833D01*
X1660542Y198750D01*
X1660333Y198500D01*
X1660208Y198208D01*
Y197167D01*
G01Y198208D02*
X1659000Y198833D01*
G01X1659292Y200392D02*
X1659083Y200683D01*
X1659000Y201017D01*
X1659083Y201350D01*
X1659333Y201642D01*
X1659708Y201850D01*
X1660083Y201933D01*
X1660542D01*
X1660917Y201850D01*
X1661250Y201642D01*
X1661417Y201392D01*
X1661500Y201100D01*
X1661417Y200767D01*
X1661250Y200517D01*
X1661000Y200350D01*
X1660667Y200267D01*
X1660375Y200350D01*
X1660083Y200558D01*
X1659917Y200808D01*
X1659875Y201100D01*
X1659958Y201433D01*
X1660167Y201683D01*
X1660542Y201933D01*
G01X1659000Y203408D02*
X1661500D01*
Y204992D01*
G01X1660292Y204408D02*
Y203408D01*
G01X1661083Y206508D02*
X1661333Y206758D01*
X1661458Y207050D01*
X1661500Y207383D01*
X1661417Y207800D01*
X1661208Y208092D01*
X1660958Y208175D01*
X1660708Y208133D01*
X1660500Y207967D01*
X1660083Y207133D01*
X1659792Y206758D01*
X1659375Y206508D01*
X1659000Y206425D01*
Y208175D01*
G01X1661083Y209608D02*
X1661333Y209858D01*
X1661458Y210150D01*
X1661500Y210483D01*
X1661417Y210900D01*
X1661208Y211192D01*
X1660958Y211275D01*
X1660708Y211233D01*
X1660500Y211067D01*
X1660083Y210233D01*
X1659792Y209858D01*
X1659375Y209608D01*
X1659000Y209525D01*
Y211275D01*
G01X1707733Y176500D02*
Y179000D01*
X1706692D01*
X1706358Y178875D01*
X1706150Y178708D01*
X1706067Y178375D01*
X1706150Y178042D01*
X1706400Y177833D01*
X1706692Y177708D01*
X1707733D01*
G01X1706692D02*
X1706067Y176500D01*
G01X1704592Y178583D02*
X1704342Y178833D01*
X1704050Y178958D01*
X1703717Y179000D01*
X1703300Y178917D01*
X1703008Y178708D01*
X1702925Y178458D01*
X1702967Y178208D01*
X1703133Y178000D01*
X1703967Y177583D01*
X1704342Y177292D01*
X1704592Y176875D01*
X1704675Y176500D01*
X1702925D01*
G01X1701617Y176875D02*
X1701367Y176667D01*
X1701075Y176542D01*
X1700700Y176500D01*
X1700325Y176583D01*
X1700033Y176750D01*
X1699825Y177042D01*
X1699783Y177375D01*
X1699867Y177708D01*
X1700075Y177917D01*
X1700367Y178083D01*
X1700658Y178125D01*
X1700950Y178083D01*
X1701325Y177917D01*
X1701200Y179000D01*
X1700075D01*
G01X1698850D02*
X1698267Y176500D01*
X1697600Y179000D01*
X1696933Y176500D01*
X1696350Y179000D01*
G01X1694500Y176500D02*
Y179000D01*
X1695000Y178500D01*
G01Y176500D02*
X1694000D01*
G01X1692317Y176875D02*
X1692067Y176667D01*
X1691775Y176542D01*
X1691400Y176500D01*
X1691025Y176583D01*
X1690733Y176750D01*
X1690525Y177042D01*
X1690483Y177375D01*
X1690567Y177708D01*
X1690775Y177917D01*
X1691067Y178083D01*
X1691358Y178125D01*
X1691650Y178083D01*
X1692025Y177917D01*
X1691900Y179000D01*
X1690775D01*
G01X1689217Y176875D02*
X1688967Y176667D01*
X1688675Y176542D01*
X1688300Y176500D01*
X1687925Y176583D01*
X1687633Y176750D01*
X1687425Y177042D01*
X1687383Y177375D01*
X1687467Y177708D01*
X1687675Y177917D01*
X1687967Y178083D01*
X1688258Y178125D01*
X1688550Y178083D01*
X1688925Y177917D01*
X1688800Y179000D01*
X1687675D01*
G01X1680245Y172564D02*
X1682745D01*
Y173605D01*
X1682620Y173939D01*
X1682453Y174147D01*
X1682120Y174230D01*
X1681787Y174147D01*
X1681578Y173897D01*
X1681453Y173605D01*
Y172564D01*
G01Y173605D02*
X1680245Y174230D01*
G01X1682328Y175705D02*
X1682578Y175955D01*
X1682703Y176247D01*
X1682745Y176580D01*
X1682662Y176997D01*
X1682453Y177289D01*
X1682203Y177372D01*
X1681953Y177330D01*
X1681745Y177164D01*
X1681328Y176330D01*
X1681037Y175955D01*
X1680620Y175705D01*
X1680245Y175622D01*
Y177372D01*
G01X1680620Y178680D02*
X1680412Y178930D01*
X1680287Y179222D01*
X1680245Y179597D01*
X1680328Y179972D01*
X1680495Y180264D01*
X1680787Y180472D01*
X1681120Y180514D01*
X1681453Y180430D01*
X1681662Y180222D01*
X1681828Y179930D01*
X1681870Y179639D01*
X1681828Y179347D01*
X1681662Y178972D01*
X1682745Y179097D01*
Y180222D01*
G01Y181447D02*
X1680245Y182030D01*
X1682745Y182697D01*
X1680245Y183364D01*
X1682745Y183947D01*
G01X1680245Y185797D02*
X1682745D01*
X1682245Y185297D01*
G01X1680245D02*
Y186297D01*
G01Y188897D02*
X1680287Y189189D01*
X1680412Y189522D01*
X1680620Y189730D01*
X1680912Y189814D01*
X1681203Y189730D01*
X1681453Y189480D01*
X1681578Y189105D01*
Y188689D01*
X1681662Y188439D01*
X1681870Y188230D01*
X1682162Y188147D01*
X1682453Y188272D01*
X1682662Y188564D01*
X1682745Y188897D01*
X1682662Y189230D01*
X1682453Y189522D01*
X1682162Y189647D01*
X1681870Y189564D01*
X1681662Y189355D01*
X1681578Y189105D01*
Y188689D01*
X1681453Y188314D01*
X1681203Y188064D01*
X1680912Y187980D01*
X1680620Y188064D01*
X1680412Y188272D01*
X1680287Y188605D01*
X1680245Y188897D01*
G01Y192497D02*
X1682745D01*
X1680953Y190955D01*
Y193039D01*
G01X1703583Y168692D02*
X1703833Y168817D01*
X1704125Y168900D01*
X1704458D01*
X1704833Y168775D01*
X1705125Y168567D01*
X1705333Y168317D01*
X1705500Y167900D01*
X1705542Y167525D01*
X1705458Y167150D01*
X1705333Y166900D01*
X1705083Y166650D01*
X1704792Y166483D01*
X1704500Y166400D01*
X1704208D01*
X1703917Y166483D01*
X1703667Y166608D01*
X1703458Y166775D01*
G01X1702192Y168483D02*
X1701942Y168733D01*
X1701650Y168858D01*
X1701317Y168900D01*
X1700900Y168817D01*
X1700608Y168608D01*
X1700525Y168358D01*
X1700567Y168108D01*
X1700733Y167900D01*
X1701567Y167483D01*
X1701942Y167192D01*
X1702192Y166775D01*
X1702275Y166400D01*
X1700525D01*
G01X1699217Y166775D02*
X1698967Y166567D01*
X1698675Y166442D01*
X1698300Y166400D01*
X1697925Y166483D01*
X1697633Y166650D01*
X1697425Y166942D01*
X1697383Y167275D01*
X1697467Y167608D01*
X1697675Y167817D01*
X1697967Y167983D01*
X1698258Y168025D01*
X1698550Y167983D01*
X1698925Y167817D01*
X1698800Y168900D01*
X1697675D01*
G01X1696450D02*
X1695867Y166400D01*
X1695200Y168900D01*
X1694533Y166400D01*
X1693950Y168900D01*
G01X1693017Y166775D02*
X1692767Y166567D01*
X1692475Y166442D01*
X1692100Y166400D01*
X1691725Y166483D01*
X1691433Y166650D01*
X1691225Y166942D01*
X1691183Y167275D01*
X1691267Y167608D01*
X1691475Y167817D01*
X1691767Y167983D01*
X1692058Y168025D01*
X1692350Y167983D01*
X1692725Y167817D01*
X1692600Y168900D01*
X1691475D01*
G01X1703383Y172292D02*
X1703633Y172417D01*
X1703925Y172500D01*
X1704258D01*
X1704633Y172375D01*
X1704925Y172167D01*
X1705133Y171917D01*
X1705300Y171500D01*
X1705342Y171125D01*
X1705258Y170750D01*
X1705133Y170500D01*
X1704883Y170250D01*
X1704592Y170083D01*
X1704300Y170000D01*
X1704008D01*
X1703717Y170083D01*
X1703467Y170208D01*
X1703258Y170375D01*
G01X1701200Y170000D02*
Y172500D01*
X1701700Y172000D01*
G01Y170000D02*
X1700700D01*
G01X1698100Y172500D02*
Y170000D01*
G01X1699058Y172500D02*
X1697142D01*
G01X1695792Y172083D02*
X1695542Y172333D01*
X1695250Y172458D01*
X1694917Y172500D01*
X1694500Y172417D01*
X1694208Y172208D01*
X1694125Y171958D01*
X1694167Y171708D01*
X1694333Y171500D01*
X1695167Y171083D01*
X1695542Y170792D01*
X1695792Y170375D01*
X1695875Y170000D01*
X1694125D01*
G01X1691900D02*
Y172500D01*
X1692400Y172000D01*
G01Y170000D02*
X1691400D01*
G01X1690892Y159400D02*
Y161900D01*
X1689308D01*
G01X1689892Y160692D02*
X1690892D01*
G01X1686667Y160733D02*
X1686500Y160858D01*
X1686375Y161067D01*
X1686292Y161358D01*
X1686375Y161608D01*
X1686542Y161775D01*
X1686833Y161900D01*
X1687958D01*
Y159400D01*
X1686583D01*
X1686292Y159567D01*
X1686125Y159817D01*
X1686042Y160108D01*
X1686125Y160400D01*
X1686375Y160650D01*
X1686667Y160733D01*
X1687958D01*
G01X1684692Y161483D02*
X1684442Y161733D01*
X1684150Y161858D01*
X1683817Y161900D01*
X1683400Y161817D01*
X1683108Y161608D01*
X1683025Y161358D01*
X1683067Y161108D01*
X1683233Y160900D01*
X1684067Y160483D01*
X1684442Y160192D01*
X1684692Y159775D01*
X1684775Y159400D01*
X1683025D01*
G01X1680800Y161900D02*
Y159400D01*
G01X1681758Y161900D02*
X1679842D01*
G01X1678617Y159775D02*
X1678367Y159567D01*
X1678075Y159442D01*
X1677700Y159400D01*
X1677325Y159483D01*
X1677033Y159650D01*
X1676825Y159942D01*
X1676783Y160275D01*
X1676867Y160608D01*
X1677075Y160817D01*
X1677367Y160983D01*
X1677658Y161025D01*
X1677950Y160983D01*
X1678325Y160817D01*
X1678200Y161900D01*
X1677075D01*
G01X1723353Y240330D02*
Y242830D01*
X1722312D01*
X1721978Y242705D01*
X1721770Y242538D01*
X1721687Y242205D01*
X1721770Y241872D01*
X1722020Y241663D01*
X1722312Y241538D01*
X1723353D01*
G01X1722312D02*
X1721687Y240330D01*
G01X1719420D02*
Y242830D01*
X1719920Y242330D01*
G01Y240330D02*
X1718920D01*
G01X1717570Y242830D02*
X1716987Y240330D01*
X1716320Y242830D01*
X1715653Y240330D01*
X1715070Y242830D01*
G01X1712720Y240330D02*
Y242830D01*
X1714262Y241038D01*
X1712178D01*
G01X1710120Y242830D02*
X1710453Y242747D01*
X1710703Y242538D01*
X1710870Y242288D01*
X1710995Y241955D01*
X1711037Y241580D01*
X1710995Y241205D01*
X1710870Y240872D01*
X1710703Y240622D01*
X1710453Y240413D01*
X1710120Y240330D01*
X1709787Y240413D01*
X1709537Y240622D01*
X1709370Y240872D01*
X1709245Y241205D01*
X1709203Y241580D01*
X1709245Y241955D01*
X1709370Y242288D01*
X1709537Y242538D01*
X1709787Y242747D01*
X1710120Y242830D01*
G01X1721283Y257359D02*
X1721533Y257484D01*
X1721825Y257567D01*
X1722158D01*
X1722533Y257442D01*
X1722825Y257234D01*
X1723033Y256984D01*
X1723200Y256567D01*
X1723242Y256192D01*
X1723158Y255817D01*
X1723033Y255567D01*
X1722783Y255317D01*
X1722492Y255150D01*
X1722200Y255067D01*
X1721908D01*
X1721617Y255150D01*
X1721367Y255275D01*
X1721158Y255442D01*
G01X1719892Y257150D02*
X1719642Y257400D01*
X1719350Y257525D01*
X1719017Y257567D01*
X1718600Y257484D01*
X1718308Y257275D01*
X1718225Y257025D01*
X1718267Y256775D01*
X1718433Y256567D01*
X1719267Y256150D01*
X1719642Y255859D01*
X1719892Y255442D01*
X1719975Y255067D01*
X1718225D01*
G01X1716833D02*
Y257567D01*
X1715833D01*
X1715500Y257442D01*
X1715250Y257150D01*
X1715167Y256817D01*
X1715250Y256484D01*
X1715458Y256234D01*
X1715833Y256109D01*
X1716833D01*
G01X1712900Y255067D02*
Y257567D01*
X1713400Y257067D01*
G01Y255067D02*
X1712400D01*
G01X1709800Y257567D02*
X1710133Y257484D01*
X1710383Y257275D01*
X1710550Y257025D01*
X1710675Y256692D01*
X1710717Y256317D01*
X1710675Y255942D01*
X1710550Y255609D01*
X1710383Y255359D01*
X1710133Y255150D01*
X1709800Y255067D01*
X1709467Y255150D01*
X1709217Y255359D01*
X1709050Y255609D01*
X1708925Y255942D01*
X1708883Y256317D01*
X1708925Y256692D01*
X1709050Y257025D01*
X1709217Y257275D01*
X1709467Y257484D01*
X1709800Y257567D01*
G01X1669750Y276767D02*
X1670083Y276809D01*
X1670375Y276975D01*
X1670625Y277225D01*
X1670792Y277517D01*
X1670875Y277850D01*
Y278184D01*
X1670792Y278517D01*
X1670625Y278809D01*
X1670375Y279059D01*
X1670083Y279225D01*
X1669750Y279267D01*
X1669417Y279225D01*
X1669125Y279059D01*
X1668875Y278809D01*
X1668708Y278517D01*
X1668625Y278184D01*
Y277850D01*
X1668708Y277517D01*
X1668875Y277225D01*
X1669125Y276975D01*
X1669417Y276809D01*
X1669750Y276767D01*
G01X1669417Y277434D02*
X1668917Y276767D01*
G01X1666650D02*
X1666358Y276809D01*
X1666025Y276934D01*
X1665817Y277142D01*
X1665733Y277434D01*
X1665817Y277725D01*
X1666067Y277975D01*
X1666442Y278100D01*
X1666858D01*
X1667108Y278184D01*
X1667317Y278392D01*
X1667400Y278684D01*
X1667275Y278975D01*
X1666983Y279184D01*
X1666650Y279267D01*
X1666317Y279184D01*
X1666025Y278975D01*
X1665900Y278684D01*
X1665983Y278392D01*
X1666192Y278184D01*
X1666442Y278100D01*
X1666858D01*
X1667233Y277975D01*
X1667483Y277725D01*
X1667567Y277434D01*
X1667483Y277142D01*
X1667275Y276934D01*
X1666942Y276809D01*
X1666650Y276767D01*
G01X1664342D02*
Y279267D01*
X1662758D01*
G01X1663342Y278059D02*
X1664342D01*
G01X1661242Y278850D02*
X1660992Y279100D01*
X1660700Y279225D01*
X1660367Y279267D01*
X1659950Y279184D01*
X1659658Y278975D01*
X1659575Y278725D01*
X1659617Y278475D01*
X1659783Y278267D01*
X1660617Y277850D01*
X1660992Y277559D01*
X1661242Y277142D01*
X1661325Y276767D01*
X1659575D01*
G01X1650750Y280750D02*
Y278250D01*
G01X1666333Y341200D02*
Y343700D01*
X1665292D01*
X1664958Y343575D01*
X1664750Y343408D01*
X1664667Y343075D01*
X1664750Y342742D01*
X1665000Y342533D01*
X1665292Y342408D01*
X1666333D01*
G01X1665292D02*
X1664667Y341200D01*
G01X1663192Y343283D02*
X1662942Y343533D01*
X1662650Y343658D01*
X1662317Y343700D01*
X1661900Y343617D01*
X1661608Y343408D01*
X1661525Y343158D01*
X1661567Y342908D01*
X1661733Y342700D01*
X1662567Y342283D01*
X1662942Y341992D01*
X1663192Y341575D01*
X1663275Y341200D01*
X1661525D01*
G01X1660133D02*
Y343700D01*
X1659133D01*
X1658800Y343575D01*
X1658550Y343283D01*
X1658467Y342950D01*
X1658550Y342617D01*
X1658758Y342367D01*
X1659133Y342242D01*
X1660133D01*
G01X1656200Y341200D02*
Y343700D01*
X1656700Y343200D01*
G01Y341200D02*
X1655700D01*
G01X1653100D02*
Y343700D01*
X1653600Y343200D01*
G01Y341200D02*
X1652600D01*
G01X1666700Y317667D02*
X1669200D01*
Y318708D01*
X1669075Y319042D01*
X1668908Y319250D01*
X1668575Y319333D01*
X1668242Y319250D01*
X1668033Y319000D01*
X1667908Y318708D01*
Y317667D01*
G01Y318708D02*
X1666700Y319333D01*
G01X1668783Y320808D02*
X1669033Y321058D01*
X1669158Y321350D01*
X1669200Y321683D01*
X1669117Y322100D01*
X1668908Y322392D01*
X1668658Y322475D01*
X1668408Y322433D01*
X1668200Y322267D01*
X1667783Y321433D01*
X1667492Y321058D01*
X1667075Y320808D01*
X1666700Y320725D01*
Y322475D01*
G01Y323867D02*
X1669200D01*
Y324867D01*
X1669075Y325200D01*
X1668783Y325450D01*
X1668450Y325533D01*
X1668117Y325450D01*
X1667867Y325242D01*
X1667742Y324867D01*
Y323867D01*
G01X1666700Y327800D02*
X1669200D01*
X1668700Y327300D01*
G01X1666700D02*
Y328300D01*
G01X1667200Y329983D02*
X1666908Y330233D01*
X1666742Y330567D01*
X1666700Y330942D01*
X1666742Y331275D01*
X1666950Y331608D01*
X1667200Y331817D01*
X1667450Y331858D01*
X1667742Y331775D01*
X1667950Y331483D01*
X1668033Y331192D01*
Y330817D01*
G01Y331192D02*
X1668158Y331442D01*
X1668367Y331650D01*
X1668617Y331733D01*
X1668867Y331650D01*
X1669075Y331442D01*
X1669200Y331067D01*
X1669158Y330692D01*
X1668992Y330317D01*
G01X1666648Y303228D02*
X1669148D01*
Y304269D01*
X1669023Y304603D01*
X1668856Y304811D01*
X1668523Y304894D01*
X1668190Y304811D01*
X1667981Y304561D01*
X1667856Y304269D01*
Y303228D01*
G01Y304269D02*
X1666648Y304894D01*
G01Y307161D02*
X1669148D01*
X1668648Y306661D01*
G01X1666648D02*
Y307661D01*
G01Y309428D02*
X1669148D01*
Y310469D01*
X1669023Y310803D01*
X1668856Y311011D01*
X1668523Y311094D01*
X1668190Y311011D01*
X1667981Y310761D01*
X1667856Y310469D01*
Y309428D01*
G01Y310469D02*
X1666648Y311094D01*
G01Y313361D02*
X1666690Y313653D01*
X1666815Y313986D01*
X1667023Y314194D01*
X1667315Y314278D01*
X1667606Y314194D01*
X1667856Y313944D01*
X1667981Y313569D01*
Y313153D01*
X1668065Y312903D01*
X1668273Y312694D01*
X1668565Y312611D01*
X1668856Y312736D01*
X1669065Y313028D01*
X1669148Y313361D01*
X1669065Y313694D01*
X1668856Y313986D01*
X1668565Y314111D01*
X1668273Y314028D01*
X1668065Y313819D01*
X1667981Y313569D01*
Y313153D01*
X1667856Y312778D01*
X1667606Y312528D01*
X1667315Y312444D01*
X1667023Y312528D01*
X1666815Y312736D01*
X1666690Y313069D01*
X1666648Y313361D01*
G01X1675893Y300794D02*
Y299002D01*
X1675726Y298627D01*
X1675393Y298377D01*
X1674976Y298294D01*
X1674559Y298377D01*
X1674226Y298627D01*
X1674059Y299002D01*
Y300794D01*
G01X1671876Y298294D02*
Y300794D01*
X1672376Y300294D01*
G01Y298294D02*
X1671376D01*
G01X1669609D02*
Y300794D01*
X1668568D01*
X1668234Y300669D01*
X1668026Y300502D01*
X1667943Y300169D01*
X1668026Y299836D01*
X1668276Y299627D01*
X1668568Y299502D01*
X1669609D01*
G01X1668568D02*
X1667943Y298294D01*
G01X1665676D02*
Y300794D01*
X1666176Y300294D01*
G01Y298294D02*
X1665176D01*
G01X1672339Y283658D02*
X1672464Y283408D01*
X1672547Y283116D01*
Y282783D01*
X1672422Y282408D01*
X1672214Y282116D01*
X1671964Y281908D01*
X1671547Y281741D01*
X1671172Y281699D01*
X1670797Y281783D01*
X1670547Y281908D01*
X1670297Y282158D01*
X1670130Y282449D01*
X1670047Y282741D01*
Y283033D01*
X1670130Y283324D01*
X1670255Y283574D01*
X1670422Y283783D01*
G01X1670047Y285841D02*
X1672547D01*
X1672047Y285341D01*
G01X1670047D02*
Y286341D01*
G01Y288108D02*
X1672547D01*
Y289149D01*
X1672422Y289483D01*
X1672255Y289691D01*
X1671922Y289774D01*
X1671589Y289691D01*
X1671380Y289441D01*
X1671255Y289149D01*
Y288108D01*
G01Y289149D02*
X1670047Y289774D01*
G01X1672130Y291249D02*
X1672380Y291499D01*
X1672505Y291791D01*
X1672547Y292124D01*
X1672464Y292541D01*
X1672255Y292833D01*
X1672005Y292916D01*
X1671755Y292874D01*
X1671547Y292708D01*
X1671130Y291874D01*
X1670839Y291499D01*
X1670422Y291249D01*
X1670047Y291166D01*
Y292916D01*
G01Y295058D02*
X1670589Y295141D01*
X1671047Y295266D01*
X1671464Y295433D01*
X1671922Y295641D01*
X1672547Y295974D01*
Y294308D01*
G01X1668672Y283608D02*
X1668797Y283358D01*
X1668880Y283066D01*
Y282733D01*
X1668755Y282358D01*
X1668547Y282066D01*
X1668297Y281858D01*
X1667880Y281691D01*
X1667505Y281649D01*
X1667130Y281733D01*
X1666880Y281858D01*
X1666630Y282108D01*
X1666463Y282399D01*
X1666380Y282691D01*
Y282983D01*
X1666463Y283274D01*
X1666588Y283524D01*
X1666755Y283733D01*
G01X1666380Y285791D02*
X1668880D01*
X1668380Y285291D01*
G01X1666380D02*
Y286291D01*
G01Y288058D02*
X1668880D01*
Y289099D01*
X1668755Y289433D01*
X1668588Y289641D01*
X1668255Y289724D01*
X1667922Y289641D01*
X1667713Y289391D01*
X1667588Y289099D01*
Y288058D01*
G01Y289099D02*
X1666380Y289724D01*
G01X1668463Y291199D02*
X1668713Y291449D01*
X1668838Y291741D01*
X1668880Y292074D01*
X1668797Y292491D01*
X1668588Y292783D01*
X1668338Y292866D01*
X1668088Y292824D01*
X1667880Y292658D01*
X1667463Y291824D01*
X1667172Y291449D01*
X1666755Y291199D01*
X1666380Y291116D01*
Y292866D01*
G01Y295091D02*
X1666422Y295383D01*
X1666547Y295716D01*
X1666755Y295924D01*
X1667047Y296008D01*
X1667338Y295924D01*
X1667588Y295674D01*
X1667713Y295299D01*
Y294883D01*
X1667797Y294633D01*
X1668005Y294424D01*
X1668297Y294341D01*
X1668588Y294466D01*
X1668797Y294758D01*
X1668880Y295091D01*
X1668797Y295424D01*
X1668588Y295716D01*
X1668297Y295841D01*
X1668005Y295758D01*
X1667797Y295549D01*
X1667713Y295299D01*
Y294883D01*
X1667588Y294508D01*
X1667338Y294258D01*
X1667047Y294174D01*
X1666755Y294258D01*
X1666547Y294466D01*
X1666422Y294799D01*
X1666380Y295091D01*
G01X1653250Y312250D02*
Y309750D01*
G01X1659600Y398500D02*
X1655800D01*
G01X1676200Y438350D02*
Y398500D01*
X1662900D01*
G01X1676200Y445400D02*
Y440750D01*
G01X1660118Y431114D02*
X1662618D01*
Y432155D01*
X1662493Y432489D01*
X1662326Y432697D01*
X1661993Y432780D01*
X1661660Y432697D01*
X1661451Y432447D01*
X1661326Y432155D01*
Y431114D01*
G01Y432155D02*
X1660118Y432780D01*
G01X1660618Y434130D02*
X1660326Y434380D01*
X1660160Y434714D01*
X1660118Y435089D01*
X1660160Y435422D01*
X1660368Y435755D01*
X1660618Y435964D01*
X1660868Y436005D01*
X1661160Y435922D01*
X1661368Y435630D01*
X1661451Y435339D01*
Y434964D01*
G01Y435339D02*
X1661576Y435589D01*
X1661785Y435797D01*
X1662035Y435880D01*
X1662285Y435797D01*
X1662493Y435589D01*
X1662618Y435214D01*
X1662576Y434839D01*
X1662410Y434464D01*
G01X1660118Y437189D02*
X1662618D01*
X1660118Y439105D01*
X1662618D01*
G01X1660118Y441247D02*
X1662618D01*
X1662118Y440747D01*
G01X1660118D02*
Y441747D01*
G01X1662201Y443555D02*
X1662451Y443805D01*
X1662576Y444097D01*
X1662618Y444430D01*
X1662535Y444847D01*
X1662326Y445139D01*
X1662076Y445222D01*
X1661826Y445180D01*
X1661618Y445014D01*
X1661201Y444180D01*
X1660910Y443805D01*
X1660493Y443555D01*
X1660118Y443472D01*
Y445222D01*
G01X1656467Y431367D02*
X1658967D01*
Y432408D01*
X1658842Y432742D01*
X1658675Y432950D01*
X1658342Y433033D01*
X1658009Y432950D01*
X1657800Y432700D01*
X1657675Y432408D01*
Y431367D01*
G01Y432408D02*
X1656467Y433033D01*
G01X1656967Y434383D02*
X1656675Y434633D01*
X1656509Y434967D01*
X1656467Y435342D01*
X1656509Y435675D01*
X1656717Y436008D01*
X1656967Y436217D01*
X1657217Y436258D01*
X1657509Y436175D01*
X1657717Y435883D01*
X1657800Y435592D01*
Y435217D01*
G01Y435592D02*
X1657925Y435842D01*
X1658134Y436050D01*
X1658384Y436133D01*
X1658634Y436050D01*
X1658842Y435842D01*
X1658967Y435467D01*
X1658925Y435092D01*
X1658759Y434717D01*
G01X1656467Y437442D02*
X1658967D01*
X1656467Y439358D01*
X1658967D01*
G01X1656467Y441500D02*
X1658967D01*
X1658467Y441000D01*
G01X1656467D02*
Y442000D01*
G01X1658967Y444600D02*
X1658884Y444267D01*
X1658675Y444017D01*
X1658425Y443850D01*
X1658092Y443725D01*
X1657717Y443683D01*
X1657342Y443725D01*
X1657009Y443850D01*
X1656759Y444017D01*
X1656550Y444267D01*
X1656467Y444600D01*
X1656550Y444933D01*
X1656759Y445183D01*
X1657009Y445350D01*
X1657342Y445475D01*
X1657717Y445517D01*
X1658092Y445475D01*
X1658425Y445350D01*
X1658675Y445183D01*
X1658884Y444933D01*
X1658967Y444600D01*
G01X1658988Y408766D02*
X1661488D01*
Y409807D01*
X1661363Y410141D01*
X1661196Y410349D01*
X1660863Y410432D01*
X1660530Y410349D01*
X1660321Y410099D01*
X1660196Y409807D01*
Y408766D01*
G01Y409807D02*
X1658988Y410432D01*
G01Y412616D02*
X1659530Y412699D01*
X1659988Y412824D01*
X1660405Y412991D01*
X1660863Y413199D01*
X1661488Y413532D01*
Y411866D01*
G01X1658988Y414882D02*
X1661488D01*
Y415716D01*
X1661363Y416049D01*
X1661196Y416299D01*
X1660946Y416507D01*
X1660655Y416674D01*
X1660238Y416716D01*
X1659821Y416674D01*
X1659530Y416507D01*
X1659280Y416299D01*
X1659113Y416049D01*
X1658988Y415716D01*
Y414882D01*
G01Y419399D02*
X1661488D01*
X1659696Y417857D01*
Y419941D01*
G01X1658988Y422499D02*
X1661488D01*
X1659696Y420957D01*
Y423041D01*
G01X1662800Y408417D02*
X1665300D01*
Y409458D01*
X1665175Y409792D01*
X1665008Y410000D01*
X1664675Y410083D01*
X1664342Y410000D01*
X1664133Y409750D01*
X1664008Y409458D01*
Y408417D01*
G01Y409458D02*
X1662800Y410083D01*
G01X1663300Y411433D02*
X1663008Y411683D01*
X1662842Y412017D01*
X1662800Y412392D01*
X1662842Y412725D01*
X1663050Y413058D01*
X1663300Y413267D01*
X1663550Y413308D01*
X1663842Y413225D01*
X1664050Y412933D01*
X1664133Y412642D01*
Y412267D01*
G01Y412642D02*
X1664258Y412892D01*
X1664467Y413100D01*
X1664717Y413183D01*
X1664967Y413100D01*
X1665175Y412892D01*
X1665300Y412517D01*
X1665258Y412142D01*
X1665092Y411767D01*
G01X1662800Y414617D02*
X1665300D01*
Y415617D01*
X1665175Y415950D01*
X1664883Y416200D01*
X1664550Y416283D01*
X1664217Y416200D01*
X1663967Y415992D01*
X1663842Y415617D01*
Y414617D01*
G01Y417758D02*
X1664133Y418050D01*
X1664300Y418300D01*
X1664383Y418633D01*
X1664300Y418925D01*
X1664133Y419133D01*
X1663883Y419300D01*
X1663592Y419342D01*
X1663342Y419300D01*
X1663092Y419133D01*
X1662883Y418883D01*
X1662800Y418592D01*
X1662883Y418258D01*
X1663133Y417967D01*
X1663508Y417800D01*
X1663925Y417758D01*
X1664467Y417842D01*
X1664758Y417967D01*
X1665050Y418175D01*
X1665258Y418467D01*
X1665300Y418758D01*
X1665217Y419050D01*
X1665008Y419258D01*
G01X1668012Y431996D02*
X1670512D01*
Y433037D01*
X1670387Y433371D01*
X1670220Y433579D01*
X1669887Y433662D01*
X1669554Y433579D01*
X1669345Y433329D01*
X1669220Y433037D01*
Y431996D01*
G01Y433037D02*
X1668012Y433662D01*
G01X1668512Y435012D02*
X1668220Y435262D01*
X1668054Y435596D01*
X1668012Y435971D01*
X1668054Y436304D01*
X1668262Y436637D01*
X1668512Y436846D01*
X1668762Y436887D01*
X1669054Y436804D01*
X1669262Y436512D01*
X1669345Y436221D01*
Y435846D01*
G01Y436221D02*
X1669470Y436471D01*
X1669679Y436679D01*
X1669929Y436762D01*
X1670179Y436679D01*
X1670387Y436471D01*
X1670512Y436096D01*
X1670470Y435721D01*
X1670304Y435346D01*
G01X1668012Y438071D02*
X1670512D01*
X1668012Y439987D01*
X1670512D01*
G01X1668012Y442129D02*
X1670512D01*
X1670012Y441629D01*
G01X1668012D02*
Y442629D01*
G01Y445229D02*
X1670512D01*
X1670012Y444729D01*
G01X1668012D02*
Y445729D01*
G01X1671709Y432013D02*
X1674209D01*
Y433054D01*
X1674084Y433388D01*
X1673917Y433596D01*
X1673584Y433679D01*
X1673251Y433596D01*
X1673042Y433346D01*
X1672917Y433054D01*
Y432013D01*
G01Y433054D02*
X1671709Y433679D01*
G01Y435946D02*
X1671751Y436238D01*
X1671876Y436571D01*
X1672084Y436779D01*
X1672376Y436863D01*
X1672667Y436779D01*
X1672917Y436529D01*
X1673042Y436154D01*
Y435738D01*
X1673126Y435488D01*
X1673334Y435279D01*
X1673626Y435196D01*
X1673917Y435321D01*
X1674126Y435613D01*
X1674209Y435946D01*
X1674126Y436279D01*
X1673917Y436571D01*
X1673626Y436696D01*
X1673334Y436613D01*
X1673126Y436404D01*
X1673042Y436154D01*
Y435738D01*
X1672917Y435363D01*
X1672667Y435113D01*
X1672376Y435029D01*
X1672084Y435113D01*
X1671876Y435321D01*
X1671751Y435654D01*
X1671709Y435946D01*
G01Y438129D02*
X1674209D01*
Y438963D01*
X1674084Y439296D01*
X1673917Y439546D01*
X1673667Y439754D01*
X1673376Y439921D01*
X1672959Y439963D01*
X1672542Y439921D01*
X1672251Y439754D01*
X1672001Y439546D01*
X1671834Y439296D01*
X1671709Y438963D01*
Y438129D01*
G01Y442146D02*
X1674209D01*
X1673709Y441646D01*
G01X1671709D02*
Y442646D01*
G01Y445246D02*
X1674209D01*
X1673709Y444746D01*
G01X1671709D02*
Y445746D01*
G01X1674142Y425669D02*
Y428169D01*
X1673101D01*
X1672767Y428044D01*
X1672559Y427877D01*
X1672476Y427544D01*
X1672559Y427211D01*
X1672809Y427002D01*
X1673101Y426877D01*
X1674142D01*
G01X1673101D02*
X1672476Y425669D01*
G01X1670209D02*
X1669917Y425711D01*
X1669584Y425836D01*
X1669376Y426044D01*
X1669292Y426336D01*
X1669376Y426627D01*
X1669626Y426877D01*
X1670001Y427002D01*
X1670417D01*
X1670667Y427086D01*
X1670876Y427294D01*
X1670959Y427586D01*
X1670834Y427877D01*
X1670542Y428086D01*
X1670209Y428169D01*
X1669876Y428086D01*
X1669584Y427877D01*
X1669459Y427586D01*
X1669542Y427294D01*
X1669751Y427086D01*
X1670001Y427002D01*
X1670417D01*
X1670792Y426877D01*
X1671042Y426627D01*
X1671126Y426336D01*
X1671042Y426044D01*
X1670834Y425836D01*
X1670501Y425711D01*
X1670209Y425669D01*
G01X1668026D02*
Y428169D01*
X1667192D01*
X1666859Y428044D01*
X1666609Y427877D01*
X1666401Y427627D01*
X1666234Y427336D01*
X1666192Y426919D01*
X1666234Y426502D01*
X1666401Y426211D01*
X1666609Y425961D01*
X1666859Y425794D01*
X1667192Y425669D01*
X1668026D01*
G01X1664009D02*
Y428169D01*
X1664509Y427669D01*
G01Y425669D02*
X1663509D01*
G01X1661701Y426711D02*
X1661409Y427002D01*
X1661159Y427169D01*
X1660826Y427252D01*
X1660534Y427169D01*
X1660326Y427002D01*
X1660159Y426752D01*
X1660117Y426461D01*
X1660159Y426211D01*
X1660326Y425961D01*
X1660576Y425752D01*
X1660867Y425669D01*
X1661201Y425752D01*
X1661492Y426002D01*
X1661659Y426377D01*
X1661701Y426794D01*
X1661617Y427336D01*
X1661492Y427627D01*
X1661284Y427919D01*
X1660992Y428127D01*
X1660701Y428169D01*
X1660409Y428086D01*
X1660201Y427877D01*
G01X1674493Y421747D02*
Y424247D01*
X1673452D01*
X1673118Y424122D01*
X1672910Y423955D01*
X1672827Y423622D01*
X1672910Y423289D01*
X1673160Y423080D01*
X1673452Y422955D01*
X1674493D01*
G01X1673452D02*
X1672827Y421747D01*
G01X1670643D02*
X1670560Y422289D01*
X1670435Y422747D01*
X1670268Y423164D01*
X1670060Y423622D01*
X1669727Y424247D01*
X1671393D01*
G01X1668377Y421747D02*
Y424247D01*
X1667543D01*
X1667210Y424122D01*
X1666960Y423955D01*
X1666752Y423705D01*
X1666585Y423414D01*
X1666543Y422997D01*
X1666585Y422580D01*
X1666752Y422289D01*
X1666960Y422039D01*
X1667210Y421872D01*
X1667543Y421747D01*
X1668377D01*
G01X1664360D02*
Y424247D01*
X1664860Y423747D01*
G01Y421747D02*
X1663860D01*
G01X1655388Y408916D02*
X1657888D01*
Y409957D01*
X1657763Y410291D01*
X1657596Y410499D01*
X1657263Y410582D01*
X1656930Y410499D01*
X1656721Y410249D01*
X1656596Y409957D01*
Y408916D01*
G01Y409957D02*
X1655388Y410582D01*
G01X1655888Y411932D02*
X1655596Y412182D01*
X1655430Y412516D01*
X1655388Y412891D01*
X1655430Y413224D01*
X1655638Y413557D01*
X1655888Y413766D01*
X1656138Y413807D01*
X1656430Y413724D01*
X1656638Y413432D01*
X1656721Y413141D01*
Y412766D01*
G01Y413141D02*
X1656846Y413391D01*
X1657055Y413599D01*
X1657305Y413682D01*
X1657555Y413599D01*
X1657763Y413391D01*
X1657888Y413016D01*
X1657846Y412641D01*
X1657680Y412266D01*
G01X1655388Y415116D02*
X1657888D01*
Y416116D01*
X1657763Y416449D01*
X1657471Y416699D01*
X1657138Y416782D01*
X1656805Y416699D01*
X1656555Y416491D01*
X1656430Y416116D01*
Y415116D01*
G01X1655763Y418132D02*
X1655555Y418382D01*
X1655430Y418674D01*
X1655388Y419049D01*
X1655471Y419424D01*
X1655638Y419716D01*
X1655930Y419924D01*
X1656263Y419966D01*
X1656596Y419882D01*
X1656805Y419674D01*
X1656971Y419382D01*
X1657013Y419091D01*
X1656971Y418799D01*
X1656805Y418424D01*
X1657888Y418549D01*
Y419674D01*
G01X1651888Y408866D02*
X1654388D01*
Y409907D01*
X1654263Y410241D01*
X1654096Y410449D01*
X1653763Y410532D01*
X1653430Y410449D01*
X1653221Y410199D01*
X1653096Y409907D01*
Y408866D01*
G01Y409907D02*
X1651888Y410532D01*
G01X1652388Y411882D02*
X1652096Y412132D01*
X1651930Y412466D01*
X1651888Y412841D01*
X1651930Y413174D01*
X1652138Y413507D01*
X1652388Y413716D01*
X1652638Y413757D01*
X1652930Y413674D01*
X1653138Y413382D01*
X1653221Y413091D01*
Y412716D01*
G01Y413091D02*
X1653346Y413341D01*
X1653555Y413549D01*
X1653805Y413632D01*
X1654055Y413549D01*
X1654263Y413341D01*
X1654388Y412966D01*
X1654346Y412591D01*
X1654180Y412216D01*
G01X1651888Y415066D02*
X1654388D01*
Y416066D01*
X1654263Y416399D01*
X1653971Y416649D01*
X1653638Y416732D01*
X1653305Y416649D01*
X1653055Y416441D01*
X1652930Y416066D01*
Y415066D01*
G01X1652263Y418082D02*
X1652055Y418332D01*
X1651930Y418624D01*
X1651888Y418999D01*
X1651971Y419374D01*
X1652138Y419666D01*
X1652430Y419874D01*
X1652763Y419916D01*
X1653096Y419832D01*
X1653305Y419624D01*
X1653471Y419332D01*
X1653513Y419041D01*
X1653471Y418749D01*
X1653305Y418374D01*
X1654388Y418499D01*
Y419624D01*
G01X1652388Y421182D02*
X1652096Y421432D01*
X1651930Y421766D01*
X1651888Y422141D01*
X1651930Y422474D01*
X1652138Y422807D01*
X1652388Y423016D01*
X1652638Y423057D01*
X1652930Y422974D01*
X1653138Y422682D01*
X1653221Y422391D01*
Y422016D01*
G01Y422391D02*
X1653346Y422641D01*
X1653555Y422849D01*
X1653805Y422932D01*
X1654055Y422849D01*
X1654263Y422641D01*
X1654388Y422266D01*
X1654346Y421891D01*
X1654180Y421516D01*
G01X1652867Y431167D02*
X1655367D01*
Y432208D01*
X1655242Y432542D01*
X1655075Y432750D01*
X1654742Y432833D01*
X1654409Y432750D01*
X1654200Y432500D01*
X1654075Y432208D01*
Y431167D01*
G01Y432208D02*
X1652867Y432833D01*
G01X1653367Y434183D02*
X1653075Y434433D01*
X1652909Y434767D01*
X1652867Y435142D01*
X1652909Y435475D01*
X1653117Y435808D01*
X1653367Y436017D01*
X1653617Y436058D01*
X1653909Y435975D01*
X1654117Y435683D01*
X1654200Y435392D01*
Y435017D01*
G01Y435392D02*
X1654325Y435642D01*
X1654534Y435850D01*
X1654784Y435933D01*
X1655034Y435850D01*
X1655242Y435642D01*
X1655367Y435267D01*
X1655325Y434892D01*
X1655159Y434517D01*
G01X1652867Y437367D02*
X1655367D01*
Y438367D01*
X1655242Y438700D01*
X1654950Y438950D01*
X1654617Y439033D01*
X1654284Y438950D01*
X1654034Y438742D01*
X1653909Y438367D01*
Y437367D01*
G01Y440508D02*
X1654200Y440800D01*
X1654367Y441050D01*
X1654450Y441383D01*
X1654367Y441675D01*
X1654200Y441883D01*
X1653950Y442050D01*
X1653659Y442092D01*
X1653409Y442050D01*
X1653159Y441883D01*
X1652950Y441633D01*
X1652867Y441342D01*
X1652950Y441008D01*
X1653200Y440717D01*
X1653575Y440550D01*
X1653992Y440508D01*
X1654534Y440592D01*
X1654825Y440717D01*
X1655117Y440925D01*
X1655325Y441217D01*
X1655367Y441508D01*
X1655284Y441800D01*
X1655075Y442008D01*
G01X1652867Y444400D02*
X1655367D01*
X1654867Y443900D01*
G01X1652867D02*
Y444900D01*
G01X1682035Y517443D02*
X1681728Y517185D01*
X1681383Y517030D01*
X1681077D01*
X1680770Y517185D01*
X1680540Y517443D01*
X1680425Y517805D01*
X1680502Y518167D01*
X1680693Y518477D01*
X1681038Y518683D01*
X1681498Y518787D01*
X1681767Y518993D01*
X1681882Y519355D01*
X1681805Y519717D01*
X1681613Y519975D01*
X1681345Y520130D01*
X1681077D01*
X1680808Y520027D01*
X1680578Y519768D01*
G01X1678935Y517443D02*
X1678628Y517185D01*
X1678283Y517030D01*
X1677977D01*
X1677670Y517185D01*
X1677440Y517443D01*
X1677325Y517805D01*
X1677402Y518167D01*
X1677593Y518477D01*
X1677938Y518683D01*
X1678398Y518787D01*
X1678667Y518993D01*
X1678782Y519355D01*
X1678705Y519717D01*
X1678513Y519975D01*
X1678245Y520130D01*
X1677977D01*
X1677708Y520027D01*
X1677478Y519768D01*
G01X1675988Y517030D02*
X1675030Y520130D01*
X1674072Y517030D01*
G01X1674417Y518115D02*
X1675643D01*
G01X1671930Y520130D02*
Y517030D01*
G01X1672812Y520130D02*
X1671048D01*
G01X1669788Y517030D02*
X1668830Y520130D01*
X1667872Y517030D01*
G01X1668217Y518115D02*
X1669443D01*
G01X1665922Y515997D02*
X1666305Y516513D01*
X1666497Y517030D01*
Y519097D01*
X1666305Y519613D01*
X1665922Y520130D01*
G01X1663358Y519613D02*
X1663128Y519923D01*
X1662860Y520078D01*
X1662553Y520130D01*
X1662170Y520027D01*
X1661902Y519768D01*
X1661825Y519458D01*
X1661863Y519148D01*
X1662017Y518890D01*
X1662783Y518373D01*
X1663128Y518012D01*
X1663358Y517495D01*
X1663435Y517030D01*
X1661825D01*
G01X1659338Y515997D02*
X1658955Y516513D01*
X1658763Y517030D01*
Y519097D01*
X1658955Y519613D01*
X1659338Y520130D01*
G01X1695383Y523600D02*
X1695175Y523350D01*
X1694925Y523183D01*
X1694633Y523100D01*
X1694300Y523183D01*
X1694050Y523350D01*
X1693800Y523600D01*
X1693717Y523933D01*
Y525600D01*
G01X1692242Y525183D02*
X1691992Y525433D01*
X1691700Y525558D01*
X1691367Y525600D01*
X1690950Y525517D01*
X1690658Y525308D01*
X1690575Y525058D01*
X1690617Y524808D01*
X1690783Y524600D01*
X1691617Y524183D01*
X1691992Y523892D01*
X1692242Y523475D01*
X1692325Y523100D01*
X1690575D01*
G01X1689600Y525600D02*
X1689017Y523100D01*
X1688350Y525600D01*
X1687683Y523100D01*
X1687100Y525600D01*
G01X1685250Y523100D02*
Y525600D01*
X1685750Y525100D01*
G01Y523100D02*
X1684750D01*
G01X1708883Y574232D02*
Y576732D01*
X1707842D01*
X1707508Y576607D01*
X1707300Y576440D01*
X1707217Y576107D01*
X1707300Y575774D01*
X1707550Y575565D01*
X1707842Y575440D01*
X1708883D01*
G01X1707842D02*
X1707217Y574232D01*
G01X1705742Y576315D02*
X1705492Y576565D01*
X1705200Y576690D01*
X1704867Y576732D01*
X1704450Y576649D01*
X1704158Y576440D01*
X1704075Y576190D01*
X1704117Y575940D01*
X1704283Y575732D01*
X1705117Y575315D01*
X1705492Y575024D01*
X1705742Y574607D01*
X1705825Y574232D01*
X1704075D01*
G01X1702683Y576732D02*
Y574232D01*
X1701017D01*
G01X1699542Y576315D02*
X1699292Y576565D01*
X1699000Y576690D01*
X1698667Y576732D01*
X1698250Y576649D01*
X1697958Y576440D01*
X1697875Y576190D01*
X1697917Y575940D01*
X1698083Y575732D01*
X1698917Y575315D01*
X1699292Y575024D01*
X1699542Y574607D01*
X1699625Y574232D01*
X1697875D01*
G01X1695650D02*
Y576732D01*
X1696150Y576232D01*
G01Y574232D02*
X1695150D01*
G01X1702292Y587606D02*
Y590106D01*
X1701251D01*
X1700917Y589981D01*
X1700709Y589814D01*
X1700626Y589481D01*
X1700709Y589148D01*
X1700959Y588939D01*
X1701251Y588814D01*
X1702292D01*
G01X1701251D02*
X1700626Y587606D01*
G01X1699151Y589689D02*
X1698901Y589939D01*
X1698609Y590064D01*
X1698276Y590106D01*
X1697859Y590023D01*
X1697567Y589814D01*
X1697484Y589564D01*
X1697526Y589314D01*
X1697692Y589106D01*
X1698526Y588689D01*
X1698901Y588398D01*
X1699151Y587981D01*
X1699234Y587606D01*
X1697484D01*
G01X1696092Y590106D02*
Y587606D01*
X1694426D01*
G01X1692159D02*
Y590106D01*
X1692659Y589606D01*
G01Y587606D02*
X1691659D01*
G01X1689059D02*
X1688767Y587648D01*
X1688434Y587773D01*
X1688226Y587981D01*
X1688142Y588273D01*
X1688226Y588564D01*
X1688476Y588814D01*
X1688851Y588939D01*
X1689267D01*
X1689517Y589023D01*
X1689726Y589231D01*
X1689809Y589523D01*
X1689684Y589814D01*
X1689392Y590023D01*
X1689059Y590106D01*
X1688726Y590023D01*
X1688434Y589814D01*
X1688309Y589523D01*
X1688392Y589231D01*
X1688601Y589023D01*
X1688851Y588939D01*
X1689267D01*
X1689642Y588814D01*
X1689892Y588564D01*
X1689976Y588273D01*
X1689892Y587981D01*
X1689684Y587773D01*
X1689351Y587648D01*
X1689059Y587606D01*
G01X1714192Y562317D02*
X1714317Y562067D01*
X1714400Y561775D01*
Y561442D01*
X1714275Y561067D01*
X1714067Y560775D01*
X1713817Y560567D01*
X1713400Y560400D01*
X1713025Y560358D01*
X1712650Y560442D01*
X1712400Y560567D01*
X1712150Y560817D01*
X1711983Y561108D01*
X1711900Y561400D01*
Y561692D01*
X1711983Y561983D01*
X1712108Y562233D01*
X1712275Y562442D01*
G01X1713983Y563708D02*
X1714233Y563958D01*
X1714358Y564250D01*
X1714400Y564583D01*
X1714317Y565000D01*
X1714108Y565292D01*
X1713858Y565375D01*
X1713608Y565333D01*
X1713400Y565167D01*
X1712983Y564333D01*
X1712692Y563958D01*
X1712275Y563708D01*
X1711900Y563625D01*
Y565375D01*
G01X1714400Y566767D02*
X1711900D01*
Y568433D01*
G01X1712275Y569783D02*
X1712067Y570033D01*
X1711942Y570325D01*
X1711900Y570700D01*
X1711983Y571075D01*
X1712150Y571367D01*
X1712442Y571575D01*
X1712775Y571617D01*
X1713108Y571533D01*
X1713317Y571325D01*
X1713483Y571033D01*
X1713525Y570742D01*
X1713483Y570450D01*
X1713317Y570075D01*
X1714400Y570200D01*
Y571325D01*
G01Y573800D02*
X1714317Y573467D01*
X1714108Y573217D01*
X1713858Y573050D01*
X1713525Y572925D01*
X1713150Y572883D01*
X1712775Y572925D01*
X1712442Y573050D01*
X1712192Y573217D01*
X1711983Y573467D01*
X1711900Y573800D01*
X1711983Y574133D01*
X1712192Y574383D01*
X1712442Y574550D01*
X1712775Y574675D01*
X1713150Y574717D01*
X1713525Y574675D01*
X1713858Y574550D01*
X1714108Y574383D01*
X1714317Y574133D01*
X1714400Y573800D01*
G01X1691583Y578059D02*
X1691833Y578184D01*
X1692125Y578267D01*
X1692458D01*
X1692833Y578142D01*
X1693125Y577934D01*
X1693333Y577684D01*
X1693500Y577267D01*
X1693542Y576892D01*
X1693458Y576517D01*
X1693333Y576267D01*
X1693083Y576017D01*
X1692792Y575850D01*
X1692500Y575767D01*
X1692208D01*
X1691917Y575850D01*
X1691667Y575975D01*
X1691458Y576142D01*
G01X1690192Y577850D02*
X1689942Y578100D01*
X1689650Y578225D01*
X1689317Y578267D01*
X1688900Y578184D01*
X1688608Y577975D01*
X1688525Y577725D01*
X1688567Y577475D01*
X1688733Y577267D01*
X1689567Y576850D01*
X1689942Y576559D01*
X1690192Y576142D01*
X1690275Y575767D01*
X1688525D01*
G01X1687133Y578267D02*
Y575767D01*
X1685467D01*
G01X1684117Y576142D02*
X1683867Y575934D01*
X1683575Y575809D01*
X1683200Y575767D01*
X1682825Y575850D01*
X1682533Y576017D01*
X1682325Y576309D01*
X1682283Y576642D01*
X1682367Y576975D01*
X1682575Y577184D01*
X1682867Y577350D01*
X1683158Y577392D01*
X1683450Y577350D01*
X1683825Y577184D01*
X1683700Y578267D01*
X1682575D01*
G01X1680892Y577850D02*
X1680642Y578100D01*
X1680350Y578225D01*
X1680017Y578267D01*
X1679600Y578184D01*
X1679308Y577975D01*
X1679225Y577725D01*
X1679267Y577475D01*
X1679433Y577267D01*
X1680267Y576850D01*
X1680642Y576559D01*
X1680892Y576142D01*
X1680975Y575767D01*
X1679225D01*
G01X1691083Y574759D02*
X1691333Y574884D01*
X1691625Y574967D01*
X1691958D01*
X1692333Y574842D01*
X1692625Y574634D01*
X1692833Y574384D01*
X1693000Y573967D01*
X1693042Y573592D01*
X1692958Y573217D01*
X1692833Y572967D01*
X1692583Y572717D01*
X1692292Y572550D01*
X1692000Y572467D01*
X1691708D01*
X1691417Y572550D01*
X1691167Y572675D01*
X1690958Y572842D01*
G01X1689692Y574550D02*
X1689442Y574800D01*
X1689150Y574925D01*
X1688817Y574967D01*
X1688400Y574884D01*
X1688108Y574675D01*
X1688025Y574425D01*
X1688067Y574175D01*
X1688233Y573967D01*
X1689067Y573550D01*
X1689442Y573259D01*
X1689692Y572842D01*
X1689775Y572467D01*
X1688025D01*
G01X1686633Y574967D02*
Y572467D01*
X1684967D01*
G01X1683617Y572842D02*
X1683367Y572634D01*
X1683075Y572509D01*
X1682700Y572467D01*
X1682325Y572550D01*
X1682033Y572717D01*
X1681825Y573009D01*
X1681783Y573342D01*
X1681867Y573675D01*
X1682075Y573884D01*
X1682367Y574050D01*
X1682658Y574092D01*
X1682950Y574050D01*
X1683325Y573884D01*
X1683200Y574967D01*
X1682075D01*
G01X1679600Y572467D02*
Y574967D01*
X1680100Y574467D01*
G01Y572467D02*
X1679100D01*
G01X1673060Y575499D02*
X1673310Y575624D01*
X1673602Y575707D01*
X1673935D01*
X1674310Y575582D01*
X1674602Y575374D01*
X1674810Y575124D01*
X1674977Y574707D01*
X1675019Y574332D01*
X1674935Y573957D01*
X1674810Y573707D01*
X1674560Y573457D01*
X1674269Y573290D01*
X1673977Y573207D01*
X1673685D01*
X1673394Y573290D01*
X1673144Y573415D01*
X1672935Y573582D01*
G01X1671669Y575290D02*
X1671419Y575540D01*
X1671127Y575665D01*
X1670794Y575707D01*
X1670377Y575624D01*
X1670085Y575415D01*
X1670002Y575165D01*
X1670044Y574915D01*
X1670210Y574707D01*
X1671044Y574290D01*
X1671419Y573999D01*
X1671669Y573582D01*
X1671752Y573207D01*
X1670002D01*
G01X1668610Y575707D02*
Y573207D01*
X1666944D01*
G01X1665469Y575290D02*
X1665219Y575540D01*
X1664927Y575665D01*
X1664594Y575707D01*
X1664177Y575624D01*
X1663885Y575415D01*
X1663802Y575165D01*
X1663844Y574915D01*
X1664010Y574707D01*
X1664844Y574290D01*
X1665219Y573999D01*
X1665469Y573582D01*
X1665552Y573207D01*
X1663802D01*
G01X1662494Y573707D02*
X1662244Y573415D01*
X1661910Y573249D01*
X1661535Y573207D01*
X1661202Y573249D01*
X1660869Y573457D01*
X1660660Y573707D01*
X1660619Y573957D01*
X1660702Y574249D01*
X1660994Y574457D01*
X1661285Y574540D01*
X1661660D01*
G01X1661285D02*
X1661035Y574665D01*
X1660827Y574874D01*
X1660744Y575124D01*
X1660827Y575374D01*
X1661035Y575582D01*
X1661410Y575707D01*
X1661785Y575665D01*
X1662160Y575499D01*
G01X1673360Y578899D02*
X1673610Y579024D01*
X1673902Y579107D01*
X1674235D01*
X1674610Y578982D01*
X1674902Y578774D01*
X1675110Y578524D01*
X1675277Y578107D01*
X1675319Y577732D01*
X1675235Y577357D01*
X1675110Y577107D01*
X1674860Y576857D01*
X1674569Y576690D01*
X1674277Y576607D01*
X1673985D01*
X1673694Y576690D01*
X1673444Y576815D01*
X1673235Y576982D01*
G01X1671969Y578690D02*
X1671719Y578940D01*
X1671427Y579065D01*
X1671094Y579107D01*
X1670677Y579024D01*
X1670385Y578815D01*
X1670302Y578565D01*
X1670344Y578315D01*
X1670510Y578107D01*
X1671344Y577690D01*
X1671719Y577399D01*
X1671969Y576982D01*
X1672052Y576607D01*
X1670302D01*
G01X1668910Y579107D02*
Y576607D01*
X1667244D01*
G01X1665769Y578690D02*
X1665519Y578940D01*
X1665227Y579065D01*
X1664894Y579107D01*
X1664477Y579024D01*
X1664185Y578815D01*
X1664102Y578565D01*
X1664144Y578315D01*
X1664310Y578107D01*
X1665144Y577690D01*
X1665519Y577399D01*
X1665769Y576982D01*
X1665852Y576607D01*
X1664102D01*
G01X1662669Y578690D02*
X1662419Y578940D01*
X1662127Y579065D01*
X1661794Y579107D01*
X1661377Y579024D01*
X1661085Y578815D01*
X1661002Y578565D01*
X1661044Y578315D01*
X1661210Y578107D01*
X1662044Y577690D01*
X1662419Y577399D01*
X1662669Y576982D01*
X1662752Y576607D01*
X1661002D01*
G01X1702980Y554700D02*
X1706080D01*
X1705460Y554240D01*
G01X1702980D02*
Y555160D01*
G01Y556957D02*
X1706080D01*
Y557723D01*
X1705925Y558030D01*
X1705718Y558260D01*
X1705408Y558452D01*
X1705047Y558605D01*
X1704530Y558643D01*
X1704013Y558605D01*
X1703652Y558452D01*
X1703342Y558260D01*
X1703135Y558030D01*
X1702980Y557723D01*
Y556957D01*
G01Y560900D02*
X1706080D01*
X1705460Y560440D01*
G01X1702980D02*
Y561360D01*
G01X1794234Y527997D02*
Y552897D01*
X1654034D01*
Y527997D01*
X1794234D01*
G01X1713597Y606762D02*
Y609262D01*
X1712556D01*
X1712222Y609137D01*
X1712014Y608970D01*
X1711931Y608637D01*
X1712014Y608304D01*
X1712264Y608095D01*
X1712556Y607970D01*
X1713597D01*
G01X1712556D02*
X1711931Y606762D01*
G01X1710456Y608845D02*
X1710206Y609095D01*
X1709914Y609220D01*
X1709581Y609262D01*
X1709164Y609179D01*
X1708872Y608970D01*
X1708789Y608720D01*
X1708831Y608470D01*
X1708997Y608262D01*
X1709831Y607845D01*
X1710206Y607554D01*
X1710456Y607137D01*
X1710539Y606762D01*
X1708789D01*
G01X1707397Y609262D02*
Y606762D01*
X1705731D01*
G01X1703464D02*
Y609262D01*
X1703964Y608762D01*
G01Y606762D02*
X1702964D01*
G01X1700364D02*
Y609262D01*
X1700864Y608762D01*
G01Y606762D02*
X1699864D01*
G01X1702080Y591438D02*
Y593938D01*
X1701039D01*
X1700705Y593813D01*
X1700497Y593646D01*
X1700414Y593313D01*
X1700497Y592980D01*
X1700747Y592771D01*
X1701039Y592646D01*
X1702080D01*
G01X1701039D02*
X1700414Y591438D01*
G01X1698939Y593521D02*
X1698689Y593771D01*
X1698397Y593896D01*
X1698064Y593938D01*
X1697647Y593855D01*
X1697355Y593646D01*
X1697272Y593396D01*
X1697314Y593146D01*
X1697480Y592938D01*
X1698314Y592521D01*
X1698689Y592230D01*
X1698939Y591813D01*
X1699022Y591438D01*
X1697272D01*
G01X1695880Y593938D02*
Y591438D01*
X1694214D01*
G01X1691947D02*
Y593938D01*
X1692447Y593438D01*
G01Y591438D02*
X1691447D01*
G01X1689764Y591813D02*
X1689514Y591605D01*
X1689222Y591480D01*
X1688847Y591438D01*
X1688472Y591521D01*
X1688180Y591688D01*
X1687972Y591980D01*
X1687930Y592313D01*
X1688014Y592646D01*
X1688222Y592855D01*
X1688514Y593021D01*
X1688805Y593063D01*
X1689097Y593021D01*
X1689472Y592855D01*
X1689347Y593938D01*
X1688222D01*
G01X1699966Y603379D02*
Y605879D01*
X1698925D01*
X1698591Y605754D01*
X1698383Y605587D01*
X1698300Y605254D01*
X1698383Y604921D01*
X1698633Y604712D01*
X1698925Y604587D01*
X1699966D01*
G01X1698925D02*
X1698300Y603379D01*
G01X1696825Y605462D02*
X1696575Y605712D01*
X1696283Y605837D01*
X1695950Y605879D01*
X1695533Y605796D01*
X1695241Y605587D01*
X1695158Y605337D01*
X1695200Y605087D01*
X1695366Y604879D01*
X1696200Y604462D01*
X1696575Y604171D01*
X1696825Y603754D01*
X1696908Y603379D01*
X1695158D01*
G01X1693766Y605879D02*
Y603379D01*
X1692100D01*
G01X1689833D02*
Y605879D01*
X1690333Y605379D01*
G01Y603379D02*
X1689333D01*
G01X1687525Y605462D02*
X1687275Y605712D01*
X1686983Y605837D01*
X1686650Y605879D01*
X1686233Y605796D01*
X1685941Y605587D01*
X1685858Y605337D01*
X1685900Y605087D01*
X1686066Y604879D01*
X1686900Y604462D01*
X1687275Y604171D01*
X1687525Y603754D01*
X1687608Y603379D01*
X1685858D01*
G01X1665297Y622551D02*
X1665547Y622676D01*
X1665839Y622759D01*
X1666172D01*
X1666547Y622634D01*
X1666839Y622426D01*
X1667047Y622176D01*
X1667214Y621759D01*
X1667256Y621384D01*
X1667172Y621009D01*
X1667047Y620759D01*
X1666797Y620509D01*
X1666506Y620342D01*
X1666214Y620259D01*
X1665922D01*
X1665631Y620342D01*
X1665381Y620467D01*
X1665172Y620634D01*
G01X1663906Y622342D02*
X1663656Y622592D01*
X1663364Y622717D01*
X1663031Y622759D01*
X1662614Y622676D01*
X1662322Y622467D01*
X1662239Y622217D01*
X1662281Y621967D01*
X1662447Y621759D01*
X1663281Y621342D01*
X1663656Y621051D01*
X1663906Y620634D01*
X1663989Y620259D01*
X1662239D01*
G01X1660847Y622759D02*
Y620259D01*
X1659181D01*
G01X1657831Y620759D02*
X1657581Y620467D01*
X1657247Y620301D01*
X1656872Y620259D01*
X1656539Y620301D01*
X1656206Y620509D01*
X1655997Y620759D01*
X1655956Y621009D01*
X1656039Y621301D01*
X1656331Y621509D01*
X1656622Y621592D01*
X1656997D01*
G01X1656622D02*
X1656372Y621717D01*
X1656164Y621926D01*
X1656081Y622176D01*
X1656164Y622426D01*
X1656372Y622634D01*
X1656747Y622759D01*
X1657122Y622717D01*
X1657497Y622551D01*
G01X1665297Y619051D02*
X1665547Y619176D01*
X1665839Y619259D01*
X1666172D01*
X1666547Y619134D01*
X1666839Y618926D01*
X1667047Y618676D01*
X1667214Y618259D01*
X1667256Y617884D01*
X1667172Y617509D01*
X1667047Y617259D01*
X1666797Y617009D01*
X1666506Y616842D01*
X1666214Y616759D01*
X1665922D01*
X1665631Y616842D01*
X1665381Y616967D01*
X1665172Y617134D01*
G01X1663906Y618842D02*
X1663656Y619092D01*
X1663364Y619217D01*
X1663031Y619259D01*
X1662614Y619176D01*
X1662322Y618967D01*
X1662239Y618717D01*
X1662281Y618467D01*
X1662447Y618259D01*
X1663281Y617842D01*
X1663656Y617551D01*
X1663906Y617134D01*
X1663989Y616759D01*
X1662239D01*
G01X1660847Y619259D02*
Y616759D01*
X1659181D01*
G01X1656414D02*
Y619259D01*
X1657956Y617467D01*
X1655872D01*
G01X1682133Y608359D02*
X1682383Y608484D01*
X1682675Y608567D01*
X1683008D01*
X1683383Y608442D01*
X1683675Y608234D01*
X1683883Y607984D01*
X1684050Y607567D01*
X1684092Y607192D01*
X1684008Y606817D01*
X1683883Y606567D01*
X1683633Y606317D01*
X1683342Y606150D01*
X1683050Y606067D01*
X1682758D01*
X1682467Y606150D01*
X1682217Y606275D01*
X1682008Y606442D01*
G01X1680742Y608150D02*
X1680492Y608400D01*
X1680200Y608525D01*
X1679867Y608567D01*
X1679450Y608484D01*
X1679158Y608275D01*
X1679075Y608025D01*
X1679117Y607775D01*
X1679283Y607567D01*
X1680117Y607150D01*
X1680492Y606859D01*
X1680742Y606442D01*
X1680825Y606067D01*
X1679075D01*
G01X1677683Y608567D02*
Y606067D01*
X1676017D01*
G01X1674542Y607109D02*
X1674250Y607400D01*
X1674000Y607567D01*
X1673667Y607650D01*
X1673375Y607567D01*
X1673167Y607400D01*
X1673000Y607150D01*
X1672958Y606859D01*
X1673000Y606609D01*
X1673167Y606359D01*
X1673417Y606150D01*
X1673708Y606067D01*
X1674042Y606150D01*
X1674333Y606400D01*
X1674500Y606775D01*
X1674542Y607192D01*
X1674458Y607734D01*
X1674333Y608025D01*
X1674125Y608317D01*
X1673833Y608525D01*
X1673542Y608567D01*
X1673250Y608484D01*
X1673042Y608275D01*
G01X1682083Y604959D02*
X1682333Y605084D01*
X1682625Y605167D01*
X1682958D01*
X1683333Y605042D01*
X1683625Y604834D01*
X1683833Y604584D01*
X1684000Y604167D01*
X1684042Y603792D01*
X1683958Y603417D01*
X1683833Y603167D01*
X1683583Y602917D01*
X1683292Y602750D01*
X1683000Y602667D01*
X1682708D01*
X1682417Y602750D01*
X1682167Y602875D01*
X1681958Y603042D01*
G01X1680692Y604750D02*
X1680442Y605000D01*
X1680150Y605125D01*
X1679817Y605167D01*
X1679400Y605084D01*
X1679108Y604875D01*
X1679025Y604625D01*
X1679067Y604375D01*
X1679233Y604167D01*
X1680067Y603750D01*
X1680442Y603459D01*
X1680692Y603042D01*
X1680775Y602667D01*
X1679025D01*
G01X1677633Y605167D02*
Y602667D01*
X1675967D01*
G01X1673700D02*
Y605167D01*
X1674200Y604667D01*
G01Y602667D02*
X1673200D01*
G01X1670600Y605167D02*
X1670933Y605084D01*
X1671183Y604875D01*
X1671350Y604625D01*
X1671475Y604292D01*
X1671517Y603917D01*
X1671475Y603542D01*
X1671350Y603209D01*
X1671183Y602959D01*
X1670933Y602750D01*
X1670600Y602667D01*
X1670267Y602750D01*
X1670017Y602959D01*
X1669850Y603209D01*
X1669725Y603542D01*
X1669683Y603917D01*
X1669725Y604292D01*
X1669850Y604625D01*
X1670017Y604875D01*
X1670267Y605084D01*
X1670600Y605167D01*
G01X1778197Y27315D02*
Y29815D01*
X1777156D01*
X1776822Y29690D01*
X1776614Y29523D01*
X1776531Y29190D01*
X1776614Y28857D01*
X1776864Y28648D01*
X1777156Y28523D01*
X1778197D01*
G01X1777156D02*
X1776531Y27315D01*
G01X1775056Y29398D02*
X1774806Y29648D01*
X1774514Y29773D01*
X1774181Y29815D01*
X1773764Y29732D01*
X1773472Y29523D01*
X1773389Y29273D01*
X1773431Y29023D01*
X1773597Y28815D01*
X1774431Y28398D01*
X1774806Y28107D01*
X1775056Y27690D01*
X1775139Y27315D01*
X1773389D01*
G01X1772081Y29815D02*
Y28023D01*
X1771914Y27648D01*
X1771581Y27398D01*
X1771164Y27315D01*
X1770747Y27398D01*
X1770414Y27648D01*
X1770247Y28023D01*
Y29815D01*
G01X1767564Y27315D02*
Y29815D01*
X1769106Y28023D01*
X1767022D01*
G01X1765881Y27815D02*
X1765631Y27523D01*
X1765297Y27357D01*
X1764922Y27315D01*
X1764589Y27357D01*
X1764256Y27565D01*
X1764047Y27815D01*
X1764006Y28065D01*
X1764089Y28357D01*
X1764381Y28565D01*
X1764672Y28648D01*
X1765047D01*
G01X1764672D02*
X1764422Y28773D01*
X1764214Y28982D01*
X1764131Y29232D01*
X1764214Y29482D01*
X1764422Y29690D01*
X1764797Y29815D01*
X1765172Y29773D01*
X1765547Y29607D01*
G01X1784752Y23269D02*
Y25769D01*
X1783711D01*
X1783377Y25644D01*
X1783169Y25477D01*
X1783086Y25144D01*
X1783169Y24811D01*
X1783419Y24602D01*
X1783711Y24477D01*
X1784752D01*
G01X1783711D02*
X1783086Y23269D01*
G01X1781611Y24311D02*
X1781319Y24602D01*
X1781069Y24769D01*
X1780736Y24852D01*
X1780444Y24769D01*
X1780236Y24602D01*
X1780069Y24352D01*
X1780027Y24061D01*
X1780069Y23811D01*
X1780236Y23561D01*
X1780486Y23352D01*
X1780777Y23269D01*
X1781111Y23352D01*
X1781402Y23602D01*
X1781569Y23977D01*
X1781611Y24394D01*
X1781527Y24936D01*
X1781402Y25227D01*
X1781194Y25519D01*
X1780902Y25727D01*
X1780611Y25769D01*
X1780319Y25686D01*
X1780111Y25477D01*
G01X1778969Y25769D02*
X1778386Y23269D01*
X1777719Y25769D01*
X1777052Y23269D01*
X1776469Y25769D01*
G01X1775411Y25352D02*
X1775161Y25602D01*
X1774869Y25727D01*
X1774536Y25769D01*
X1774119Y25686D01*
X1773827Y25477D01*
X1773744Y25227D01*
X1773786Y24977D01*
X1773952Y24769D01*
X1774786Y24352D01*
X1775161Y24061D01*
X1775411Y23644D01*
X1775494Y23269D01*
X1773744D01*
G01X1764867Y9544D02*
X1767367D01*
Y10585D01*
X1767242Y10919D01*
X1767075Y11127D01*
X1766742Y11210D01*
X1766409Y11127D01*
X1766200Y10877D01*
X1766075Y10585D01*
Y9544D01*
G01Y10585D02*
X1764867Y11210D01*
G01X1765909Y12685D02*
X1766200Y12977D01*
X1766367Y13227D01*
X1766450Y13560D01*
X1766367Y13852D01*
X1766200Y14060D01*
X1765950Y14227D01*
X1765659Y14269D01*
X1765409Y14227D01*
X1765159Y14060D01*
X1764950Y13810D01*
X1764867Y13519D01*
X1764950Y13185D01*
X1765200Y12894D01*
X1765575Y12727D01*
X1765992Y12685D01*
X1766534Y12769D01*
X1766825Y12894D01*
X1767117Y13102D01*
X1767325Y13394D01*
X1767367Y13685D01*
X1767284Y13977D01*
X1767075Y14185D01*
G01X1767367Y15327D02*
X1764867Y15910D01*
X1767367Y16577D01*
X1764867Y17244D01*
X1767367Y17827D01*
G01X1764867Y19677D02*
X1767367D01*
X1766867Y19177D01*
G01X1764867D02*
Y20177D01*
G01X1763192Y33917D02*
X1763317Y33667D01*
X1763400Y33375D01*
Y33042D01*
X1763275Y32667D01*
X1763067Y32375D01*
X1762817Y32167D01*
X1762400Y32000D01*
X1762025Y31958D01*
X1761650Y32042D01*
X1761400Y32167D01*
X1761150Y32417D01*
X1760983Y32708D01*
X1760900Y33000D01*
Y33292D01*
X1760983Y33583D01*
X1761108Y33833D01*
X1761275Y34042D01*
G01X1762983Y35308D02*
X1763233Y35558D01*
X1763358Y35850D01*
X1763400Y36183D01*
X1763317Y36600D01*
X1763108Y36892D01*
X1762858Y36975D01*
X1762608Y36933D01*
X1762400Y36767D01*
X1761983Y35933D01*
X1761692Y35558D01*
X1761275Y35308D01*
X1760900Y35225D01*
Y36975D01*
G01X1763400Y38283D02*
X1761608D01*
X1761233Y38450D01*
X1760983Y38783D01*
X1760900Y39200D01*
X1760983Y39617D01*
X1761233Y39950D01*
X1761608Y40117D01*
X1763400D01*
G01X1762983Y41508D02*
X1763233Y41758D01*
X1763358Y42050D01*
X1763400Y42383D01*
X1763317Y42800D01*
X1763108Y43092D01*
X1762858Y43175D01*
X1762608Y43133D01*
X1762400Y42967D01*
X1761983Y42133D01*
X1761692Y41758D01*
X1761275Y41508D01*
X1760900Y41425D01*
Y43175D01*
G01X1761942Y44608D02*
X1762233Y44900D01*
X1762400Y45150D01*
X1762483Y45483D01*
X1762400Y45775D01*
X1762233Y45983D01*
X1761983Y46150D01*
X1761692Y46192D01*
X1761442Y46150D01*
X1761192Y45983D01*
X1760983Y45733D01*
X1760900Y45442D01*
X1760983Y45108D01*
X1761233Y44817D01*
X1761608Y44650D01*
X1762025Y44608D01*
X1762567Y44692D01*
X1762858Y44817D01*
X1763150Y45025D01*
X1763358Y45317D01*
X1763400Y45608D01*
X1763317Y45900D01*
X1763108Y46108D01*
G01X1733117Y32900D02*
Y31108D01*
X1732950Y30733D01*
X1732617Y30483D01*
X1732200Y30400D01*
X1731783Y30483D01*
X1731450Y30733D01*
X1731283Y31108D01*
Y32900D01*
G01X1729808Y30692D02*
X1729517Y30483D01*
X1729183Y30400D01*
X1728850Y30483D01*
X1728558Y30733D01*
X1728350Y31108D01*
X1728267Y31483D01*
Y31942D01*
X1728350Y32317D01*
X1728558Y32650D01*
X1728808Y32817D01*
X1729100Y32900D01*
X1729433Y32817D01*
X1729683Y32650D01*
X1729850Y32400D01*
X1729933Y32067D01*
X1729850Y31775D01*
X1729642Y31483D01*
X1729392Y31317D01*
X1729100Y31275D01*
X1728767Y31358D01*
X1728517Y31567D01*
X1728267Y31942D01*
G01X1725750Y31650D02*
X1724917D01*
Y30900D01*
X1725167Y30650D01*
X1725458Y30483D01*
X1725875Y30400D01*
X1726292Y30483D01*
X1726583Y30650D01*
X1726833Y30900D01*
X1727000Y31192D01*
X1727083Y31525D01*
Y31817D01*
X1727000Y32067D01*
X1726833Y32358D01*
X1726583Y32608D01*
X1726333Y32775D01*
X1726000Y32900D01*
X1725708D01*
X1725375Y32817D01*
X1725125Y32650D01*
G01X1722900Y30400D02*
Y32900D01*
X1723400Y32400D01*
G01Y30400D02*
X1722400D01*
G01X1755003Y-22350D02*
X1751903D01*
X1752523Y-21890D01*
G01X1755003D02*
Y-22810D01*
G01Y-25450D02*
X1751903D01*
X1752523Y-24990D01*
G01X1755003D02*
Y-25910D01*
G01Y6000D02*
X1751903D01*
X1752523Y6460D01*
G01X1755003D02*
Y5540D01*
G01X1752420Y3628D02*
X1752110Y3398D01*
X1751955Y3130D01*
X1751903Y2823D01*
X1752006Y2440D01*
X1752265Y2172D01*
X1752575Y2095D01*
X1752885Y2133D01*
X1753143Y2287D01*
X1753660Y3053D01*
X1754021Y3398D01*
X1754538Y3628D01*
X1755003Y3705D01*
Y2095D01*
G01X1768421Y3628D02*
X1768111Y3398D01*
X1767956Y3130D01*
X1767904Y2823D01*
X1768007Y2440D01*
X1768266Y2172D01*
X1768576Y2095D01*
X1768886Y2133D01*
X1769144Y2287D01*
X1769661Y3053D01*
X1770022Y3398D01*
X1770539Y3628D01*
X1771004Y3705D01*
Y2095D01*
G01X1753900Y96300D02*
X1762500D01*
Y86100D01*
X1751700D01*
Y73000D01*
X1743800D01*
Y71300D01*
X1732000D01*
Y81400D01*
X1735100D01*
Y97200D01*
G01X1734430Y96010D02*
X1732930Y94510D01*
Y97510D01*
X1734430Y96010D01*
G01X1767700Y68317D02*
X1770200D01*
Y69358D01*
X1770075Y69692D01*
X1769908Y69900D01*
X1769575Y69983D01*
X1769242Y69900D01*
X1769033Y69650D01*
X1768908Y69358D01*
Y68317D01*
G01Y69358D02*
X1767700Y69983D01*
G01X1768200Y71333D02*
X1767908Y71583D01*
X1767742Y71917D01*
X1767700Y72292D01*
X1767742Y72625D01*
X1767950Y72958D01*
X1768200Y73167D01*
X1768450Y73208D01*
X1768742Y73125D01*
X1768950Y72833D01*
X1769033Y72542D01*
Y72167D01*
G01Y72542D02*
X1769158Y72792D01*
X1769367Y73000D01*
X1769617Y73083D01*
X1769867Y73000D01*
X1770075Y72792D01*
X1770200Y72417D01*
X1770158Y72042D01*
X1769992Y71667D01*
G01X1770200Y74100D02*
X1767700Y74683D01*
X1770200Y75350D01*
X1767700Y76017D01*
X1770200Y76600D01*
G01X1768200Y77533D02*
X1767908Y77783D01*
X1767742Y78117D01*
X1767700Y78492D01*
X1767742Y78825D01*
X1767950Y79158D01*
X1768200Y79367D01*
X1768450Y79408D01*
X1768742Y79325D01*
X1768950Y79033D01*
X1769033Y78742D01*
Y78367D01*
G01Y78742D02*
X1769158Y78992D01*
X1769367Y79200D01*
X1769617Y79283D01*
X1769867Y79200D01*
X1770075Y78992D01*
X1770200Y78617D01*
X1770158Y78242D01*
X1769992Y77867D01*
G01X1755583Y66000D02*
Y68500D01*
X1754542D01*
X1754208Y68375D01*
X1754000Y68208D01*
X1753917Y67875D01*
X1754000Y67542D01*
X1754250Y67333D01*
X1754542Y67208D01*
X1755583D01*
G01X1754542D02*
X1753917Y66000D01*
G01X1752567Y66500D02*
X1752317Y66208D01*
X1751983Y66042D01*
X1751608Y66000D01*
X1751275Y66042D01*
X1750942Y66250D01*
X1750733Y66500D01*
X1750692Y66750D01*
X1750775Y67042D01*
X1751067Y67250D01*
X1751358Y67333D01*
X1751733D01*
G01X1751358D02*
X1751108Y67458D01*
X1750900Y67667D01*
X1750817Y67917D01*
X1750900Y68167D01*
X1751108Y68375D01*
X1751483Y68500D01*
X1751858Y68458D01*
X1752233Y68292D01*
G01X1749800Y68500D02*
X1749217Y66000D01*
X1748550Y68500D01*
X1747883Y66000D01*
X1747300Y68500D01*
G01X1746158Y66292D02*
X1745867Y66083D01*
X1745533Y66000D01*
X1745200Y66083D01*
X1744908Y66333D01*
X1744700Y66708D01*
X1744617Y67083D01*
Y67542D01*
X1744700Y67917D01*
X1744908Y68250D01*
X1745158Y68417D01*
X1745450Y68500D01*
X1745783Y68417D01*
X1746033Y68250D01*
X1746200Y68000D01*
X1746283Y67667D01*
X1746200Y67375D01*
X1745992Y67083D01*
X1745742Y66917D01*
X1745450Y66875D01*
X1745117Y66958D01*
X1744867Y67167D01*
X1744617Y67542D01*
G01X1764783Y58600D02*
Y61100D01*
X1763742D01*
X1763408Y60975D01*
X1763200Y60808D01*
X1763117Y60475D01*
X1763200Y60142D01*
X1763450Y59933D01*
X1763742Y59808D01*
X1764783D01*
G01X1763742D02*
X1763117Y58600D01*
G01X1761767Y59100D02*
X1761517Y58808D01*
X1761183Y58642D01*
X1760808Y58600D01*
X1760475Y58642D01*
X1760142Y58850D01*
X1759933Y59100D01*
X1759892Y59350D01*
X1759975Y59642D01*
X1760267Y59850D01*
X1760558Y59933D01*
X1760933D01*
G01X1760558D02*
X1760308Y60058D01*
X1760100Y60267D01*
X1760017Y60517D01*
X1760100Y60767D01*
X1760308Y60975D01*
X1760683Y61100D01*
X1761058Y61058D01*
X1761433Y60892D01*
G01X1759000Y61100D02*
X1758417Y58600D01*
X1757750Y61100D01*
X1757083Y58600D01*
X1756500Y61100D01*
G01X1754733Y58600D02*
X1754650Y59142D01*
X1754525Y59600D01*
X1754358Y60017D01*
X1754150Y60475D01*
X1753817Y61100D01*
X1755483D01*
G01X1759633Y41400D02*
Y43900D01*
X1758592D01*
X1758258Y43775D01*
X1758050Y43608D01*
X1757967Y43275D01*
X1758050Y42942D01*
X1758300Y42733D01*
X1758592Y42608D01*
X1759633D01*
G01X1758592D02*
X1757967Y41400D01*
G01X1755700D02*
Y43900D01*
X1756200Y43400D01*
G01Y41400D02*
X1755200D01*
G01X1753517Y43900D02*
Y42108D01*
X1753350Y41733D01*
X1753017Y41483D01*
X1752600Y41400D01*
X1752183Y41483D01*
X1751850Y41733D01*
X1751683Y42108D01*
Y43900D01*
G01X1750417Y41900D02*
X1750167Y41608D01*
X1749833Y41442D01*
X1749458Y41400D01*
X1749125Y41442D01*
X1748792Y41650D01*
X1748583Y41900D01*
X1748542Y42150D01*
X1748625Y42442D01*
X1748917Y42650D01*
X1749208Y42733D01*
X1749583D01*
G01X1749208D02*
X1748958Y42858D01*
X1748750Y43067D01*
X1748667Y43317D01*
X1748750Y43567D01*
X1748958Y43775D01*
X1749333Y43900D01*
X1749708Y43858D01*
X1750083Y43692D01*
G01X1746483Y41400D02*
X1746400Y41942D01*
X1746275Y42400D01*
X1746108Y42817D01*
X1745900Y43275D01*
X1745567Y43900D01*
X1747233D01*
G01X1759633Y48400D02*
Y50900D01*
X1758592D01*
X1758258Y50775D01*
X1758050Y50608D01*
X1757967Y50275D01*
X1758050Y49942D01*
X1758300Y49733D01*
X1758592Y49608D01*
X1759633D01*
G01X1758592D02*
X1757967Y48400D01*
G01X1755700D02*
Y50900D01*
X1756200Y50400D01*
G01Y48400D02*
X1755200D01*
G01X1753850Y50900D02*
X1753267Y48400D01*
X1752600Y50900D01*
X1751933Y48400D01*
X1751350Y50900D01*
G01X1750417Y48900D02*
X1750167Y48608D01*
X1749833Y48442D01*
X1749458Y48400D01*
X1749125Y48442D01*
X1748792Y48650D01*
X1748583Y48900D01*
X1748542Y49150D01*
X1748625Y49442D01*
X1748917Y49650D01*
X1749208Y49733D01*
X1749583D01*
G01X1749208D02*
X1748958Y49858D01*
X1748750Y50067D01*
X1748667Y50317D01*
X1748750Y50567D01*
X1748958Y50775D01*
X1749333Y50900D01*
X1749708Y50858D01*
X1750083Y50692D01*
G01X1747317Y48775D02*
X1747067Y48567D01*
X1746775Y48442D01*
X1746400Y48400D01*
X1746025Y48483D01*
X1745733Y48650D01*
X1745525Y48942D01*
X1745483Y49275D01*
X1745567Y49608D01*
X1745775Y49817D01*
X1746067Y49983D01*
X1746358Y50025D01*
X1746650Y49983D01*
X1747025Y49817D01*
X1746900Y50900D01*
X1745775D01*
G01X1741033Y67300D02*
Y69800D01*
X1739992D01*
X1739658Y69675D01*
X1739450Y69508D01*
X1739367Y69175D01*
X1739450Y68842D01*
X1739700Y68633D01*
X1739992Y68508D01*
X1741033D01*
G01X1739992D02*
X1739367Y67300D01*
G01X1737100D02*
Y69800D01*
X1737600Y69300D01*
G01Y67300D02*
X1736600D01*
G01X1734917Y69800D02*
Y68008D01*
X1734750Y67633D01*
X1734417Y67383D01*
X1734000Y67300D01*
X1733583Y67383D01*
X1733250Y67633D01*
X1733083Y68008D01*
Y69800D01*
G01X1731817Y67800D02*
X1731567Y67508D01*
X1731233Y67342D01*
X1730858Y67300D01*
X1730525Y67342D01*
X1730192Y67550D01*
X1729983Y67800D01*
X1729942Y68050D01*
X1730025Y68342D01*
X1730317Y68550D01*
X1730608Y68633D01*
X1730983D01*
G01X1730608D02*
X1730358Y68758D01*
X1730150Y68967D01*
X1730067Y69217D01*
X1730150Y69467D01*
X1730358Y69675D01*
X1730733Y69800D01*
X1731108Y69758D01*
X1731483Y69592D01*
G01X1727800Y69800D02*
X1728133Y69717D01*
X1728383Y69508D01*
X1728550Y69258D01*
X1728675Y68925D01*
X1728717Y68550D01*
X1728675Y68175D01*
X1728550Y67842D01*
X1728383Y67592D01*
X1728133Y67383D01*
X1727800Y67300D01*
X1727467Y67383D01*
X1727217Y67592D01*
X1727050Y67842D01*
X1726925Y68175D01*
X1726883Y68550D01*
X1726925Y68925D01*
X1727050Y69258D01*
X1727217Y69508D01*
X1727467Y69717D01*
X1727800Y69800D01*
G01X1725783Y93050D02*
Y95550D01*
X1724742D01*
X1724408Y95425D01*
X1724200Y95258D01*
X1724117Y94925D01*
X1724200Y94592D01*
X1724450Y94383D01*
X1724742Y94258D01*
X1725783D01*
G01X1724742D02*
X1724117Y93050D01*
G01X1722767Y93550D02*
X1722517Y93258D01*
X1722183Y93092D01*
X1721808Y93050D01*
X1721475Y93092D01*
X1721142Y93300D01*
X1720933Y93550D01*
X1720892Y93800D01*
X1720975Y94092D01*
X1721267Y94300D01*
X1721558Y94383D01*
X1721933D01*
G01X1721558D02*
X1721308Y94508D01*
X1721100Y94717D01*
X1721017Y94967D01*
X1721100Y95217D01*
X1721308Y95425D01*
X1721683Y95550D01*
X1722058Y95508D01*
X1722433Y95342D01*
G01X1720000Y95550D02*
X1719417Y93050D01*
X1718750Y95550D01*
X1718083Y93050D01*
X1717500Y95550D01*
G01X1716442Y94092D02*
X1716150Y94383D01*
X1715900Y94550D01*
X1715567Y94633D01*
X1715275Y94550D01*
X1715067Y94383D01*
X1714900Y94133D01*
X1714858Y93842D01*
X1714900Y93592D01*
X1715067Y93342D01*
X1715317Y93133D01*
X1715608Y93050D01*
X1715942Y93133D01*
X1716233Y93383D01*
X1716400Y93758D01*
X1716442Y94175D01*
X1716358Y94717D01*
X1716233Y95008D01*
X1716025Y95300D01*
X1715733Y95508D01*
X1715442Y95550D01*
X1715150Y95467D01*
X1714942Y95258D01*
G01X1757883Y47192D02*
X1758133Y47317D01*
X1758425Y47400D01*
X1758758D01*
X1759133Y47275D01*
X1759425Y47067D01*
X1759633Y46817D01*
X1759800Y46400D01*
X1759842Y46025D01*
X1759758Y45650D01*
X1759633Y45400D01*
X1759383Y45150D01*
X1759092Y44983D01*
X1758800Y44900D01*
X1758508D01*
X1758217Y44983D01*
X1757967Y45108D01*
X1757758Y45275D01*
G01X1755700Y44900D02*
Y47400D01*
X1756200Y46900D01*
G01Y44900D02*
X1755200D01*
G01X1753517Y47400D02*
Y45608D01*
X1753350Y45233D01*
X1753017Y44983D01*
X1752600Y44900D01*
X1752183Y44983D01*
X1751850Y45233D01*
X1751683Y45608D01*
Y47400D01*
G01X1750292Y46983D02*
X1750042Y47233D01*
X1749750Y47358D01*
X1749417Y47400D01*
X1749000Y47317D01*
X1748708Y47108D01*
X1748625Y46858D01*
X1748667Y46608D01*
X1748833Y46400D01*
X1749667Y45983D01*
X1750042Y45692D01*
X1750292Y45275D01*
X1750375Y44900D01*
X1748625D01*
G01X1747192Y46983D02*
X1746942Y47233D01*
X1746650Y47358D01*
X1746317Y47400D01*
X1745900Y47317D01*
X1745608Y47108D01*
X1745525Y46858D01*
X1745567Y46608D01*
X1745733Y46400D01*
X1746567Y45983D01*
X1746942Y45692D01*
X1747192Y45275D01*
X1747275Y44900D01*
X1745525D01*
G01X1731283Y36192D02*
X1731533Y36317D01*
X1731825Y36400D01*
X1732158D01*
X1732533Y36275D01*
X1732825Y36067D01*
X1733033Y35817D01*
X1733200Y35400D01*
X1733242Y35025D01*
X1733158Y34650D01*
X1733033Y34400D01*
X1732783Y34150D01*
X1732492Y33983D01*
X1732200Y33900D01*
X1731908D01*
X1731617Y33983D01*
X1731367Y34108D01*
X1731158Y34275D01*
G01X1729100Y33900D02*
Y36400D01*
X1729600Y35900D01*
G01Y33900D02*
X1728600D01*
G01X1726917Y36400D02*
Y34608D01*
X1726750Y34233D01*
X1726417Y33983D01*
X1726000Y33900D01*
X1725583Y33983D01*
X1725250Y34233D01*
X1725083Y34608D01*
Y36400D01*
G01X1722900Y33900D02*
Y36400D01*
X1723400Y35900D01*
G01Y33900D02*
X1722400D01*
G01X1720508Y34192D02*
X1720217Y33983D01*
X1719883Y33900D01*
X1719550Y33983D01*
X1719258Y34233D01*
X1719050Y34608D01*
X1718967Y34983D01*
Y35442D01*
X1719050Y35817D01*
X1719258Y36150D01*
X1719508Y36317D01*
X1719800Y36400D01*
X1720133Y36317D01*
X1720383Y36150D01*
X1720550Y35900D01*
X1720633Y35567D01*
X1720550Y35275D01*
X1720342Y34983D01*
X1720092Y34817D01*
X1719800Y34775D01*
X1719467Y34858D01*
X1719217Y35067D01*
X1718967Y35442D01*
G01X1716250Y65200D02*
Y60750D01*
X1713750D01*
Y65200D01*
G01X1767486Y57138D02*
X1771075D01*
Y55245D01*
X1774354Y57138D01*
X1771075Y59031D01*
Y57138D01*
G01X1767300Y45050D02*
X1764650D01*
Y41600D01*
G01X1776550D02*
Y45050D01*
X1773900D01*
G01X1739900Y72450D02*
X1736650D01*
Y75950D01*
G01X1739900Y84450D02*
X1736650D01*
Y80950D01*
G01X1742150Y79700D02*
Y77200D01*
G01X1772000Y79250D02*
Y82500D01*
X1775500D01*
G01X1724250Y73800D02*
X1724583Y73842D01*
X1724875Y74008D01*
X1725125Y74258D01*
X1725292Y74550D01*
X1725375Y74883D01*
Y75217D01*
X1725292Y75550D01*
X1725125Y75842D01*
X1724875Y76092D01*
X1724583Y76258D01*
X1724250Y76300D01*
X1723917Y76258D01*
X1723625Y76092D01*
X1723375Y75842D01*
X1723208Y75550D01*
X1723125Y75217D01*
Y74883D01*
X1723208Y74550D01*
X1723375Y74258D01*
X1723625Y74008D01*
X1723917Y73842D01*
X1724250Y73800D01*
G01X1723917Y74467D02*
X1723417Y73800D01*
G01X1721858Y74092D02*
X1721567Y73883D01*
X1721233Y73800D01*
X1720900Y73883D01*
X1720608Y74133D01*
X1720400Y74508D01*
X1720317Y74883D01*
Y75342D01*
X1720400Y75717D01*
X1720608Y76050D01*
X1720858Y76217D01*
X1721150Y76300D01*
X1721483Y76217D01*
X1721733Y76050D01*
X1721900Y75800D01*
X1721983Y75467D01*
X1721900Y75175D01*
X1721692Y74883D01*
X1721442Y74717D01*
X1721150Y74675D01*
X1720817Y74758D01*
X1720567Y74967D01*
X1720317Y75342D01*
G01X1719300Y76300D02*
X1718717Y73800D01*
X1718050Y76300D01*
X1717383Y73800D01*
X1716800Y76300D01*
G01X1715867Y74300D02*
X1715617Y74008D01*
X1715283Y73842D01*
X1714908Y73800D01*
X1714575Y73842D01*
X1714242Y74050D01*
X1714033Y74300D01*
X1713992Y74550D01*
X1714075Y74842D01*
X1714367Y75050D01*
X1714658Y75133D01*
X1715033D01*
G01X1714658D02*
X1714408Y75258D01*
X1714200Y75467D01*
X1714117Y75717D01*
X1714200Y75967D01*
X1714408Y76175D01*
X1714783Y76300D01*
X1715158Y76258D01*
X1715533Y76092D01*
G01X1721000Y81000D02*
X1718500D01*
G01X1725750Y83250D02*
Y86500D01*
X1722250D01*
G01X1713750Y83250D02*
Y86500D01*
X1717250D01*
G01X1759633Y51900D02*
Y54400D01*
X1758592D01*
X1758258Y54275D01*
X1758050Y54108D01*
X1757967Y53775D01*
X1758050Y53442D01*
X1758300Y53233D01*
X1758592Y53108D01*
X1759633D01*
G01X1758592D02*
X1757967Y51900D01*
G01X1755700D02*
Y54400D01*
X1756200Y53900D01*
G01Y51900D02*
X1755200D01*
G01X1753517Y54400D02*
Y52608D01*
X1753350Y52233D01*
X1753017Y51983D01*
X1752600Y51900D01*
X1752183Y51983D01*
X1751850Y52233D01*
X1751683Y52608D01*
Y54400D01*
G01X1749000Y51900D02*
Y54400D01*
X1750542Y52608D01*
X1748458D01*
G01X1747317Y52400D02*
X1747067Y52108D01*
X1746733Y51942D01*
X1746358Y51900D01*
X1746025Y51942D01*
X1745692Y52150D01*
X1745483Y52400D01*
X1745442Y52650D01*
X1745525Y52942D01*
X1745817Y53150D01*
X1746108Y53233D01*
X1746483D01*
G01X1746108D02*
X1745858Y53358D01*
X1745650Y53567D01*
X1745567Y53817D01*
X1745650Y54067D01*
X1745858Y54275D01*
X1746233Y54400D01*
X1746608Y54358D01*
X1746983Y54192D01*
G01X1746500Y63300D02*
Y59300D01*
X1739100D01*
G01X1740200Y85950D02*
Y89950D01*
X1747600D01*
G01X1754750Y69500D02*
X1755083Y69542D01*
X1755375Y69708D01*
X1755625Y69958D01*
X1755792Y70250D01*
X1755875Y70583D01*
Y70917D01*
X1755792Y71250D01*
X1755625Y71542D01*
X1755375Y71792D01*
X1755083Y71958D01*
X1754750Y72000D01*
X1754417Y71958D01*
X1754125Y71792D01*
X1753875Y71542D01*
X1753708Y71250D01*
X1753625Y70917D01*
Y70583D01*
X1753708Y70250D01*
X1753875Y69958D01*
X1754125Y69708D01*
X1754417Y69542D01*
X1754750Y69500D01*
G01X1754417Y70167D02*
X1753917Y69500D01*
G01X1752358Y69792D02*
X1752067Y69583D01*
X1751733Y69500D01*
X1751400Y69583D01*
X1751108Y69833D01*
X1750900Y70208D01*
X1750817Y70583D01*
Y71042D01*
X1750900Y71417D01*
X1751108Y71750D01*
X1751358Y71917D01*
X1751650Y72000D01*
X1751983Y71917D01*
X1752233Y71750D01*
X1752400Y71500D01*
X1752483Y71167D01*
X1752400Y70875D01*
X1752192Y70583D01*
X1751942Y70417D01*
X1751650Y70375D01*
X1751317Y70458D01*
X1751067Y70667D01*
X1750817Y71042D01*
G01X1749800Y72000D02*
X1749217Y69500D01*
X1748550Y72000D01*
X1747883Y69500D01*
X1747300Y72000D01*
G01X1744950Y69500D02*
Y72000D01*
X1746492Y70208D01*
X1744408D01*
G01X1766700Y73500D02*
Y83500D01*
G01D02*
X1753300D01*
G01D02*
Y73500D01*
G01D02*
X1766700D01*
G01X1750600Y149200D02*
X1761600D01*
Y148500D01*
G01X1758900Y150600D02*
X1760400Y152100D01*
X1757400D01*
X1758900Y150600D01*
G01X1735100Y97200D02*
X1748000D01*
Y96300D01*
X1750300D01*
G01X1724800Y113500D02*
X1728100D01*
Y96010D01*
X1734430D01*
G01X1750600Y136700D02*
Y149200D01*
G01X1810100Y195900D02*
X1811270D01*
Y174250D01*
X1791140D01*
Y157280D01*
X1785610D01*
Y153900D01*
X1758900D01*
Y150800D01*
G01X1753000Y125400D02*
X1750600D01*
Y134400D01*
G01X1761600Y129000D02*
Y125400D01*
X1754500D01*
G01X1761600Y133500D02*
Y130500D01*
G01Y138000D02*
Y135000D01*
G01Y142500D02*
Y139500D01*
G01Y147000D02*
Y144000D01*
G01X1762983Y101100D02*
Y103600D01*
X1761942D01*
X1761608Y103475D01*
X1761400Y103308D01*
X1761317Y102975D01*
X1761400Y102642D01*
X1761650Y102433D01*
X1761942Y102308D01*
X1762983D01*
G01X1761942D02*
X1761317Y101100D01*
G01X1759842Y102142D02*
X1759550Y102433D01*
X1759300Y102600D01*
X1758967Y102683D01*
X1758675Y102600D01*
X1758467Y102433D01*
X1758300Y102183D01*
X1758258Y101892D01*
X1758300Y101642D01*
X1758467Y101392D01*
X1758717Y101183D01*
X1759008Y101100D01*
X1759342Y101183D01*
X1759633Y101433D01*
X1759800Y101808D01*
X1759842Y102225D01*
X1759758Y102767D01*
X1759633Y103058D01*
X1759425Y103350D01*
X1759133Y103558D01*
X1758842Y103600D01*
X1758550Y103517D01*
X1758342Y103308D01*
G01X1757200Y103600D02*
X1756617Y101100D01*
X1755950Y103600D01*
X1755283Y101100D01*
X1754700Y103600D01*
G01X1753642Y103183D02*
X1753392Y103433D01*
X1753100Y103558D01*
X1752767Y103600D01*
X1752350Y103517D01*
X1752058Y103308D01*
X1751975Y103058D01*
X1752017Y102808D01*
X1752183Y102600D01*
X1753017Y102183D01*
X1753392Y101892D01*
X1753642Y101475D01*
X1753725Y101100D01*
X1751975D01*
G01X1750542Y103183D02*
X1750292Y103433D01*
X1750000Y103558D01*
X1749667Y103600D01*
X1749250Y103517D01*
X1748958Y103308D01*
X1748875Y103058D01*
X1748917Y102808D01*
X1749083Y102600D01*
X1749917Y102183D01*
X1750292Y101892D01*
X1750542Y101475D01*
X1750625Y101100D01*
X1748875D01*
G01X1762983Y97600D02*
Y100100D01*
X1761942D01*
X1761608Y99975D01*
X1761400Y99808D01*
X1761317Y99475D01*
X1761400Y99142D01*
X1761650Y98933D01*
X1761942Y98808D01*
X1762983D01*
G01X1761942D02*
X1761317Y97600D01*
G01X1759842Y98642D02*
X1759550Y98933D01*
X1759300Y99100D01*
X1758967Y99183D01*
X1758675Y99100D01*
X1758467Y98933D01*
X1758300Y98683D01*
X1758258Y98392D01*
X1758300Y98142D01*
X1758467Y97892D01*
X1758717Y97683D01*
X1759008Y97600D01*
X1759342Y97683D01*
X1759633Y97933D01*
X1759800Y98308D01*
X1759842Y98725D01*
X1759758Y99267D01*
X1759633Y99558D01*
X1759425Y99850D01*
X1759133Y100058D01*
X1758842Y100100D01*
X1758550Y100017D01*
X1758342Y99808D01*
G01X1757200Y100100D02*
X1756617Y97600D01*
X1755950Y100100D01*
X1755283Y97600D01*
X1754700Y100100D01*
G01X1753642Y99683D02*
X1753392Y99933D01*
X1753100Y100058D01*
X1752767Y100100D01*
X1752350Y100017D01*
X1752058Y99808D01*
X1751975Y99558D01*
X1752017Y99308D01*
X1752183Y99100D01*
X1753017Y98683D01*
X1753392Y98392D01*
X1753642Y97975D01*
X1753725Y97600D01*
X1751975D01*
G01X1749750Y100100D02*
X1750083Y100017D01*
X1750333Y99808D01*
X1750500Y99558D01*
X1750625Y99225D01*
X1750667Y98850D01*
X1750625Y98475D01*
X1750500Y98142D01*
X1750333Y97892D01*
X1750083Y97683D01*
X1749750Y97600D01*
X1749417Y97683D01*
X1749167Y97892D01*
X1749000Y98142D01*
X1748875Y98475D01*
X1748833Y98850D01*
X1748875Y99225D01*
X1749000Y99558D01*
X1749167Y99808D01*
X1749417Y100017D01*
X1749750Y100100D01*
G01X1762983Y104600D02*
Y107100D01*
X1761942D01*
X1761608Y106975D01*
X1761400Y106808D01*
X1761317Y106475D01*
X1761400Y106142D01*
X1761650Y105933D01*
X1761942Y105808D01*
X1762983D01*
G01X1761942D02*
X1761317Y104600D01*
G01X1759842Y105642D02*
X1759550Y105933D01*
X1759300Y106100D01*
X1758967Y106183D01*
X1758675Y106100D01*
X1758467Y105933D01*
X1758300Y105683D01*
X1758258Y105392D01*
X1758300Y105142D01*
X1758467Y104892D01*
X1758717Y104683D01*
X1759008Y104600D01*
X1759342Y104683D01*
X1759633Y104933D01*
X1759800Y105308D01*
X1759842Y105725D01*
X1759758Y106267D01*
X1759633Y106558D01*
X1759425Y106850D01*
X1759133Y107058D01*
X1758842Y107100D01*
X1758550Y107017D01*
X1758342Y106808D01*
G01X1757200Y107100D02*
X1756617Y104600D01*
X1755950Y107100D01*
X1755283Y104600D01*
X1754700Y107100D01*
G01X1753642Y106683D02*
X1753392Y106933D01*
X1753100Y107058D01*
X1752767Y107100D01*
X1752350Y107017D01*
X1752058Y106808D01*
X1751975Y106558D01*
X1752017Y106308D01*
X1752183Y106100D01*
X1753017Y105683D01*
X1753392Y105392D01*
X1753642Y104975D01*
X1753725Y104600D01*
X1751975D01*
G01X1750667Y105100D02*
X1750417Y104808D01*
X1750083Y104642D01*
X1749708Y104600D01*
X1749375Y104642D01*
X1749042Y104850D01*
X1748833Y105100D01*
X1748792Y105350D01*
X1748875Y105642D01*
X1749167Y105850D01*
X1749458Y105933D01*
X1749833D01*
G01X1749458D02*
X1749208Y106058D01*
X1749000Y106267D01*
X1748917Y106517D01*
X1749000Y106767D01*
X1749208Y106975D01*
X1749583Y107100D01*
X1749958Y107058D01*
X1750333Y106892D01*
G01X1745483Y153550D02*
Y156050D01*
X1744442D01*
X1744108Y155925D01*
X1743900Y155758D01*
X1743817Y155425D01*
X1743900Y155092D01*
X1744150Y154883D01*
X1744442Y154758D01*
X1745483D01*
G01X1744442D02*
X1743817Y153550D01*
G01X1742342Y155633D02*
X1742092Y155883D01*
X1741800Y156008D01*
X1741467Y156050D01*
X1741050Y155967D01*
X1740758Y155758D01*
X1740675Y155508D01*
X1740717Y155258D01*
X1740883Y155050D01*
X1741717Y154633D01*
X1742092Y154342D01*
X1742342Y153925D01*
X1742425Y153550D01*
X1740675D01*
G01X1739367Y153925D02*
X1739117Y153717D01*
X1738825Y153592D01*
X1738450Y153550D01*
X1738075Y153633D01*
X1737783Y153800D01*
X1737575Y154092D01*
X1737533Y154425D01*
X1737617Y154758D01*
X1737825Y154967D01*
X1738117Y155133D01*
X1738408Y155175D01*
X1738700Y155133D01*
X1739075Y154967D01*
X1738950Y156050D01*
X1737825D01*
G01X1736600D02*
X1736017Y153550D01*
X1735350Y156050D01*
X1734683Y153550D01*
X1734100Y156050D01*
G01X1732250Y153550D02*
Y156050D01*
X1732750Y155550D01*
G01Y153550D02*
X1731750D01*
G01X1729150D02*
Y156050D01*
X1729650Y155550D01*
G01Y153550D02*
X1728650D01*
G01X1726050D02*
X1725758Y153592D01*
X1725425Y153717D01*
X1725217Y153925D01*
X1725133Y154217D01*
X1725217Y154508D01*
X1725467Y154758D01*
X1725842Y154883D01*
X1726258D01*
X1726508Y154967D01*
X1726717Y155175D01*
X1726800Y155467D01*
X1726675Y155758D01*
X1726383Y155967D01*
X1726050Y156050D01*
X1725717Y155967D01*
X1725425Y155758D01*
X1725300Y155467D01*
X1725383Y155175D01*
X1725592Y154967D01*
X1725842Y154883D01*
X1726258D01*
X1726633Y154758D01*
X1726883Y154508D01*
X1726967Y154217D01*
X1726883Y153925D01*
X1726675Y153717D01*
X1726342Y153592D01*
X1726050Y153550D01*
G01X1746433Y145400D02*
Y147900D01*
X1745392D01*
X1745058Y147775D01*
X1744850Y147608D01*
X1744767Y147275D01*
X1744850Y146942D01*
X1745100Y146733D01*
X1745392Y146608D01*
X1746433D01*
G01X1745392D02*
X1744767Y145400D01*
G01X1743292Y147483D02*
X1743042Y147733D01*
X1742750Y147858D01*
X1742417Y147900D01*
X1742000Y147817D01*
X1741708Y147608D01*
X1741625Y147358D01*
X1741667Y147108D01*
X1741833Y146900D01*
X1742667Y146483D01*
X1743042Y146192D01*
X1743292Y145775D01*
X1743375Y145400D01*
X1741625D01*
G01X1740317Y145775D02*
X1740067Y145567D01*
X1739775Y145442D01*
X1739400Y145400D01*
X1739025Y145483D01*
X1738733Y145650D01*
X1738525Y145942D01*
X1738483Y146275D01*
X1738567Y146608D01*
X1738775Y146817D01*
X1739067Y146983D01*
X1739358Y147025D01*
X1739650Y146983D01*
X1740025Y146817D01*
X1739900Y147900D01*
X1738775D01*
G01X1737550D02*
X1736967Y145400D01*
X1736300Y147900D01*
X1735633Y145400D01*
X1735050Y147900D01*
G01X1733200Y145400D02*
Y147900D01*
X1733700Y147400D01*
G01Y145400D02*
X1732700D01*
G01X1730100D02*
Y147900D01*
X1730600Y147400D01*
G01Y145400D02*
X1729600D01*
G01X1727708Y145692D02*
X1727417Y145483D01*
X1727083Y145400D01*
X1726750Y145483D01*
X1726458Y145733D01*
X1726250Y146108D01*
X1726167Y146483D01*
Y146942D01*
X1726250Y147317D01*
X1726458Y147650D01*
X1726708Y147817D01*
X1727000Y147900D01*
X1727333Y147817D01*
X1727583Y147650D01*
X1727750Y147400D01*
X1727833Y147067D01*
X1727750Y146775D01*
X1727542Y146483D01*
X1727292Y146317D01*
X1727000Y146275D01*
X1726667Y146358D01*
X1726417Y146567D01*
X1726167Y146942D01*
G01X1737500Y104117D02*
X1740000D01*
Y105158D01*
X1739875Y105492D01*
X1739708Y105700D01*
X1739375Y105783D01*
X1739042Y105700D01*
X1738833Y105450D01*
X1738708Y105158D01*
Y104117D01*
G01Y105158D02*
X1737500Y105783D01*
G01Y108050D02*
X1740000D01*
X1739500Y107550D01*
G01X1737500D02*
Y108550D01*
G01X1740000Y111150D02*
X1737500D01*
G01X1740000Y110192D02*
Y112108D01*
G01X1739583Y113458D02*
X1739833Y113708D01*
X1739958Y114000D01*
X1740000Y114333D01*
X1739917Y114750D01*
X1739708Y115042D01*
X1739458Y115125D01*
X1739208Y115083D01*
X1739000Y114917D01*
X1738583Y114083D01*
X1738292Y113708D01*
X1737875Y113458D01*
X1737500Y113375D01*
Y115125D01*
G01X1737792Y116642D02*
X1737583Y116933D01*
X1737500Y117267D01*
X1737583Y117600D01*
X1737833Y117892D01*
X1738208Y118100D01*
X1738583Y118183D01*
X1739042D01*
X1739417Y118100D01*
X1739750Y117892D01*
X1739917Y117642D01*
X1740000Y117350D01*
X1739917Y117017D01*
X1739750Y116767D01*
X1739500Y116600D01*
X1739167Y116517D01*
X1738875Y116600D01*
X1738583Y116808D01*
X1738417Y117058D01*
X1738375Y117350D01*
X1738458Y117683D01*
X1738667Y117933D01*
X1739042Y118183D01*
G01X1769733Y122200D02*
Y124700D01*
X1768692D01*
X1768358Y124575D01*
X1768150Y124408D01*
X1768067Y124075D01*
X1768150Y123742D01*
X1768400Y123533D01*
X1768692Y123408D01*
X1769733D01*
G01X1768692D02*
X1768067Y122200D01*
G01X1765800D02*
Y124700D01*
X1766300Y124200D01*
G01Y122200D02*
X1765300D01*
G01X1762700Y124700D02*
Y122200D01*
G01X1763658Y124700D02*
X1761742D01*
G01X1760517Y122700D02*
X1760267Y122408D01*
X1759933Y122242D01*
X1759558Y122200D01*
X1759225Y122242D01*
X1758892Y122450D01*
X1758683Y122700D01*
X1758642Y122950D01*
X1758725Y123242D01*
X1759017Y123450D01*
X1759308Y123533D01*
X1759683D01*
G01X1759308D02*
X1759058Y123658D01*
X1758850Y123867D01*
X1758767Y124117D01*
X1758850Y124367D01*
X1759058Y124575D01*
X1759433Y124700D01*
X1759808Y124658D01*
X1760183Y124492D01*
G01X1756500Y124700D02*
X1756833Y124617D01*
X1757083Y124408D01*
X1757250Y124158D01*
X1757375Y123825D01*
X1757417Y123450D01*
X1757375Y123075D01*
X1757250Y122742D01*
X1757083Y122492D01*
X1756833Y122283D01*
X1756500Y122200D01*
X1756167Y122283D01*
X1755917Y122492D01*
X1755750Y122742D01*
X1755625Y123075D01*
X1755583Y123450D01*
X1755625Y123825D01*
X1755750Y124158D01*
X1755917Y124408D01*
X1756167Y124617D01*
X1756500Y124700D01*
G01X1774833Y108892D02*
X1775083Y109017D01*
X1775375Y109100D01*
X1775708D01*
X1776083Y108975D01*
X1776375Y108767D01*
X1776583Y108517D01*
X1776750Y108100D01*
X1776792Y107725D01*
X1776708Y107350D01*
X1776583Y107100D01*
X1776333Y106850D01*
X1776042Y106683D01*
X1775750Y106600D01*
X1775458D01*
X1775167Y106683D01*
X1774917Y106808D01*
X1774708Y106975D01*
G01X1773442Y107642D02*
X1773150Y107933D01*
X1772900Y108100D01*
X1772567Y108183D01*
X1772275Y108100D01*
X1772067Y107933D01*
X1771900Y107683D01*
X1771858Y107392D01*
X1771900Y107142D01*
X1772067Y106892D01*
X1772317Y106683D01*
X1772608Y106600D01*
X1772942Y106683D01*
X1773233Y106933D01*
X1773400Y107308D01*
X1773442Y107725D01*
X1773358Y108267D01*
X1773233Y108558D01*
X1773025Y108850D01*
X1772733Y109058D01*
X1772442Y109100D01*
X1772150Y109017D01*
X1771942Y108808D01*
G01X1770800Y109100D02*
X1770217Y106600D01*
X1769550Y109100D01*
X1768883Y106600D01*
X1768300Y109100D01*
G01X1767367Y107100D02*
X1767117Y106808D01*
X1766783Y106642D01*
X1766408Y106600D01*
X1766075Y106642D01*
X1765742Y106850D01*
X1765533Y107100D01*
X1765492Y107350D01*
X1765575Y107642D01*
X1765867Y107850D01*
X1766158Y107933D01*
X1766533D01*
G01X1766158D02*
X1765908Y108058D01*
X1765700Y108267D01*
X1765617Y108517D01*
X1765700Y108767D01*
X1765908Y108975D01*
X1766283Y109100D01*
X1766658Y109058D01*
X1767033Y108892D01*
G01X1737492Y128167D02*
X1737617Y127917D01*
X1737700Y127625D01*
Y127292D01*
X1737575Y126917D01*
X1737367Y126625D01*
X1737117Y126417D01*
X1736700Y126250D01*
X1736325Y126208D01*
X1735950Y126292D01*
X1735700Y126417D01*
X1735450Y126667D01*
X1735283Y126958D01*
X1735200Y127250D01*
Y127542D01*
X1735283Y127833D01*
X1735408Y128083D01*
X1735575Y128292D01*
G01X1735200Y130350D02*
X1737700D01*
X1737200Y129850D01*
G01X1735200D02*
Y130850D01*
G01X1737700Y132200D02*
X1735200Y132783D01*
X1737700Y133450D01*
X1735200Y134117D01*
X1737700Y134700D01*
G01X1737283Y135758D02*
X1737533Y136008D01*
X1737658Y136300D01*
X1737700Y136633D01*
X1737617Y137050D01*
X1737408Y137342D01*
X1737158Y137425D01*
X1736908Y137383D01*
X1736700Y137217D01*
X1736283Y136383D01*
X1735992Y136008D01*
X1735575Y135758D01*
X1735200Y135675D01*
Y137425D01*
G01X1737700Y139650D02*
X1737617Y139317D01*
X1737408Y139067D01*
X1737158Y138900D01*
X1736825Y138775D01*
X1736450Y138733D01*
X1736075Y138775D01*
X1735742Y138900D01*
X1735492Y139067D01*
X1735283Y139317D01*
X1735200Y139650D01*
X1735283Y139983D01*
X1735492Y140233D01*
X1735742Y140400D01*
X1736075Y140525D01*
X1736450Y140567D01*
X1736825Y140525D01*
X1737158Y140400D01*
X1737408Y140233D01*
X1737617Y139983D01*
X1737700Y139650D01*
G01X1732792Y105867D02*
X1732917Y105617D01*
X1733000Y105325D01*
Y104992D01*
X1732875Y104617D01*
X1732667Y104325D01*
X1732417Y104117D01*
X1732000Y103950D01*
X1731625Y103908D01*
X1731250Y103992D01*
X1731000Y104117D01*
X1730750Y104367D01*
X1730583Y104658D01*
X1730500Y104950D01*
Y105242D01*
X1730583Y105533D01*
X1730708Y105783D01*
X1730875Y105992D01*
G01X1732583Y107258D02*
X1732833Y107508D01*
X1732958Y107800D01*
X1733000Y108133D01*
X1732917Y108550D01*
X1732708Y108842D01*
X1732458Y108925D01*
X1732208Y108883D01*
X1732000Y108717D01*
X1731583Y107883D01*
X1731292Y107508D01*
X1730875Y107258D01*
X1730500Y107175D01*
Y108925D01*
G01X1730875Y110233D02*
X1730667Y110483D01*
X1730542Y110775D01*
X1730500Y111150D01*
X1730583Y111525D01*
X1730750Y111817D01*
X1731042Y112025D01*
X1731375Y112067D01*
X1731708Y111983D01*
X1731917Y111775D01*
X1732083Y111483D01*
X1732125Y111192D01*
X1732083Y110900D01*
X1731917Y110525D01*
X1733000Y110650D01*
Y111775D01*
G01Y113000D02*
X1730500Y113583D01*
X1733000Y114250D01*
X1730500Y114917D01*
X1733000Y115500D01*
G01X1730500Y117350D02*
X1733000D01*
X1732500Y116850D01*
G01X1730500D02*
Y117850D01*
G01X1731000Y119533D02*
X1730708Y119783D01*
X1730542Y120117D01*
X1730500Y120492D01*
X1730542Y120825D01*
X1730750Y121158D01*
X1731000Y121367D01*
X1731250Y121408D01*
X1731542Y121325D01*
X1731750Y121033D01*
X1731833Y120742D01*
Y120367D01*
G01Y120742D02*
X1731958Y120992D01*
X1732167Y121200D01*
X1732417Y121283D01*
X1732667Y121200D01*
X1732875Y120992D01*
X1733000Y120617D01*
X1732958Y120242D01*
X1732792Y119867D01*
G01X1736292Y105867D02*
X1736417Y105617D01*
X1736500Y105325D01*
Y104992D01*
X1736375Y104617D01*
X1736167Y104325D01*
X1735917Y104117D01*
X1735500Y103950D01*
X1735125Y103908D01*
X1734750Y103992D01*
X1734500Y104117D01*
X1734250Y104367D01*
X1734083Y104658D01*
X1734000Y104950D01*
Y105242D01*
X1734083Y105533D01*
X1734208Y105783D01*
X1734375Y105992D01*
G01X1736083Y107258D02*
X1736333Y107508D01*
X1736458Y107800D01*
X1736500Y108133D01*
X1736417Y108550D01*
X1736208Y108842D01*
X1735958Y108925D01*
X1735708Y108883D01*
X1735500Y108717D01*
X1735083Y107883D01*
X1734792Y107508D01*
X1734375Y107258D01*
X1734000Y107175D01*
Y108925D01*
G01X1734375Y110233D02*
X1734167Y110483D01*
X1734042Y110775D01*
X1734000Y111150D01*
X1734083Y111525D01*
X1734250Y111817D01*
X1734542Y112025D01*
X1734875Y112067D01*
X1735208Y111983D01*
X1735417Y111775D01*
X1735583Y111483D01*
X1735625Y111192D01*
X1735583Y110900D01*
X1735417Y110525D01*
X1736500Y110650D01*
Y111775D01*
G01Y113000D02*
X1734000Y113583D01*
X1736500Y114250D01*
X1734000Y114917D01*
X1736500Y115500D01*
G01X1734000Y117350D02*
X1736500D01*
X1736000Y116850D01*
G01X1734000D02*
Y117850D01*
G01X1736083Y119658D02*
X1736333Y119908D01*
X1736458Y120200D01*
X1736500Y120533D01*
X1736417Y120950D01*
X1736208Y121242D01*
X1735958Y121325D01*
X1735708Y121283D01*
X1735500Y121117D01*
X1735083Y120283D01*
X1734792Y119908D01*
X1734375Y119658D01*
X1734000Y119575D01*
Y121325D01*
G01X1743292Y105867D02*
X1743417Y105617D01*
X1743500Y105325D01*
Y104992D01*
X1743375Y104617D01*
X1743167Y104325D01*
X1742917Y104117D01*
X1742500Y103950D01*
X1742125Y103908D01*
X1741750Y103992D01*
X1741500Y104117D01*
X1741250Y104367D01*
X1741083Y104658D01*
X1741000Y104950D01*
Y105242D01*
X1741083Y105533D01*
X1741208Y105783D01*
X1741375Y105992D01*
G01X1743083Y107258D02*
X1743333Y107508D01*
X1743458Y107800D01*
X1743500Y108133D01*
X1743417Y108550D01*
X1743208Y108842D01*
X1742958Y108925D01*
X1742708Y108883D01*
X1742500Y108717D01*
X1742083Y107883D01*
X1741792Y107508D01*
X1741375Y107258D01*
X1741000Y107175D01*
Y108925D01*
G01X1741375Y110233D02*
X1741167Y110483D01*
X1741042Y110775D01*
X1741000Y111150D01*
X1741083Y111525D01*
X1741250Y111817D01*
X1741542Y112025D01*
X1741875Y112067D01*
X1742208Y111983D01*
X1742417Y111775D01*
X1742583Y111483D01*
X1742625Y111192D01*
X1742583Y110900D01*
X1742417Y110525D01*
X1743500Y110650D01*
Y111775D01*
G01Y113000D02*
X1741000Y113583D01*
X1743500Y114250D01*
X1741000Y114917D01*
X1743500Y115500D01*
G01X1741000Y117350D02*
X1743500D01*
X1743000Y116850D01*
G01X1741000D02*
Y117850D01*
G01Y120450D02*
X1743500D01*
X1743000Y119950D01*
G01X1741000D02*
Y120950D01*
G01X1767983Y120992D02*
X1768233Y121117D01*
X1768525Y121200D01*
X1768858D01*
X1769233Y121075D01*
X1769525Y120867D01*
X1769733Y120617D01*
X1769900Y120200D01*
X1769942Y119825D01*
X1769858Y119450D01*
X1769733Y119200D01*
X1769483Y118950D01*
X1769192Y118783D01*
X1768900Y118700D01*
X1768608D01*
X1768317Y118783D01*
X1768067Y118908D01*
X1767858Y119075D01*
G01X1766592Y120783D02*
X1766342Y121033D01*
X1766050Y121158D01*
X1765717Y121200D01*
X1765300Y121117D01*
X1765008Y120908D01*
X1764925Y120658D01*
X1764967Y120408D01*
X1765133Y120200D01*
X1765967Y119783D01*
X1766342Y119492D01*
X1766592Y119075D01*
X1766675Y118700D01*
X1764925D01*
G01X1763617Y119075D02*
X1763367Y118867D01*
X1763075Y118742D01*
X1762700Y118700D01*
X1762325Y118783D01*
X1762033Y118950D01*
X1761825Y119242D01*
X1761783Y119575D01*
X1761867Y119908D01*
X1762075Y120117D01*
X1762367Y120283D01*
X1762658Y120325D01*
X1762950Y120283D01*
X1763325Y120117D01*
X1763200Y121200D01*
X1762075D01*
G01X1760850D02*
X1760267Y118700D01*
X1759600Y121200D01*
X1758933Y118700D01*
X1758350Y121200D01*
G01X1756500Y118700D02*
Y121200D01*
X1757000Y120700D01*
G01Y118700D02*
X1756000D01*
G01X1753400Y121200D02*
X1753733Y121117D01*
X1753983Y120908D01*
X1754150Y120658D01*
X1754275Y120325D01*
X1754317Y119950D01*
X1754275Y119575D01*
X1754150Y119242D01*
X1753983Y118992D01*
X1753733Y118783D01*
X1753400Y118700D01*
X1753067Y118783D01*
X1752817Y118992D01*
X1752650Y119242D01*
X1752525Y119575D01*
X1752483Y119950D01*
X1752525Y120325D01*
X1752650Y120658D01*
X1752817Y120908D01*
X1753067Y121117D01*
X1753400Y121200D01*
G01X1753708Y130250D02*
Y134250D01*
X1761108D01*
G01X1753708Y125750D02*
Y129750D01*
X1761108D01*
G01X1753708Y139250D02*
Y143250D01*
X1761108D01*
G01X1753708Y134750D02*
Y138750D01*
X1761108D01*
G01X1787683Y135600D02*
Y138100D01*
X1786642D01*
X1786308Y137975D01*
X1786100Y137808D01*
X1786017Y137475D01*
X1786100Y137142D01*
X1786350Y136933D01*
X1786642Y136808D01*
X1787683D01*
G01X1786642D02*
X1786017Y135600D01*
G01X1784542Y137683D02*
X1784292Y137933D01*
X1784000Y138058D01*
X1783667Y138100D01*
X1783250Y138017D01*
X1782958Y137808D01*
X1782875Y137558D01*
X1782917Y137308D01*
X1783083Y137100D01*
X1783917Y136683D01*
X1784292Y136392D01*
X1784542Y135975D01*
X1784625Y135600D01*
X1782875D01*
G01X1781567Y135975D02*
X1781317Y135767D01*
X1781025Y135642D01*
X1780650Y135600D01*
X1780275Y135683D01*
X1779983Y135850D01*
X1779775Y136142D01*
X1779733Y136475D01*
X1779817Y136808D01*
X1780025Y137017D01*
X1780317Y137183D01*
X1780608Y137225D01*
X1780900Y137183D01*
X1781275Y137017D01*
X1781150Y138100D01*
X1780025D01*
G01X1778800D02*
X1778217Y135600D01*
X1777550Y138100D01*
X1776883Y135600D01*
X1776300Y138100D01*
G01X1775242Y137683D02*
X1774992Y137933D01*
X1774700Y138058D01*
X1774367Y138100D01*
X1773950Y138017D01*
X1773658Y137808D01*
X1773575Y137558D01*
X1773617Y137308D01*
X1773783Y137100D01*
X1774617Y136683D01*
X1774992Y136392D01*
X1775242Y135975D01*
X1775325Y135600D01*
X1773575D01*
G01X1771350D02*
X1771058Y135642D01*
X1770725Y135767D01*
X1770517Y135975D01*
X1770433Y136267D01*
X1770517Y136558D01*
X1770767Y136808D01*
X1771142Y136933D01*
X1771558D01*
X1771808Y137017D01*
X1772017Y137225D01*
X1772100Y137517D01*
X1771975Y137808D01*
X1771683Y138017D01*
X1771350Y138100D01*
X1771017Y138017D01*
X1770725Y137808D01*
X1770600Y137517D01*
X1770683Y137225D01*
X1770892Y137017D01*
X1771142Y136933D01*
X1771558D01*
X1771933Y136808D01*
X1772183Y136558D01*
X1772267Y136267D01*
X1772183Y135975D01*
X1771975Y135767D01*
X1771642Y135642D01*
X1771350Y135600D01*
G01X1762270Y130250D02*
Y134250D01*
X1769670D01*
G01X1787683Y132100D02*
Y134600D01*
X1786642D01*
X1786308Y134475D01*
X1786100Y134308D01*
X1786017Y133975D01*
X1786100Y133642D01*
X1786350Y133433D01*
X1786642Y133308D01*
X1787683D01*
G01X1786642D02*
X1786017Y132100D01*
G01X1784542Y134183D02*
X1784292Y134433D01*
X1784000Y134558D01*
X1783667Y134600D01*
X1783250Y134517D01*
X1782958Y134308D01*
X1782875Y134058D01*
X1782917Y133808D01*
X1783083Y133600D01*
X1783917Y133183D01*
X1784292Y132892D01*
X1784542Y132475D01*
X1784625Y132100D01*
X1782875D01*
G01X1781567Y132475D02*
X1781317Y132267D01*
X1781025Y132142D01*
X1780650Y132100D01*
X1780275Y132183D01*
X1779983Y132350D01*
X1779775Y132642D01*
X1779733Y132975D01*
X1779817Y133308D01*
X1780025Y133517D01*
X1780317Y133683D01*
X1780608Y133725D01*
X1780900Y133683D01*
X1781275Y133517D01*
X1781150Y134600D01*
X1780025D01*
G01X1778800D02*
X1778217Y132100D01*
X1777550Y134600D01*
X1776883Y132100D01*
X1776300Y134600D01*
G01X1775242Y134183D02*
X1774992Y134433D01*
X1774700Y134558D01*
X1774367Y134600D01*
X1773950Y134517D01*
X1773658Y134308D01*
X1773575Y134058D01*
X1773617Y133808D01*
X1773783Y133600D01*
X1774617Y133183D01*
X1774992Y132892D01*
X1775242Y132475D01*
X1775325Y132100D01*
X1773575D01*
G01X1771433D02*
X1771350Y132642D01*
X1771225Y133100D01*
X1771058Y133517D01*
X1770850Y133975D01*
X1770517Y134600D01*
X1772183D01*
G01X1762270Y125750D02*
Y129750D01*
X1769670D01*
G01X1787683Y145600D02*
Y148100D01*
X1786642D01*
X1786308Y147975D01*
X1786100Y147808D01*
X1786017Y147475D01*
X1786100Y147142D01*
X1786350Y146933D01*
X1786642Y146808D01*
X1787683D01*
G01X1786642D02*
X1786017Y145600D01*
G01X1784542Y147683D02*
X1784292Y147933D01*
X1784000Y148058D01*
X1783667Y148100D01*
X1783250Y148017D01*
X1782958Y147808D01*
X1782875Y147558D01*
X1782917Y147308D01*
X1783083Y147100D01*
X1783917Y146683D01*
X1784292Y146392D01*
X1784542Y145975D01*
X1784625Y145600D01*
X1782875D01*
G01X1781567Y145975D02*
X1781317Y145767D01*
X1781025Y145642D01*
X1780650Y145600D01*
X1780275Y145683D01*
X1779983Y145850D01*
X1779775Y146142D01*
X1779733Y146475D01*
X1779817Y146808D01*
X1780025Y147017D01*
X1780317Y147183D01*
X1780608Y147225D01*
X1780900Y147183D01*
X1781275Y147017D01*
X1781150Y148100D01*
X1780025D01*
G01X1778800D02*
X1778217Y145600D01*
X1777550Y148100D01*
X1776883Y145600D01*
X1776300Y148100D01*
G01X1775367Y146100D02*
X1775117Y145808D01*
X1774783Y145642D01*
X1774408Y145600D01*
X1774075Y145642D01*
X1773742Y145850D01*
X1773533Y146100D01*
X1773492Y146350D01*
X1773575Y146642D01*
X1773867Y146850D01*
X1774158Y146933D01*
X1774533D01*
G01X1774158D02*
X1773908Y147058D01*
X1773700Y147267D01*
X1773617Y147517D01*
X1773700Y147767D01*
X1773908Y147975D01*
X1774283Y148100D01*
X1774658Y148058D01*
X1775033Y147892D01*
G01X1772142Y147683D02*
X1771892Y147933D01*
X1771600Y148058D01*
X1771267Y148100D01*
X1770850Y148017D01*
X1770558Y147808D01*
X1770475Y147558D01*
X1770517Y147308D01*
X1770683Y147100D01*
X1771517Y146683D01*
X1771892Y146392D01*
X1772142Y145975D01*
X1772225Y145600D01*
X1770475D01*
G01X1762270Y139250D02*
Y143250D01*
X1769670D01*
G01X1787683Y142100D02*
Y144600D01*
X1786642D01*
X1786308Y144475D01*
X1786100Y144308D01*
X1786017Y143975D01*
X1786100Y143642D01*
X1786350Y143433D01*
X1786642Y143308D01*
X1787683D01*
G01X1786642D02*
X1786017Y142100D01*
G01X1784542Y144183D02*
X1784292Y144433D01*
X1784000Y144558D01*
X1783667Y144600D01*
X1783250Y144517D01*
X1782958Y144308D01*
X1782875Y144058D01*
X1782917Y143808D01*
X1783083Y143600D01*
X1783917Y143183D01*
X1784292Y142892D01*
X1784542Y142475D01*
X1784625Y142100D01*
X1782875D01*
G01X1781567Y142475D02*
X1781317Y142267D01*
X1781025Y142142D01*
X1780650Y142100D01*
X1780275Y142183D01*
X1779983Y142350D01*
X1779775Y142642D01*
X1779733Y142975D01*
X1779817Y143308D01*
X1780025Y143517D01*
X1780317Y143683D01*
X1780608Y143725D01*
X1780900Y143683D01*
X1781275Y143517D01*
X1781150Y144600D01*
X1780025D01*
G01X1778800D02*
X1778217Y142100D01*
X1777550Y144600D01*
X1776883Y142100D01*
X1776300Y144600D01*
G01X1773950Y142100D02*
Y144600D01*
X1775492Y142808D01*
X1773408D01*
G01X1771350Y142100D02*
X1771058Y142142D01*
X1770725Y142267D01*
X1770517Y142475D01*
X1770433Y142767D01*
X1770517Y143058D01*
X1770767Y143308D01*
X1771142Y143433D01*
X1771558D01*
X1771808Y143517D01*
X1772017Y143725D01*
X1772100Y144017D01*
X1771975Y144308D01*
X1771683Y144517D01*
X1771350Y144600D01*
X1771017Y144517D01*
X1770725Y144308D01*
X1770600Y144017D01*
X1770683Y143725D01*
X1770892Y143517D01*
X1771142Y143433D01*
X1771558D01*
X1771933Y143308D01*
X1772183Y143058D01*
X1772267Y142767D01*
X1772183Y142475D01*
X1771975Y142267D01*
X1771642Y142142D01*
X1771350Y142100D01*
G01X1762270Y134750D02*
Y138750D01*
X1769670D01*
G01X1753708Y143798D02*
Y147798D01*
X1761108D01*
G01X1787683Y149100D02*
Y151600D01*
X1786642D01*
X1786308Y151475D01*
X1786100Y151308D01*
X1786017Y150975D01*
X1786100Y150642D01*
X1786350Y150433D01*
X1786642Y150308D01*
X1787683D01*
G01X1786642D02*
X1786017Y149100D01*
G01X1784542Y151183D02*
X1784292Y151433D01*
X1784000Y151558D01*
X1783667Y151600D01*
X1783250Y151517D01*
X1782958Y151308D01*
X1782875Y151058D01*
X1782917Y150808D01*
X1783083Y150600D01*
X1783917Y150183D01*
X1784292Y149892D01*
X1784542Y149475D01*
X1784625Y149100D01*
X1782875D01*
G01X1781567Y149475D02*
X1781317Y149267D01*
X1781025Y149142D01*
X1780650Y149100D01*
X1780275Y149183D01*
X1779983Y149350D01*
X1779775Y149642D01*
X1779733Y149975D01*
X1779817Y150308D01*
X1780025Y150517D01*
X1780317Y150683D01*
X1780608Y150725D01*
X1780900Y150683D01*
X1781275Y150517D01*
X1781150Y151600D01*
X1780025D01*
G01X1778800D02*
X1778217Y149100D01*
X1777550Y151600D01*
X1776883Y149100D01*
X1776300Y151600D01*
G01X1775367Y149600D02*
X1775117Y149308D01*
X1774783Y149142D01*
X1774408Y149100D01*
X1774075Y149142D01*
X1773742Y149350D01*
X1773533Y149600D01*
X1773492Y149850D01*
X1773575Y150142D01*
X1773867Y150350D01*
X1774158Y150433D01*
X1774533D01*
G01X1774158D02*
X1773908Y150558D01*
X1773700Y150767D01*
X1773617Y151017D01*
X1773700Y151267D01*
X1773908Y151475D01*
X1774283Y151600D01*
X1774658Y151558D01*
X1775033Y151392D01*
G01X1771350Y149100D02*
X1771058Y149142D01*
X1770725Y149267D01*
X1770517Y149475D01*
X1770433Y149767D01*
X1770517Y150058D01*
X1770767Y150308D01*
X1771142Y150433D01*
X1771558D01*
X1771808Y150517D01*
X1772017Y150725D01*
X1772100Y151017D01*
X1771975Y151308D01*
X1771683Y151517D01*
X1771350Y151600D01*
X1771017Y151517D01*
X1770725Y151308D01*
X1770600Y151017D01*
X1770683Y150725D01*
X1770892Y150517D01*
X1771142Y150433D01*
X1771558D01*
X1771933Y150308D01*
X1772183Y150058D01*
X1772267Y149767D01*
X1772183Y149475D01*
X1771975Y149267D01*
X1771642Y149142D01*
X1771350Y149100D01*
G01X1762222Y143798D02*
Y147798D01*
X1769622D01*
G01X1721350Y140717D02*
X1723850D01*
Y141758D01*
X1723725Y142092D01*
X1723558Y142300D01*
X1723225Y142383D01*
X1722892Y142300D01*
X1722683Y142050D01*
X1722558Y141758D01*
Y140717D01*
G01Y141758D02*
X1721350Y142383D01*
G01X1723433Y143858D02*
X1723683Y144108D01*
X1723808Y144400D01*
X1723850Y144733D01*
X1723767Y145150D01*
X1723558Y145442D01*
X1723308Y145525D01*
X1723058Y145483D01*
X1722850Y145317D01*
X1722433Y144483D01*
X1722142Y144108D01*
X1721725Y143858D01*
X1721350Y143775D01*
Y145525D01*
G01X1721725Y146833D02*
X1721517Y147083D01*
X1721392Y147375D01*
X1721350Y147750D01*
X1721433Y148125D01*
X1721600Y148417D01*
X1721892Y148625D01*
X1722225Y148667D01*
X1722558Y148583D01*
X1722767Y148375D01*
X1722933Y148083D01*
X1722975Y147792D01*
X1722933Y147500D01*
X1722767Y147125D01*
X1723850Y147250D01*
Y148375D01*
G01Y149600D02*
X1721350Y150183D01*
X1723850Y150850D01*
X1721350Y151517D01*
X1723850Y152100D01*
G01X1721350Y153950D02*
X1723850D01*
X1723350Y153450D01*
G01X1721350D02*
Y154450D01*
G01X1721850Y156133D02*
X1721558Y156383D01*
X1721392Y156717D01*
X1721350Y157092D01*
X1721392Y157425D01*
X1721600Y157758D01*
X1721850Y157967D01*
X1722100Y158008D01*
X1722392Y157925D01*
X1722600Y157633D01*
X1722683Y157342D01*
Y156967D01*
G01Y157342D02*
X1722808Y157592D01*
X1723017Y157800D01*
X1723267Y157883D01*
X1723517Y157800D01*
X1723725Y157592D01*
X1723850Y157217D01*
X1723808Y156842D01*
X1723642Y156467D01*
G01X1717850Y140717D02*
X1720350D01*
Y141758D01*
X1720225Y142092D01*
X1720058Y142300D01*
X1719725Y142383D01*
X1719392Y142300D01*
X1719183Y142050D01*
X1719058Y141758D01*
Y140717D01*
G01Y141758D02*
X1717850Y142383D01*
G01X1719933Y143858D02*
X1720183Y144108D01*
X1720308Y144400D01*
X1720350Y144733D01*
X1720267Y145150D01*
X1720058Y145442D01*
X1719808Y145525D01*
X1719558Y145483D01*
X1719350Y145317D01*
X1718933Y144483D01*
X1718642Y144108D01*
X1718225Y143858D01*
X1717850Y143775D01*
Y145525D01*
G01X1718225Y146833D02*
X1718017Y147083D01*
X1717892Y147375D01*
X1717850Y147750D01*
X1717933Y148125D01*
X1718100Y148417D01*
X1718392Y148625D01*
X1718725Y148667D01*
X1719058Y148583D01*
X1719267Y148375D01*
X1719433Y148083D01*
X1719475Y147792D01*
X1719433Y147500D01*
X1719267Y147125D01*
X1720350Y147250D01*
Y148375D01*
G01Y149600D02*
X1717850Y150183D01*
X1720350Y150850D01*
X1717850Y151517D01*
X1720350Y152100D01*
G01X1717850Y153950D02*
X1720350D01*
X1719850Y153450D01*
G01X1717850D02*
Y154450D01*
G01Y156967D02*
X1718392Y157050D01*
X1718850Y157175D01*
X1719267Y157342D01*
X1719725Y157550D01*
X1720350Y157883D01*
Y156217D01*
G01X1729983Y182600D02*
Y185100D01*
X1728942D01*
X1728608Y184975D01*
X1728400Y184808D01*
X1728317Y184475D01*
X1728400Y184142D01*
X1728650Y183933D01*
X1728942Y183808D01*
X1729983D01*
G01X1728942D02*
X1728317Y182600D01*
G01X1726842Y184683D02*
X1726592Y184933D01*
X1726300Y185058D01*
X1725967Y185100D01*
X1725550Y185017D01*
X1725258Y184808D01*
X1725175Y184558D01*
X1725217Y184308D01*
X1725383Y184100D01*
X1726217Y183683D01*
X1726592Y183392D01*
X1726842Y182975D01*
X1726925Y182600D01*
X1725175D01*
G01X1724200Y185100D02*
X1723617Y182600D01*
X1722950Y185100D01*
X1722283Y182600D01*
X1721700Y185100D01*
G01X1719850Y182600D02*
Y185100D01*
X1720350Y184600D01*
G01Y182600D02*
X1719350D01*
G01X1772017Y215044D02*
X1772142Y214794D01*
X1772225Y214502D01*
Y214169D01*
X1772100Y213794D01*
X1771892Y213502D01*
X1771642Y213294D01*
X1771225Y213127D01*
X1770850Y213085D01*
X1770475Y213169D01*
X1770225Y213294D01*
X1769975Y213544D01*
X1769808Y213835D01*
X1769725Y214127D01*
Y214419D01*
X1769808Y214710D01*
X1769933Y214960D01*
X1770100Y215169D01*
G01X1769725Y217227D02*
X1772225D01*
X1771725Y216727D01*
G01X1769725D02*
Y217727D01*
G01Y219494D02*
X1772225D01*
Y220535D01*
X1772100Y220869D01*
X1771933Y221077D01*
X1771600Y221160D01*
X1771267Y221077D01*
X1771058Y220827D01*
X1770933Y220535D01*
Y219494D01*
G01Y220535D02*
X1769725Y221160D01*
G01Y223427D02*
X1772225D01*
X1771725Y222927D01*
G01X1769725D02*
Y223927D01*
G01X1772225Y226527D02*
X1772142Y226194D01*
X1771933Y225944D01*
X1771683Y225777D01*
X1771350Y225652D01*
X1770975Y225610D01*
X1770600Y225652D01*
X1770267Y225777D01*
X1770017Y225944D01*
X1769808Y226194D01*
X1769725Y226527D01*
X1769808Y226860D01*
X1770017Y227110D01*
X1770267Y227277D01*
X1770600Y227402D01*
X1770975Y227444D01*
X1771350Y227402D01*
X1771683Y227277D01*
X1771933Y227110D01*
X1772142Y226860D01*
X1772225Y226527D01*
G01X1776017Y216594D02*
X1776142Y216344D01*
X1776225Y216052D01*
Y215719D01*
X1776100Y215344D01*
X1775892Y215052D01*
X1775642Y214844D01*
X1775225Y214677D01*
X1774850Y214635D01*
X1774475Y214719D01*
X1774225Y214844D01*
X1773975Y215094D01*
X1773808Y215385D01*
X1773725Y215677D01*
Y215969D01*
X1773808Y216260D01*
X1773933Y216510D01*
X1774100Y216719D01*
G01X1773725Y218777D02*
X1776225D01*
X1775725Y218277D01*
G01X1773725D02*
Y219277D01*
G01Y221044D02*
X1776225D01*
Y222085D01*
X1776100Y222419D01*
X1775933Y222627D01*
X1775600Y222710D01*
X1775267Y222627D01*
X1775058Y222377D01*
X1774933Y222085D01*
Y221044D01*
G01Y222085D02*
X1773725Y222710D01*
G01X1774017Y224269D02*
X1773808Y224560D01*
X1773725Y224894D01*
X1773808Y225227D01*
X1774058Y225519D01*
X1774433Y225727D01*
X1774808Y225810D01*
X1775267D01*
X1775642Y225727D01*
X1775975Y225519D01*
X1776142Y225269D01*
X1776225Y224977D01*
X1776142Y224644D01*
X1775975Y224394D01*
X1775725Y224227D01*
X1775392Y224144D01*
X1775100Y224227D01*
X1774808Y224435D01*
X1774642Y224685D01*
X1774600Y224977D01*
X1774683Y225310D01*
X1774892Y225560D01*
X1775267Y225810D01*
G01X1760389Y215344D02*
X1760514Y215094D01*
X1760597Y214802D01*
Y214469D01*
X1760472Y214094D01*
X1760264Y213802D01*
X1760014Y213594D01*
X1759597Y213427D01*
X1759222Y213385D01*
X1758847Y213469D01*
X1758597Y213594D01*
X1758347Y213844D01*
X1758180Y214135D01*
X1758097Y214427D01*
Y214719D01*
X1758180Y215010D01*
X1758305Y215260D01*
X1758472Y215469D01*
G01X1760180Y216735D02*
X1760430Y216985D01*
X1760555Y217277D01*
X1760597Y217610D01*
X1760514Y218027D01*
X1760305Y218319D01*
X1760055Y218402D01*
X1759805Y218360D01*
X1759597Y218194D01*
X1759180Y217360D01*
X1758889Y216985D01*
X1758472Y216735D01*
X1758097Y216652D01*
Y218402D01*
G01Y219794D02*
X1760597D01*
Y220835D01*
X1760472Y221169D01*
X1760305Y221377D01*
X1759972Y221460D01*
X1759639Y221377D01*
X1759430Y221127D01*
X1759305Y220835D01*
Y219794D01*
G01Y220835D02*
X1758097Y221460D01*
G01Y223727D02*
X1760597D01*
X1760097Y223227D01*
G01X1758097D02*
Y224227D01*
G01Y227327D02*
X1760597D01*
X1758805Y225785D01*
Y227869D01*
G01X1764459Y215117D02*
X1764584Y214867D01*
X1764667Y214575D01*
Y214242D01*
X1764542Y213867D01*
X1764334Y213575D01*
X1764084Y213367D01*
X1763667Y213200D01*
X1763292Y213158D01*
X1762917Y213242D01*
X1762667Y213367D01*
X1762417Y213617D01*
X1762250Y213908D01*
X1762167Y214200D01*
Y214492D01*
X1762250Y214783D01*
X1762375Y215033D01*
X1762542Y215242D01*
G01X1764250Y216508D02*
X1764500Y216758D01*
X1764625Y217050D01*
X1764667Y217383D01*
X1764584Y217800D01*
X1764375Y218092D01*
X1764125Y218175D01*
X1763875Y218133D01*
X1763667Y217967D01*
X1763250Y217133D01*
X1762959Y216758D01*
X1762542Y216508D01*
X1762167Y216425D01*
Y218175D01*
G01Y219567D02*
X1764667D01*
Y220608D01*
X1764542Y220942D01*
X1764375Y221150D01*
X1764042Y221233D01*
X1763709Y221150D01*
X1763500Y220900D01*
X1763375Y220608D01*
Y219567D01*
G01Y220608D02*
X1762167Y221233D01*
G01Y223500D02*
X1764667D01*
X1764167Y223000D01*
G01X1762167D02*
Y224000D01*
G01X1762667Y225683D02*
X1762375Y225933D01*
X1762209Y226267D01*
X1762167Y226642D01*
X1762209Y226975D01*
X1762417Y227308D01*
X1762667Y227517D01*
X1762917Y227558D01*
X1763209Y227475D01*
X1763417Y227183D01*
X1763500Y226892D01*
Y226517D01*
G01Y226892D02*
X1763625Y227142D01*
X1763834Y227350D01*
X1764084Y227433D01*
X1764334Y227350D01*
X1764542Y227142D01*
X1764667Y226767D01*
X1764625Y226392D01*
X1764459Y226017D01*
G01X1736932Y214197D02*
X1737057Y213947D01*
X1737140Y213655D01*
Y213322D01*
X1737015Y212947D01*
X1736807Y212655D01*
X1736557Y212447D01*
X1736140Y212280D01*
X1735765Y212238D01*
X1735390Y212322D01*
X1735140Y212447D01*
X1734890Y212697D01*
X1734723Y212988D01*
X1734640Y213280D01*
Y213572D01*
X1734723Y213863D01*
X1734848Y214113D01*
X1735015Y214322D01*
G01X1736723Y215588D02*
X1736973Y215838D01*
X1737098Y216130D01*
X1737140Y216463D01*
X1737057Y216880D01*
X1736848Y217172D01*
X1736598Y217255D01*
X1736348Y217213D01*
X1736140Y217047D01*
X1735723Y216213D01*
X1735432Y215838D01*
X1735015Y215588D01*
X1734640Y215505D01*
Y217255D01*
G01Y218647D02*
X1737140D01*
Y219688D01*
X1737015Y220022D01*
X1736848Y220230D01*
X1736515Y220313D01*
X1736182Y220230D01*
X1735973Y219980D01*
X1735848Y219688D01*
Y218647D01*
G01Y219688D02*
X1734640Y220313D01*
G01Y222580D02*
X1737140D01*
X1736640Y222080D01*
G01X1734640D02*
Y223080D01*
G01X1737140Y225680D02*
X1737057Y225347D01*
X1736848Y225097D01*
X1736598Y224930D01*
X1736265Y224805D01*
X1735890Y224763D01*
X1735515Y224805D01*
X1735182Y224930D01*
X1734932Y225097D01*
X1734723Y225347D01*
X1734640Y225680D01*
X1734723Y226013D01*
X1734932Y226263D01*
X1735182Y226430D01*
X1735515Y226555D01*
X1735890Y226597D01*
X1736265Y226555D01*
X1736598Y226430D01*
X1736848Y226263D01*
X1737057Y226013D01*
X1737140Y225680D01*
G01X1727792Y215567D02*
X1727917Y215317D01*
X1728000Y215025D01*
Y214692D01*
X1727875Y214317D01*
X1727667Y214025D01*
X1727417Y213817D01*
X1727000Y213650D01*
X1726625Y213608D01*
X1726250Y213692D01*
X1726000Y213817D01*
X1725750Y214067D01*
X1725583Y214358D01*
X1725500Y214650D01*
Y214942D01*
X1725583Y215233D01*
X1725708Y215483D01*
X1725875Y215692D01*
G01X1727583Y216958D02*
X1727833Y217208D01*
X1727958Y217500D01*
X1728000Y217833D01*
X1727917Y218250D01*
X1727708Y218542D01*
X1727458Y218625D01*
X1727208Y218583D01*
X1727000Y218417D01*
X1726583Y217583D01*
X1726292Y217208D01*
X1725875Y216958D01*
X1725500Y216875D01*
Y218625D01*
G01Y220017D02*
X1728000D01*
Y221058D01*
X1727875Y221392D01*
X1727708Y221600D01*
X1727375Y221683D01*
X1727042Y221600D01*
X1726833Y221350D01*
X1726708Y221058D01*
Y220017D01*
G01Y221058D02*
X1725500Y221683D01*
G01Y223950D02*
X1728000D01*
X1727500Y223450D01*
G01X1725500D02*
Y224450D01*
G01X1726542Y226258D02*
X1726833Y226550D01*
X1727000Y226800D01*
X1727083Y227133D01*
X1727000Y227425D01*
X1726833Y227633D01*
X1726583Y227800D01*
X1726292Y227842D01*
X1726042Y227800D01*
X1725792Y227633D01*
X1725583Y227383D01*
X1725500Y227092D01*
X1725583Y226758D01*
X1725833Y226467D01*
X1726208Y226300D01*
X1726625Y226258D01*
X1727167Y226342D01*
X1727458Y226467D01*
X1727750Y226675D01*
X1727958Y226967D01*
X1728000Y227258D01*
X1727917Y227550D01*
X1727708Y227758D01*
G01X1724292Y215567D02*
X1724417Y215317D01*
X1724500Y215025D01*
Y214692D01*
X1724375Y214317D01*
X1724167Y214025D01*
X1723917Y213817D01*
X1723500Y213650D01*
X1723125Y213608D01*
X1722750Y213692D01*
X1722500Y213817D01*
X1722250Y214067D01*
X1722083Y214358D01*
X1722000Y214650D01*
Y214942D01*
X1722083Y215233D01*
X1722208Y215483D01*
X1722375Y215692D01*
G01X1724083Y216958D02*
X1724333Y217208D01*
X1724458Y217500D01*
X1724500Y217833D01*
X1724417Y218250D01*
X1724208Y218542D01*
X1723958Y218625D01*
X1723708Y218583D01*
X1723500Y218417D01*
X1723083Y217583D01*
X1722792Y217208D01*
X1722375Y216958D01*
X1722000Y216875D01*
Y218625D01*
G01Y220017D02*
X1724500D01*
Y221058D01*
X1724375Y221392D01*
X1724208Y221600D01*
X1723875Y221683D01*
X1723542Y221600D01*
X1723333Y221350D01*
X1723208Y221058D01*
Y220017D01*
G01Y221058D02*
X1722000Y221683D01*
G01Y223950D02*
X1724500D01*
X1724000Y223450D01*
G01X1722000D02*
Y224450D01*
G01Y226967D02*
X1722542Y227050D01*
X1723000Y227175D01*
X1723417Y227342D01*
X1723875Y227550D01*
X1724500Y227883D01*
Y226217D01*
G01X1720792Y215567D02*
X1720917Y215317D01*
X1721000Y215025D01*
Y214692D01*
X1720875Y214317D01*
X1720667Y214025D01*
X1720417Y213817D01*
X1720000Y213650D01*
X1719625Y213608D01*
X1719250Y213692D01*
X1719000Y213817D01*
X1718750Y214067D01*
X1718583Y214358D01*
X1718500Y214650D01*
Y214942D01*
X1718583Y215233D01*
X1718708Y215483D01*
X1718875Y215692D01*
G01X1720583Y216958D02*
X1720833Y217208D01*
X1720958Y217500D01*
X1721000Y217833D01*
X1720917Y218250D01*
X1720708Y218542D01*
X1720458Y218625D01*
X1720208Y218583D01*
X1720000Y218417D01*
X1719583Y217583D01*
X1719292Y217208D01*
X1718875Y216958D01*
X1718500Y216875D01*
Y218625D01*
G01Y220017D02*
X1721000D01*
Y221058D01*
X1720875Y221392D01*
X1720708Y221600D01*
X1720375Y221683D01*
X1720042Y221600D01*
X1719833Y221350D01*
X1719708Y221058D01*
Y220017D01*
G01Y221058D02*
X1718500Y221683D01*
G01Y223950D02*
X1721000D01*
X1720500Y223450D01*
G01X1718500D02*
Y224450D01*
G01Y227050D02*
X1718542Y227342D01*
X1718667Y227675D01*
X1718875Y227883D01*
X1719167Y227967D01*
X1719458Y227883D01*
X1719708Y227633D01*
X1719833Y227258D01*
Y226842D01*
X1719917Y226592D01*
X1720125Y226383D01*
X1720417Y226300D01*
X1720708Y226425D01*
X1720917Y226717D01*
X1721000Y227050D01*
X1720917Y227383D01*
X1720708Y227675D01*
X1720417Y227800D01*
X1720125Y227717D01*
X1719917Y227508D01*
X1719833Y227258D01*
Y226842D01*
X1719708Y226467D01*
X1719458Y226217D01*
X1719167Y226133D01*
X1718875Y226217D01*
X1718667Y226425D01*
X1718542Y226758D01*
X1718500Y227050D01*
G01X1731292Y215567D02*
X1731417Y215317D01*
X1731500Y215025D01*
Y214692D01*
X1731375Y214317D01*
X1731167Y214025D01*
X1730917Y213817D01*
X1730500Y213650D01*
X1730125Y213608D01*
X1729750Y213692D01*
X1729500Y213817D01*
X1729250Y214067D01*
X1729083Y214358D01*
X1729000Y214650D01*
Y214942D01*
X1729083Y215233D01*
X1729208Y215483D01*
X1729375Y215692D01*
G01X1731083Y216958D02*
X1731333Y217208D01*
X1731458Y217500D01*
X1731500Y217833D01*
X1731417Y218250D01*
X1731208Y218542D01*
X1730958Y218625D01*
X1730708Y218583D01*
X1730500Y218417D01*
X1730083Y217583D01*
X1729792Y217208D01*
X1729375Y216958D01*
X1729000Y216875D01*
Y218625D01*
G01Y220017D02*
X1731500D01*
Y221058D01*
X1731375Y221392D01*
X1731208Y221600D01*
X1730875Y221683D01*
X1730542Y221600D01*
X1730333Y221350D01*
X1730208Y221058D01*
Y220017D01*
G01Y221058D02*
X1729000Y221683D01*
G01Y223950D02*
X1731500D01*
X1731000Y223450D01*
G01X1729000D02*
Y224450D01*
G01X1729375Y226133D02*
X1729167Y226383D01*
X1729042Y226675D01*
X1729000Y227050D01*
X1729083Y227425D01*
X1729250Y227717D01*
X1729542Y227925D01*
X1729875Y227967D01*
X1730208Y227883D01*
X1730417Y227675D01*
X1730583Y227383D01*
X1730625Y227092D01*
X1730583Y226800D01*
X1730417Y226425D01*
X1731500Y226550D01*
Y227675D01*
G01X1741522Y216287D02*
X1741647Y216037D01*
X1741730Y215745D01*
Y215412D01*
X1741605Y215037D01*
X1741397Y214745D01*
X1741147Y214537D01*
X1740730Y214370D01*
X1740355Y214328D01*
X1739980Y214412D01*
X1739730Y214537D01*
X1739480Y214787D01*
X1739313Y215078D01*
X1739230Y215370D01*
Y215662D01*
X1739313Y215953D01*
X1739438Y216203D01*
X1739605Y216412D01*
G01X1741313Y217678D02*
X1741563Y217928D01*
X1741688Y218220D01*
X1741730Y218553D01*
X1741647Y218970D01*
X1741438Y219262D01*
X1741188Y219345D01*
X1740938Y219303D01*
X1740730Y219137D01*
X1740313Y218303D01*
X1740022Y217928D01*
X1739605Y217678D01*
X1739230Y217595D01*
Y219345D01*
G01Y220737D02*
X1741730D01*
Y221778D01*
X1741605Y222112D01*
X1741438Y222320D01*
X1741105Y222403D01*
X1740772Y222320D01*
X1740563Y222070D01*
X1740438Y221778D01*
Y220737D01*
G01Y221778D02*
X1739230Y222403D01*
G01X1739522Y223962D02*
X1739313Y224253D01*
X1739230Y224587D01*
X1739313Y224920D01*
X1739563Y225212D01*
X1739938Y225420D01*
X1740313Y225503D01*
X1740772D01*
X1741147Y225420D01*
X1741480Y225212D01*
X1741647Y224962D01*
X1741730Y224670D01*
X1741647Y224337D01*
X1741480Y224087D01*
X1741230Y223920D01*
X1740897Y223837D01*
X1740605Y223920D01*
X1740313Y224128D01*
X1740147Y224378D01*
X1740105Y224670D01*
X1740188Y225003D01*
X1740397Y225253D01*
X1740772Y225503D01*
G01X1751681Y215438D02*
X1751806Y215188D01*
X1751889Y214896D01*
Y214563D01*
X1751764Y214188D01*
X1751556Y213896D01*
X1751306Y213688D01*
X1750889Y213521D01*
X1750514Y213479D01*
X1750139Y213563D01*
X1749889Y213688D01*
X1749639Y213938D01*
X1749472Y214229D01*
X1749389Y214521D01*
Y214813D01*
X1749472Y215104D01*
X1749597Y215354D01*
X1749764Y215563D01*
G01X1751472Y216829D02*
X1751722Y217079D01*
X1751847Y217371D01*
X1751889Y217704D01*
X1751806Y218121D01*
X1751597Y218413D01*
X1751347Y218496D01*
X1751097Y218454D01*
X1750889Y218288D01*
X1750472Y217454D01*
X1750181Y217079D01*
X1749764Y216829D01*
X1749389Y216746D01*
Y218496D01*
G01Y219888D02*
X1751889D01*
Y220929D01*
X1751764Y221263D01*
X1751597Y221471D01*
X1751264Y221554D01*
X1750931Y221471D01*
X1750722Y221221D01*
X1750597Y220929D01*
Y219888D01*
G01Y220929D02*
X1749389Y221554D01*
G01Y223738D02*
X1749931Y223821D01*
X1750389Y223946D01*
X1750806Y224113D01*
X1751264Y224321D01*
X1751889Y224654D01*
Y222988D01*
G01X1747681Y215438D02*
X1747806Y215188D01*
X1747889Y214896D01*
Y214563D01*
X1747764Y214188D01*
X1747556Y213896D01*
X1747306Y213688D01*
X1746889Y213521D01*
X1746514Y213479D01*
X1746139Y213563D01*
X1745889Y213688D01*
X1745639Y213938D01*
X1745472Y214229D01*
X1745389Y214521D01*
Y214813D01*
X1745472Y215104D01*
X1745597Y215354D01*
X1745764Y215563D01*
G01X1747472Y216829D02*
X1747722Y217079D01*
X1747847Y217371D01*
X1747889Y217704D01*
X1747806Y218121D01*
X1747597Y218413D01*
X1747347Y218496D01*
X1747097Y218454D01*
X1746889Y218288D01*
X1746472Y217454D01*
X1746181Y217079D01*
X1745764Y216829D01*
X1745389Y216746D01*
Y218496D01*
G01Y219888D02*
X1747889D01*
Y220929D01*
X1747764Y221263D01*
X1747597Y221471D01*
X1747264Y221554D01*
X1746931Y221471D01*
X1746722Y221221D01*
X1746597Y220929D01*
Y219888D01*
G01Y220929D02*
X1745389Y221554D01*
G01Y223821D02*
X1745431Y224113D01*
X1745556Y224446D01*
X1745764Y224654D01*
X1746056Y224738D01*
X1746347Y224654D01*
X1746597Y224404D01*
X1746722Y224029D01*
Y223613D01*
X1746806Y223363D01*
X1747014Y223154D01*
X1747306Y223071D01*
X1747597Y223196D01*
X1747806Y223488D01*
X1747889Y223821D01*
X1747806Y224154D01*
X1747597Y224446D01*
X1747306Y224571D01*
X1747014Y224488D01*
X1746806Y224279D01*
X1746722Y224029D01*
Y223613D01*
X1746597Y223238D01*
X1746347Y222988D01*
X1746056Y222904D01*
X1745764Y222988D01*
X1745556Y223196D01*
X1745431Y223529D01*
X1745389Y223821D01*
G01X1730033Y186300D02*
Y188800D01*
X1728992D01*
X1728658Y188675D01*
X1728450Y188508D01*
X1728367Y188175D01*
X1728450Y187842D01*
X1728700Y187633D01*
X1728992Y187508D01*
X1730033D01*
G01X1728992D02*
X1728367Y186300D01*
G01X1726892Y188383D02*
X1726642Y188633D01*
X1726350Y188758D01*
X1726017Y188800D01*
X1725600Y188717D01*
X1725308Y188508D01*
X1725225Y188258D01*
X1725267Y188008D01*
X1725433Y187800D01*
X1726267Y187383D01*
X1726642Y187092D01*
X1726892Y186675D01*
X1726975Y186300D01*
X1725225D01*
G01X1723833D02*
Y188800D01*
X1722792D01*
X1722458Y188675D01*
X1722250Y188508D01*
X1722167Y188175D01*
X1722250Y187842D01*
X1722500Y187633D01*
X1722792Y187508D01*
X1723833D01*
G01X1722792D02*
X1722167Y186300D01*
G01X1719900D02*
X1719608Y186342D01*
X1719275Y186467D01*
X1719067Y186675D01*
X1718983Y186967D01*
X1719067Y187258D01*
X1719317Y187508D01*
X1719692Y187633D01*
X1720108D01*
X1720358Y187717D01*
X1720567Y187925D01*
X1720650Y188217D01*
X1720525Y188508D01*
X1720233Y188717D01*
X1719900Y188800D01*
X1719567Y188717D01*
X1719275Y188508D01*
X1719150Y188217D01*
X1719233Y187925D01*
X1719442Y187717D01*
X1719692Y187633D01*
X1720108D01*
X1720483Y187508D01*
X1720733Y187258D01*
X1720817Y186967D01*
X1720733Y186675D01*
X1720525Y186467D01*
X1720192Y186342D01*
X1719900Y186300D01*
G01Y196700D02*
Y200700D01*
X1727300D01*
G01X1770800Y157717D02*
X1773300D01*
Y158758D01*
X1773175Y159092D01*
X1773008Y159300D01*
X1772675Y159383D01*
X1772342Y159300D01*
X1772133Y159050D01*
X1772008Y158758D01*
Y157717D01*
G01Y158758D02*
X1770800Y159383D01*
G01X1772883Y160858D02*
X1773133Y161108D01*
X1773258Y161400D01*
X1773300Y161733D01*
X1773217Y162150D01*
X1773008Y162442D01*
X1772758Y162525D01*
X1772508Y162483D01*
X1772300Y162317D01*
X1771883Y161483D01*
X1771592Y161108D01*
X1771175Y160858D01*
X1770800Y160775D01*
Y162525D01*
G01X1771175Y163833D02*
X1770967Y164083D01*
X1770842Y164375D01*
X1770800Y164750D01*
X1770883Y165125D01*
X1771050Y165417D01*
X1771342Y165625D01*
X1771675Y165667D01*
X1772008Y165583D01*
X1772217Y165375D01*
X1772383Y165083D01*
X1772425Y164792D01*
X1772383Y164500D01*
X1772217Y164125D01*
X1773300Y164250D01*
Y165375D01*
G01Y166600D02*
X1770800Y167183D01*
X1773300Y167850D01*
X1770800Y168517D01*
X1773300Y169100D01*
G01X1770800Y170950D02*
X1773300D01*
X1772800Y170450D01*
G01X1770800D02*
Y171450D01*
G01Y174550D02*
X1773300D01*
X1771508Y173008D01*
Y175092D01*
G01X1743189Y160269D02*
X1739189D01*
Y167669D01*
G01X1774300Y157717D02*
X1776800D01*
Y158758D01*
X1776675Y159092D01*
X1776508Y159300D01*
X1776175Y159383D01*
X1775842Y159300D01*
X1775633Y159050D01*
X1775508Y158758D01*
Y157717D01*
G01Y158758D02*
X1774300Y159383D01*
G01X1776383Y160858D02*
X1776633Y161108D01*
X1776758Y161400D01*
X1776800Y161733D01*
X1776717Y162150D01*
X1776508Y162442D01*
X1776258Y162525D01*
X1776008Y162483D01*
X1775800Y162317D01*
X1775383Y161483D01*
X1775092Y161108D01*
X1774675Y160858D01*
X1774300Y160775D01*
Y162525D01*
G01X1774675Y163833D02*
X1774467Y164083D01*
X1774342Y164375D01*
X1774300Y164750D01*
X1774383Y165125D01*
X1774550Y165417D01*
X1774842Y165625D01*
X1775175Y165667D01*
X1775508Y165583D01*
X1775717Y165375D01*
X1775883Y165083D01*
X1775925Y164792D01*
X1775883Y164500D01*
X1775717Y164125D01*
X1776800Y164250D01*
Y165375D01*
G01Y166600D02*
X1774300Y167183D01*
X1776800Y167850D01*
X1774300Y168517D01*
X1776800Y169100D01*
G01X1774300Y170950D02*
X1776800D01*
X1776300Y170450D01*
G01X1774300D02*
Y171450D01*
G01X1775342Y173258D02*
X1775633Y173550D01*
X1775800Y173800D01*
X1775883Y174133D01*
X1775800Y174425D01*
X1775633Y174633D01*
X1775383Y174800D01*
X1775092Y174842D01*
X1774842Y174800D01*
X1774592Y174633D01*
X1774383Y174383D01*
X1774300Y174092D01*
X1774383Y173758D01*
X1774633Y173467D01*
X1775008Y173300D01*
X1775425Y173258D01*
X1775967Y173342D01*
X1776258Y173467D01*
X1776550Y173675D01*
X1776758Y173967D01*
X1776800Y174258D01*
X1776717Y174550D01*
X1776508Y174758D01*
G01X1747689Y160269D02*
X1743689D01*
Y167669D01*
G01X1752189Y160269D02*
X1748189D01*
Y167669D01*
G01X1767300Y157717D02*
X1769800D01*
Y158758D01*
X1769675Y159092D01*
X1769508Y159300D01*
X1769175Y159383D01*
X1768842Y159300D01*
X1768633Y159050D01*
X1768508Y158758D01*
Y157717D01*
G01Y158758D02*
X1767300Y159383D01*
G01X1769383Y160858D02*
X1769633Y161108D01*
X1769758Y161400D01*
X1769800Y161733D01*
X1769717Y162150D01*
X1769508Y162442D01*
X1769258Y162525D01*
X1769008Y162483D01*
X1768800Y162317D01*
X1768383Y161483D01*
X1768092Y161108D01*
X1767675Y160858D01*
X1767300Y160775D01*
Y162525D01*
G01X1767675Y163833D02*
X1767467Y164083D01*
X1767342Y164375D01*
X1767300Y164750D01*
X1767383Y165125D01*
X1767550Y165417D01*
X1767842Y165625D01*
X1768175Y165667D01*
X1768508Y165583D01*
X1768717Y165375D01*
X1768883Y165083D01*
X1768925Y164792D01*
X1768883Y164500D01*
X1768717Y164125D01*
X1769800Y164250D01*
Y165375D01*
G01Y166600D02*
X1767300Y167183D01*
X1769800Y167850D01*
X1767300Y168517D01*
X1769800Y169100D01*
G01X1769383Y170158D02*
X1769633Y170408D01*
X1769758Y170700D01*
X1769800Y171033D01*
X1769717Y171450D01*
X1769508Y171742D01*
X1769258Y171825D01*
X1769008Y171783D01*
X1768800Y171617D01*
X1768383Y170783D01*
X1768092Y170408D01*
X1767675Y170158D01*
X1767300Y170075D01*
Y171825D01*
G01Y174550D02*
X1769800D01*
X1768008Y173008D01*
Y175092D01*
G01X1738689Y160269D02*
X1734689D01*
Y167669D01*
G01X1763550Y157717D02*
X1766050D01*
Y158758D01*
X1765925Y159092D01*
X1765758Y159300D01*
X1765425Y159383D01*
X1765092Y159300D01*
X1764883Y159050D01*
X1764758Y158758D01*
Y157717D01*
G01Y158758D02*
X1763550Y159383D01*
G01X1765633Y160858D02*
X1765883Y161108D01*
X1766008Y161400D01*
X1766050Y161733D01*
X1765967Y162150D01*
X1765758Y162442D01*
X1765508Y162525D01*
X1765258Y162483D01*
X1765050Y162317D01*
X1764633Y161483D01*
X1764342Y161108D01*
X1763925Y160858D01*
X1763550Y160775D01*
Y162525D01*
G01X1763925Y163833D02*
X1763717Y164083D01*
X1763592Y164375D01*
X1763550Y164750D01*
X1763633Y165125D01*
X1763800Y165417D01*
X1764092Y165625D01*
X1764425Y165667D01*
X1764758Y165583D01*
X1764967Y165375D01*
X1765133Y165083D01*
X1765175Y164792D01*
X1765133Y164500D01*
X1764967Y164125D01*
X1766050Y164250D01*
Y165375D01*
G01Y166600D02*
X1763550Y167183D01*
X1766050Y167850D01*
X1763550Y168517D01*
X1766050Y169100D01*
G01X1763550Y170950D02*
X1766050D01*
X1765550Y170450D01*
G01X1763550D02*
Y171450D01*
G01X1763925Y173133D02*
X1763717Y173383D01*
X1763592Y173675D01*
X1763550Y174050D01*
X1763633Y174425D01*
X1763800Y174717D01*
X1764092Y174925D01*
X1764425Y174967D01*
X1764758Y174883D01*
X1764967Y174675D01*
X1765133Y174383D01*
X1765175Y174092D01*
X1765133Y173800D01*
X1764967Y173425D01*
X1766050Y173550D01*
Y174675D01*
G01X1734189Y160269D02*
X1730189D01*
Y167669D01*
G01X1760000Y157717D02*
X1762500D01*
Y158758D01*
X1762375Y159092D01*
X1762208Y159300D01*
X1761875Y159383D01*
X1761542Y159300D01*
X1761333Y159050D01*
X1761208Y158758D01*
Y157717D01*
G01Y158758D02*
X1760000Y159383D01*
G01X1762083Y160858D02*
X1762333Y161108D01*
X1762458Y161400D01*
X1762500Y161733D01*
X1762417Y162150D01*
X1762208Y162442D01*
X1761958Y162525D01*
X1761708Y162483D01*
X1761500Y162317D01*
X1761083Y161483D01*
X1760792Y161108D01*
X1760375Y160858D01*
X1760000Y160775D01*
Y162525D01*
G01X1760375Y163833D02*
X1760167Y164083D01*
X1760042Y164375D01*
X1760000Y164750D01*
X1760083Y165125D01*
X1760250Y165417D01*
X1760542Y165625D01*
X1760875Y165667D01*
X1761208Y165583D01*
X1761417Y165375D01*
X1761583Y165083D01*
X1761625Y164792D01*
X1761583Y164500D01*
X1761417Y164125D01*
X1762500Y164250D01*
Y165375D01*
G01Y166600D02*
X1760000Y167183D01*
X1762500Y167850D01*
X1760000Y168517D01*
X1762500Y169100D01*
G01X1760000Y170950D02*
X1762500D01*
X1762000Y170450D01*
G01X1760000D02*
Y171450D01*
G01X1762500Y174050D02*
X1762417Y173717D01*
X1762208Y173467D01*
X1761958Y173300D01*
X1761625Y173175D01*
X1761250Y173133D01*
X1760875Y173175D01*
X1760542Y173300D01*
X1760292Y173467D01*
X1760083Y173717D01*
X1760000Y174050D01*
X1760083Y174383D01*
X1760292Y174633D01*
X1760542Y174800D01*
X1760875Y174925D01*
X1761250Y174967D01*
X1761625Y174925D01*
X1761958Y174800D01*
X1762208Y174633D01*
X1762417Y174383D01*
X1762500Y174050D01*
G01X1729689Y160269D02*
X1725689D01*
Y167669D01*
G01X1725189Y160269D02*
X1721189D01*
Y167669D01*
G01X1720689Y160269D02*
X1716689D01*
Y167669D01*
G01X1736000Y178017D02*
X1738500D01*
Y179058D01*
X1738375Y179392D01*
X1738208Y179600D01*
X1737875Y179683D01*
X1737542Y179600D01*
X1737333Y179350D01*
X1737208Y179058D01*
Y178017D01*
G01Y179058D02*
X1736000Y179683D01*
G01X1738083Y181158D02*
X1738333Y181408D01*
X1738458Y181700D01*
X1738500Y182033D01*
X1738417Y182450D01*
X1738208Y182742D01*
X1737958Y182825D01*
X1737708Y182783D01*
X1737500Y182617D01*
X1737083Y181783D01*
X1736792Y181408D01*
X1736375Y181158D01*
X1736000Y181075D01*
Y182825D01*
G01X1736375Y184133D02*
X1736167Y184383D01*
X1736042Y184675D01*
X1736000Y185050D01*
X1736083Y185425D01*
X1736250Y185717D01*
X1736542Y185925D01*
X1736875Y185967D01*
X1737208Y185883D01*
X1737417Y185675D01*
X1737583Y185383D01*
X1737625Y185092D01*
X1737583Y184800D01*
X1737417Y184425D01*
X1738500Y184550D01*
Y185675D01*
G01Y186900D02*
X1736000Y187483D01*
X1738500Y188150D01*
X1736000Y188817D01*
X1738500Y189400D01*
G01X1736500Y190333D02*
X1736208Y190583D01*
X1736042Y190917D01*
X1736000Y191292D01*
X1736042Y191625D01*
X1736250Y191958D01*
X1736500Y192167D01*
X1736750Y192208D01*
X1737042Y192125D01*
X1737250Y191833D01*
X1737333Y191542D01*
Y191167D01*
G01Y191542D02*
X1737458Y191792D01*
X1737667Y192000D01*
X1737917Y192083D01*
X1738167Y192000D01*
X1738375Y191792D01*
X1738500Y191417D01*
X1738458Y191042D01*
X1738292Y190667D01*
G01X1736292Y193642D02*
X1736083Y193933D01*
X1736000Y194267D01*
X1736083Y194600D01*
X1736333Y194892D01*
X1736708Y195100D01*
X1737083Y195183D01*
X1737542D01*
X1737917Y195100D01*
X1738250Y194892D01*
X1738417Y194642D01*
X1738500Y194350D01*
X1738417Y194017D01*
X1738250Y193767D01*
X1738000Y193600D01*
X1737667Y193517D01*
X1737375Y193600D01*
X1737083Y193808D01*
X1736917Y194058D01*
X1736875Y194350D01*
X1736958Y194683D01*
X1737167Y194933D01*
X1737542Y195183D01*
G01X1725189Y167725D02*
X1721189D01*
Y175125D01*
G01X1732500Y178017D02*
X1735000D01*
Y179058D01*
X1734875Y179392D01*
X1734708Y179600D01*
X1734375Y179683D01*
X1734042Y179600D01*
X1733833Y179350D01*
X1733708Y179058D01*
Y178017D01*
G01Y179058D02*
X1732500Y179683D01*
G01X1734583Y181158D02*
X1734833Y181408D01*
X1734958Y181700D01*
X1735000Y182033D01*
X1734917Y182450D01*
X1734708Y182742D01*
X1734458Y182825D01*
X1734208Y182783D01*
X1734000Y182617D01*
X1733583Y181783D01*
X1733292Y181408D01*
X1732875Y181158D01*
X1732500Y181075D01*
Y182825D01*
G01X1732875Y184133D02*
X1732667Y184383D01*
X1732542Y184675D01*
X1732500Y185050D01*
X1732583Y185425D01*
X1732750Y185717D01*
X1733042Y185925D01*
X1733375Y185967D01*
X1733708Y185883D01*
X1733917Y185675D01*
X1734083Y185383D01*
X1734125Y185092D01*
X1734083Y184800D01*
X1733917Y184425D01*
X1735000Y184550D01*
Y185675D01*
G01Y186900D02*
X1732500Y187483D01*
X1735000Y188150D01*
X1732500Y188817D01*
X1735000Y189400D01*
G01X1732500Y191750D02*
X1735000D01*
X1733208Y190208D01*
Y192292D01*
G01X1733000Y193433D02*
X1732708Y193683D01*
X1732542Y194017D01*
X1732500Y194392D01*
X1732542Y194725D01*
X1732750Y195058D01*
X1733000Y195267D01*
X1733250Y195308D01*
X1733542Y195225D01*
X1733750Y194933D01*
X1733833Y194642D01*
Y194267D01*
G01Y194642D02*
X1733958Y194892D01*
X1734167Y195100D01*
X1734417Y195183D01*
X1734667Y195100D01*
X1734875Y194892D01*
X1735000Y194517D01*
X1734958Y194142D01*
X1734792Y193767D01*
G01X1720689Y167725D02*
X1716689D01*
Y175125D01*
G01X1739500Y178017D02*
X1742000D01*
Y179058D01*
X1741875Y179392D01*
X1741708Y179600D01*
X1741375Y179683D01*
X1741042Y179600D01*
X1740833Y179350D01*
X1740708Y179058D01*
Y178017D01*
G01Y179058D02*
X1739500Y179683D01*
G01X1741583Y181158D02*
X1741833Y181408D01*
X1741958Y181700D01*
X1742000Y182033D01*
X1741917Y182450D01*
X1741708Y182742D01*
X1741458Y182825D01*
X1741208Y182783D01*
X1741000Y182617D01*
X1740583Y181783D01*
X1740292Y181408D01*
X1739875Y181158D01*
X1739500Y181075D01*
Y182825D01*
G01X1739875Y184133D02*
X1739667Y184383D01*
X1739542Y184675D01*
X1739500Y185050D01*
X1739583Y185425D01*
X1739750Y185717D01*
X1740042Y185925D01*
X1740375Y185967D01*
X1740708Y185883D01*
X1740917Y185675D01*
X1741083Y185383D01*
X1741125Y185092D01*
X1741083Y184800D01*
X1740917Y184425D01*
X1742000Y184550D01*
Y185675D01*
G01Y186900D02*
X1739500Y187483D01*
X1742000Y188150D01*
X1739500Y188817D01*
X1742000Y189400D01*
G01X1740000Y190333D02*
X1739708Y190583D01*
X1739542Y190917D01*
X1739500Y191292D01*
X1739542Y191625D01*
X1739750Y191958D01*
X1740000Y192167D01*
X1740250Y192208D01*
X1740542Y192125D01*
X1740750Y191833D01*
X1740833Y191542D01*
Y191167D01*
G01Y191542D02*
X1740958Y191792D01*
X1741167Y192000D01*
X1741417Y192083D01*
X1741667Y192000D01*
X1741875Y191792D01*
X1742000Y191417D01*
X1741958Y191042D01*
X1741792Y190667D01*
G01X1740542Y193558D02*
X1740833Y193850D01*
X1741000Y194100D01*
X1741083Y194433D01*
X1741000Y194725D01*
X1740833Y194933D01*
X1740583Y195100D01*
X1740292Y195142D01*
X1740042Y195100D01*
X1739792Y194933D01*
X1739583Y194683D01*
X1739500Y194392D01*
X1739583Y194058D01*
X1739833Y193767D01*
X1740208Y193600D01*
X1740625Y193558D01*
X1741167Y193642D01*
X1741458Y193767D01*
X1741750Y193975D01*
X1741958Y194267D01*
X1742000Y194558D01*
X1741917Y194850D01*
X1741708Y195058D01*
G01X1729689Y167725D02*
X1725689D01*
Y175125D01*
G01X1743000Y178017D02*
X1745500D01*
Y179058D01*
X1745375Y179392D01*
X1745208Y179600D01*
X1744875Y179683D01*
X1744542Y179600D01*
X1744333Y179350D01*
X1744208Y179058D01*
Y178017D01*
G01Y179058D02*
X1743000Y179683D01*
G01X1745083Y181158D02*
X1745333Y181408D01*
X1745458Y181700D01*
X1745500Y182033D01*
X1745417Y182450D01*
X1745208Y182742D01*
X1744958Y182825D01*
X1744708Y182783D01*
X1744500Y182617D01*
X1744083Y181783D01*
X1743792Y181408D01*
X1743375Y181158D01*
X1743000Y181075D01*
Y182825D01*
G01X1743375Y184133D02*
X1743167Y184383D01*
X1743042Y184675D01*
X1743000Y185050D01*
X1743083Y185425D01*
X1743250Y185717D01*
X1743542Y185925D01*
X1743875Y185967D01*
X1744208Y185883D01*
X1744417Y185675D01*
X1744583Y185383D01*
X1744625Y185092D01*
X1744583Y184800D01*
X1744417Y184425D01*
X1745500Y184550D01*
Y185675D01*
G01Y186900D02*
X1743000Y187483D01*
X1745500Y188150D01*
X1743000Y188817D01*
X1745500Y189400D01*
G01X1743000Y191750D02*
X1745500D01*
X1743708Y190208D01*
Y192292D01*
G01X1743000Y194350D02*
X1745500D01*
X1745000Y193850D01*
G01X1743000D02*
Y194850D01*
G01X1734189Y167725D02*
X1730189D01*
Y175125D01*
G01X1746500Y178017D02*
X1749000D01*
Y179058D01*
X1748875Y179392D01*
X1748708Y179600D01*
X1748375Y179683D01*
X1748042Y179600D01*
X1747833Y179350D01*
X1747708Y179058D01*
Y178017D01*
G01Y179058D02*
X1746500Y179683D01*
G01X1748583Y181158D02*
X1748833Y181408D01*
X1748958Y181700D01*
X1749000Y182033D01*
X1748917Y182450D01*
X1748708Y182742D01*
X1748458Y182825D01*
X1748208Y182783D01*
X1748000Y182617D01*
X1747583Y181783D01*
X1747292Y181408D01*
X1746875Y181158D01*
X1746500Y181075D01*
Y182825D01*
G01X1746875Y184133D02*
X1746667Y184383D01*
X1746542Y184675D01*
X1746500Y185050D01*
X1746583Y185425D01*
X1746750Y185717D01*
X1747042Y185925D01*
X1747375Y185967D01*
X1747708Y185883D01*
X1747917Y185675D01*
X1748083Y185383D01*
X1748125Y185092D01*
X1748083Y184800D01*
X1747917Y184425D01*
X1749000Y184550D01*
Y185675D01*
G01Y186900D02*
X1746500Y187483D01*
X1749000Y188150D01*
X1746500Y188817D01*
X1749000Y189400D01*
G01X1746875Y190333D02*
X1746667Y190583D01*
X1746542Y190875D01*
X1746500Y191250D01*
X1746583Y191625D01*
X1746750Y191917D01*
X1747042Y192125D01*
X1747375Y192167D01*
X1747708Y192083D01*
X1747917Y191875D01*
X1748083Y191583D01*
X1748125Y191292D01*
X1748083Y191000D01*
X1747917Y190625D01*
X1749000Y190750D01*
Y191875D01*
G01Y194350D02*
X1748917Y194017D01*
X1748708Y193767D01*
X1748458Y193600D01*
X1748125Y193475D01*
X1747750Y193433D01*
X1747375Y193475D01*
X1747042Y193600D01*
X1746792Y193767D01*
X1746583Y194017D01*
X1746500Y194350D01*
X1746583Y194683D01*
X1746792Y194933D01*
X1747042Y195100D01*
X1747375Y195225D01*
X1747750Y195267D01*
X1748125Y195225D01*
X1748458Y195100D01*
X1748708Y194933D01*
X1748917Y194683D01*
X1749000Y194350D01*
G01X1738689Y167725D02*
X1734689D01*
Y175125D01*
G01X1750000Y178017D02*
X1752500D01*
Y179058D01*
X1752375Y179392D01*
X1752208Y179600D01*
X1751875Y179683D01*
X1751542Y179600D01*
X1751333Y179350D01*
X1751208Y179058D01*
Y178017D01*
G01Y179058D02*
X1750000Y179683D01*
G01X1752083Y181158D02*
X1752333Y181408D01*
X1752458Y181700D01*
X1752500Y182033D01*
X1752417Y182450D01*
X1752208Y182742D01*
X1751958Y182825D01*
X1751708Y182783D01*
X1751500Y182617D01*
X1751083Y181783D01*
X1750792Y181408D01*
X1750375Y181158D01*
X1750000Y181075D01*
Y182825D01*
G01X1750375Y184133D02*
X1750167Y184383D01*
X1750042Y184675D01*
X1750000Y185050D01*
X1750083Y185425D01*
X1750250Y185717D01*
X1750542Y185925D01*
X1750875Y185967D01*
X1751208Y185883D01*
X1751417Y185675D01*
X1751583Y185383D01*
X1751625Y185092D01*
X1751583Y184800D01*
X1751417Y184425D01*
X1752500Y184550D01*
Y185675D01*
G01Y186900D02*
X1750000Y187483D01*
X1752500Y188150D01*
X1750000Y188817D01*
X1752500Y189400D01*
G01X1750000Y191750D02*
X1752500D01*
X1750708Y190208D01*
Y192292D01*
G01X1752500Y194350D02*
X1752417Y194017D01*
X1752208Y193767D01*
X1751958Y193600D01*
X1751625Y193475D01*
X1751250Y193433D01*
X1750875Y193475D01*
X1750542Y193600D01*
X1750292Y193767D01*
X1750083Y194017D01*
X1750000Y194350D01*
X1750083Y194683D01*
X1750292Y194933D01*
X1750542Y195100D01*
X1750875Y195225D01*
X1751250Y195267D01*
X1751625Y195225D01*
X1751958Y195100D01*
X1752208Y194933D01*
X1752417Y194683D01*
X1752500Y194350D01*
G01X1743189Y167725D02*
X1739189D01*
Y175125D01*
G01X1753500Y178017D02*
X1756000D01*
Y179058D01*
X1755875Y179392D01*
X1755708Y179600D01*
X1755375Y179683D01*
X1755042Y179600D01*
X1754833Y179350D01*
X1754708Y179058D01*
Y178017D01*
G01Y179058D02*
X1753500Y179683D01*
G01X1755583Y181158D02*
X1755833Y181408D01*
X1755958Y181700D01*
X1756000Y182033D01*
X1755917Y182450D01*
X1755708Y182742D01*
X1755458Y182825D01*
X1755208Y182783D01*
X1755000Y182617D01*
X1754583Y181783D01*
X1754292Y181408D01*
X1753875Y181158D01*
X1753500Y181075D01*
Y182825D01*
G01X1753875Y184133D02*
X1753667Y184383D01*
X1753542Y184675D01*
X1753500Y185050D01*
X1753583Y185425D01*
X1753750Y185717D01*
X1754042Y185925D01*
X1754375Y185967D01*
X1754708Y185883D01*
X1754917Y185675D01*
X1755083Y185383D01*
X1755125Y185092D01*
X1755083Y184800D01*
X1754917Y184425D01*
X1756000Y184550D01*
Y185675D01*
G01Y186900D02*
X1753500Y187483D01*
X1756000Y188150D01*
X1753500Y188817D01*
X1756000Y189400D01*
G01X1753500Y191750D02*
X1756000D01*
X1754208Y190208D01*
Y192292D01*
G01X1755583Y193558D02*
X1755833Y193808D01*
X1755958Y194100D01*
X1756000Y194433D01*
X1755917Y194850D01*
X1755708Y195142D01*
X1755458Y195225D01*
X1755208Y195183D01*
X1755000Y195017D01*
X1754583Y194183D01*
X1754292Y193808D01*
X1753875Y193558D01*
X1753500Y193475D01*
Y195225D01*
G01X1747689Y167725D02*
X1743689D01*
Y175125D01*
G01X1757000Y178017D02*
X1759500D01*
Y179058D01*
X1759375Y179392D01*
X1759208Y179600D01*
X1758875Y179683D01*
X1758542Y179600D01*
X1758333Y179350D01*
X1758208Y179058D01*
Y178017D01*
G01Y179058D02*
X1757000Y179683D01*
G01X1759083Y181158D02*
X1759333Y181408D01*
X1759458Y181700D01*
X1759500Y182033D01*
X1759417Y182450D01*
X1759208Y182742D01*
X1758958Y182825D01*
X1758708Y182783D01*
X1758500Y182617D01*
X1758083Y181783D01*
X1757792Y181408D01*
X1757375Y181158D01*
X1757000Y181075D01*
Y182825D01*
G01X1757375Y184133D02*
X1757167Y184383D01*
X1757042Y184675D01*
X1757000Y185050D01*
X1757083Y185425D01*
X1757250Y185717D01*
X1757542Y185925D01*
X1757875Y185967D01*
X1758208Y185883D01*
X1758417Y185675D01*
X1758583Y185383D01*
X1758625Y185092D01*
X1758583Y184800D01*
X1758417Y184425D01*
X1759500Y184550D01*
Y185675D01*
G01Y186900D02*
X1757000Y187483D01*
X1759500Y188150D01*
X1757000Y188817D01*
X1759500Y189400D01*
G01X1757000Y191750D02*
X1759500D01*
X1757708Y190208D01*
Y192292D01*
G01X1757000Y194850D02*
X1759500D01*
X1757708Y193308D01*
Y195392D01*
G01X1752189Y167725D02*
X1748189D01*
Y175125D01*
G01X1740383Y240420D02*
Y242920D01*
X1739342D01*
X1739008Y242795D01*
X1738800Y242628D01*
X1738717Y242295D01*
X1738800Y241962D01*
X1739050Y241753D01*
X1739342Y241628D01*
X1740383D01*
G01X1739342D02*
X1738717Y240420D01*
G01X1736450D02*
Y242920D01*
X1736950Y242420D01*
G01Y240420D02*
X1735950D01*
G01X1734600Y242920D02*
X1734017Y240420D01*
X1733350Y242920D01*
X1732683Y240420D01*
X1732100Y242920D01*
G01X1729750Y240420D02*
Y242920D01*
X1731292Y241128D01*
X1729208D01*
G01X1727150Y240420D02*
Y242920D01*
X1727650Y242420D01*
G01Y240420D02*
X1726650D01*
G01X1775933Y240700D02*
Y243200D01*
X1774892D01*
X1774558Y243075D01*
X1774350Y242908D01*
X1774267Y242575D01*
X1774350Y242242D01*
X1774600Y242033D01*
X1774892Y241908D01*
X1775933D01*
G01X1774892D02*
X1774267Y240700D01*
G01X1772000D02*
Y243200D01*
X1772500Y242700D01*
G01Y240700D02*
X1771500D01*
G01X1770150Y243200D02*
X1769567Y240700D01*
X1768900Y243200D01*
X1768233Y240700D01*
X1767650Y243200D01*
G01X1765300Y240700D02*
Y243200D01*
X1766842Y241408D01*
X1764758D01*
G01X1763492Y242783D02*
X1763242Y243033D01*
X1762950Y243158D01*
X1762617Y243200D01*
X1762200Y243117D01*
X1761908Y242908D01*
X1761825Y242658D01*
X1761867Y242408D01*
X1762033Y242200D01*
X1762867Y241783D01*
X1763242Y241492D01*
X1763492Y241075D01*
X1763575Y240700D01*
X1761825D01*
G01X1775933Y244200D02*
Y246700D01*
X1774892D01*
X1774558Y246575D01*
X1774350Y246408D01*
X1774267Y246075D01*
X1774350Y245742D01*
X1774600Y245533D01*
X1774892Y245408D01*
X1775933D01*
G01X1774892D02*
X1774267Y244200D01*
G01X1772000D02*
Y246700D01*
X1772500Y246200D01*
G01Y244200D02*
X1771500D01*
G01X1770150Y246700D02*
X1769567Y244200D01*
X1768900Y246700D01*
X1768233Y244200D01*
X1767650Y246700D01*
G01X1765300Y244200D02*
Y246700D01*
X1766842Y244908D01*
X1764758D01*
G01X1763617Y244700D02*
X1763367Y244408D01*
X1763033Y244242D01*
X1762658Y244200D01*
X1762325Y244242D01*
X1761992Y244450D01*
X1761783Y244700D01*
X1761742Y244950D01*
X1761825Y245242D01*
X1762117Y245450D01*
X1762408Y245533D01*
X1762783D01*
G01X1762408D02*
X1762158Y245658D01*
X1761950Y245867D01*
X1761867Y246117D01*
X1761950Y246367D01*
X1762158Y246575D01*
X1762533Y246700D01*
X1762908Y246658D01*
X1763283Y246492D01*
G01X1776392Y250917D02*
X1776517Y250667D01*
X1776600Y250375D01*
Y250042D01*
X1776475Y249667D01*
X1776267Y249375D01*
X1776017Y249167D01*
X1775600Y249000D01*
X1775225Y248958D01*
X1774850Y249042D01*
X1774600Y249167D01*
X1774350Y249417D01*
X1774183Y249708D01*
X1774100Y250000D01*
Y250292D01*
X1774183Y250583D01*
X1774308Y250833D01*
X1774475Y251042D01*
G01X1776183Y252308D02*
X1776433Y252558D01*
X1776558Y252850D01*
X1776600Y253183D01*
X1776517Y253600D01*
X1776308Y253892D01*
X1776058Y253975D01*
X1775808Y253933D01*
X1775600Y253767D01*
X1775183Y252933D01*
X1774892Y252558D01*
X1774475Y252308D01*
X1774100Y252225D01*
Y253975D01*
G01Y255367D02*
X1776600D01*
Y256367D01*
X1776475Y256700D01*
X1776183Y256950D01*
X1775850Y257033D01*
X1775517Y256950D01*
X1775267Y256742D01*
X1775142Y256367D01*
Y255367D01*
G01X1774100Y259300D02*
X1776600D01*
X1776100Y258800D01*
G01X1774100D02*
Y259800D01*
G01X1774600Y261483D02*
X1774308Y261733D01*
X1774142Y262067D01*
X1774100Y262442D01*
X1774142Y262775D01*
X1774350Y263108D01*
X1774600Y263317D01*
X1774850Y263358D01*
X1775142Y263275D01*
X1775350Y262983D01*
X1775433Y262692D01*
Y262317D01*
G01Y262692D02*
X1775558Y262942D01*
X1775767Y263150D01*
X1776017Y263233D01*
X1776267Y263150D01*
X1776475Y262942D01*
X1776600Y262567D01*
X1776558Y262192D01*
X1776392Y261817D01*
G01X1769392Y250917D02*
X1769517Y250667D01*
X1769600Y250375D01*
Y250042D01*
X1769475Y249667D01*
X1769267Y249375D01*
X1769017Y249167D01*
X1768600Y249000D01*
X1768225Y248958D01*
X1767850Y249042D01*
X1767600Y249167D01*
X1767350Y249417D01*
X1767183Y249708D01*
X1767100Y250000D01*
Y250292D01*
X1767183Y250583D01*
X1767308Y250833D01*
X1767475Y251042D01*
G01X1769183Y252308D02*
X1769433Y252558D01*
X1769558Y252850D01*
X1769600Y253183D01*
X1769517Y253600D01*
X1769308Y253892D01*
X1769058Y253975D01*
X1768808Y253933D01*
X1768600Y253767D01*
X1768183Y252933D01*
X1767892Y252558D01*
X1767475Y252308D01*
X1767100Y252225D01*
Y253975D01*
G01Y255367D02*
X1769600D01*
Y256367D01*
X1769475Y256700D01*
X1769183Y256950D01*
X1768850Y257033D01*
X1768517Y256950D01*
X1768267Y256742D01*
X1768142Y256367D01*
Y255367D01*
G01X1767100Y259300D02*
X1769600D01*
X1769100Y258800D01*
G01X1767100D02*
Y259800D01*
G01X1767475Y261483D02*
X1767267Y261733D01*
X1767142Y262025D01*
X1767100Y262400D01*
X1767183Y262775D01*
X1767350Y263067D01*
X1767642Y263275D01*
X1767975Y263317D01*
X1768308Y263233D01*
X1768517Y263025D01*
X1768683Y262733D01*
X1768725Y262442D01*
X1768683Y262150D01*
X1768517Y261775D01*
X1769600Y261900D01*
Y263025D01*
G01X1765892Y250917D02*
X1766017Y250667D01*
X1766100Y250375D01*
Y250042D01*
X1765975Y249667D01*
X1765767Y249375D01*
X1765517Y249167D01*
X1765100Y249000D01*
X1764725Y248958D01*
X1764350Y249042D01*
X1764100Y249167D01*
X1763850Y249417D01*
X1763683Y249708D01*
X1763600Y250000D01*
Y250292D01*
X1763683Y250583D01*
X1763808Y250833D01*
X1763975Y251042D01*
G01X1765683Y252308D02*
X1765933Y252558D01*
X1766058Y252850D01*
X1766100Y253183D01*
X1766017Y253600D01*
X1765808Y253892D01*
X1765558Y253975D01*
X1765308Y253933D01*
X1765100Y253767D01*
X1764683Y252933D01*
X1764392Y252558D01*
X1763975Y252308D01*
X1763600Y252225D01*
Y253975D01*
G01Y255367D02*
X1766100D01*
Y256367D01*
X1765975Y256700D01*
X1765683Y256950D01*
X1765350Y257033D01*
X1765017Y256950D01*
X1764767Y256742D01*
X1764642Y256367D01*
Y255367D01*
G01X1763600Y259300D02*
X1766100D01*
X1765600Y258800D01*
G01X1763600D02*
Y259800D01*
G01X1764642Y261608D02*
X1764933Y261900D01*
X1765100Y262150D01*
X1765183Y262483D01*
X1765100Y262775D01*
X1764933Y262983D01*
X1764683Y263150D01*
X1764392Y263192D01*
X1764142Y263150D01*
X1763892Y262983D01*
X1763683Y262733D01*
X1763600Y262442D01*
X1763683Y262108D01*
X1763933Y261817D01*
X1764308Y261650D01*
X1764725Y261608D01*
X1765267Y261692D01*
X1765558Y261817D01*
X1765850Y262025D01*
X1766058Y262317D01*
X1766100Y262608D01*
X1766017Y262900D01*
X1765808Y263108D01*
G01X1772892Y250917D02*
X1773017Y250667D01*
X1773100Y250375D01*
Y250042D01*
X1772975Y249667D01*
X1772767Y249375D01*
X1772517Y249167D01*
X1772100Y249000D01*
X1771725Y248958D01*
X1771350Y249042D01*
X1771100Y249167D01*
X1770850Y249417D01*
X1770683Y249708D01*
X1770600Y250000D01*
Y250292D01*
X1770683Y250583D01*
X1770808Y250833D01*
X1770975Y251042D01*
G01X1772683Y252308D02*
X1772933Y252558D01*
X1773058Y252850D01*
X1773100Y253183D01*
X1773017Y253600D01*
X1772808Y253892D01*
X1772558Y253975D01*
X1772308Y253933D01*
X1772100Y253767D01*
X1771683Y252933D01*
X1771392Y252558D01*
X1770975Y252308D01*
X1770600Y252225D01*
Y253975D01*
G01Y255367D02*
X1773100D01*
Y256367D01*
X1772975Y256700D01*
X1772683Y256950D01*
X1772350Y257033D01*
X1772017Y256950D01*
X1771767Y256742D01*
X1771642Y256367D01*
Y255367D01*
G01X1770600Y259300D02*
X1773100D01*
X1772600Y258800D01*
G01X1770600D02*
Y259800D01*
G01Y262900D02*
X1773100D01*
X1771308Y261358D01*
Y263442D01*
G01X1731358Y259450D02*
X1735804D01*
G01X1731361Y252350D02*
X1735806D01*
G01X1761492Y436497D02*
X1761617Y436247D01*
X1761700Y435955D01*
Y435622D01*
X1761575Y435247D01*
X1761367Y434955D01*
X1761117Y434747D01*
X1760700Y434580D01*
X1760325Y434538D01*
X1759950Y434622D01*
X1759700Y434747D01*
X1759450Y434997D01*
X1759283Y435288D01*
X1759200Y435580D01*
Y435872D01*
X1759283Y436163D01*
X1759408Y436413D01*
X1759575Y436622D01*
G01X1759200Y438680D02*
X1761700D01*
X1761200Y438180D01*
G01X1759200D02*
Y439180D01*
G01Y440697D02*
X1761700D01*
X1759617Y441780D01*
X1761700Y442863D01*
X1759200D01*
G01Y444880D02*
X1761700D01*
X1761200Y444380D01*
G01X1759200D02*
Y445380D01*
G01Y447980D02*
X1759242Y448272D01*
X1759367Y448605D01*
X1759575Y448813D01*
X1759867Y448897D01*
X1760158Y448813D01*
X1760408Y448563D01*
X1760533Y448188D01*
Y447772D01*
X1760617Y447522D01*
X1760825Y447313D01*
X1761117Y447230D01*
X1761408Y447355D01*
X1761617Y447647D01*
X1761700Y447980D01*
X1761617Y448313D01*
X1761408Y448605D01*
X1761117Y448730D01*
X1760825Y448647D01*
X1760617Y448438D01*
X1760533Y448188D01*
Y447772D01*
X1760408Y447397D01*
X1760158Y447147D01*
X1759867Y447063D01*
X1759575Y447147D01*
X1759367Y447355D01*
X1759242Y447688D01*
X1759200Y447980D01*
G01X1769992Y436597D02*
X1770117Y436347D01*
X1770200Y436055D01*
Y435722D01*
X1770075Y435347D01*
X1769867Y435055D01*
X1769617Y434847D01*
X1769200Y434680D01*
X1768825Y434638D01*
X1768450Y434722D01*
X1768200Y434847D01*
X1767950Y435097D01*
X1767783Y435388D01*
X1767700Y435680D01*
Y435972D01*
X1767783Y436263D01*
X1767908Y436513D01*
X1768075Y436722D01*
G01X1767700Y438780D02*
X1770200D01*
X1769700Y438280D01*
G01X1767700D02*
Y439280D01*
G01Y440797D02*
X1770200D01*
X1768117Y441880D01*
X1770200Y442963D01*
X1767700D01*
G01Y444980D02*
X1770200D01*
X1769700Y444480D01*
G01X1767700D02*
Y445480D01*
G01Y447997D02*
X1768242Y448080D01*
X1768700Y448205D01*
X1769117Y448372D01*
X1769575Y448580D01*
X1770200Y448913D01*
Y447247D01*
G01X1773992Y436597D02*
X1774117Y436347D01*
X1774200Y436055D01*
Y435722D01*
X1774075Y435347D01*
X1773867Y435055D01*
X1773617Y434847D01*
X1773200Y434680D01*
X1772825Y434638D01*
X1772450Y434722D01*
X1772200Y434847D01*
X1771950Y435097D01*
X1771783Y435388D01*
X1771700Y435680D01*
Y435972D01*
X1771783Y436263D01*
X1771908Y436513D01*
X1772075Y436722D01*
G01X1771700Y438780D02*
X1774200D01*
X1773700Y438280D01*
G01X1771700D02*
Y439280D01*
G01Y440797D02*
X1774200D01*
X1772117Y441880D01*
X1774200Y442963D01*
X1771700D01*
G01Y444980D02*
X1774200D01*
X1773700Y444480D01*
G01X1771700D02*
Y445480D01*
G01X1772742Y447288D02*
X1773033Y447580D01*
X1773200Y447830D01*
X1773283Y448163D01*
X1773200Y448455D01*
X1773033Y448663D01*
X1772783Y448830D01*
X1772492Y448872D01*
X1772242Y448830D01*
X1771992Y448663D01*
X1771783Y448413D01*
X1771700Y448122D01*
X1771783Y447788D01*
X1772033Y447497D01*
X1772408Y447330D01*
X1772825Y447288D01*
X1773367Y447372D01*
X1773658Y447497D01*
X1773950Y447705D01*
X1774158Y447997D01*
X1774200Y448288D01*
X1774117Y448580D01*
X1773908Y448788D01*
G01X1744642Y436133D02*
X1744767Y435883D01*
X1744850Y435591D01*
Y435258D01*
X1744725Y434883D01*
X1744517Y434591D01*
X1744267Y434383D01*
X1743850Y434216D01*
X1743475Y434174D01*
X1743100Y434258D01*
X1742850Y434383D01*
X1742600Y434633D01*
X1742433Y434924D01*
X1742350Y435216D01*
Y435508D01*
X1742433Y435799D01*
X1742558Y436049D01*
X1742725Y436258D01*
G01X1744433Y437524D02*
X1744683Y437774D01*
X1744808Y438066D01*
X1744850Y438399D01*
X1744767Y438816D01*
X1744558Y439108D01*
X1744308Y439191D01*
X1744058Y439149D01*
X1743850Y438983D01*
X1743433Y438149D01*
X1743142Y437774D01*
X1742725Y437524D01*
X1742350Y437441D01*
Y439191D01*
G01Y440333D02*
X1744850D01*
X1742767Y441416D01*
X1744850Y442499D01*
X1742350D01*
G01Y444516D02*
X1744850D01*
X1744350Y444016D01*
G01X1742350D02*
Y445016D01*
G01X1742725Y446699D02*
X1742517Y446949D01*
X1742392Y447241D01*
X1742350Y447616D01*
X1742433Y447991D01*
X1742600Y448283D01*
X1742892Y448491D01*
X1743225Y448533D01*
X1743558Y448449D01*
X1743767Y448241D01*
X1743933Y447949D01*
X1743975Y447658D01*
X1743933Y447366D01*
X1743767Y446991D01*
X1744850Y447116D01*
Y448241D01*
G01X1748642Y436133D02*
X1748767Y435883D01*
X1748850Y435591D01*
Y435258D01*
X1748725Y434883D01*
X1748517Y434591D01*
X1748267Y434383D01*
X1747850Y434216D01*
X1747475Y434174D01*
X1747100Y434258D01*
X1746850Y434383D01*
X1746600Y434633D01*
X1746433Y434924D01*
X1746350Y435216D01*
Y435508D01*
X1746433Y435799D01*
X1746558Y436049D01*
X1746725Y436258D01*
G01X1748433Y437524D02*
X1748683Y437774D01*
X1748808Y438066D01*
X1748850Y438399D01*
X1748767Y438816D01*
X1748558Y439108D01*
X1748308Y439191D01*
X1748058Y439149D01*
X1747850Y438983D01*
X1747433Y438149D01*
X1747142Y437774D01*
X1746725Y437524D01*
X1746350Y437441D01*
Y439191D01*
G01Y440333D02*
X1748850D01*
X1746767Y441416D01*
X1748850Y442499D01*
X1746350D01*
G01Y444516D02*
X1748850D01*
X1748350Y444016D01*
G01X1746350D02*
Y445016D01*
G01Y448116D02*
X1748850D01*
X1747058Y446574D01*
Y448658D01*
G01X1757492Y436497D02*
X1757617Y436247D01*
X1757700Y435955D01*
Y435622D01*
X1757575Y435247D01*
X1757367Y434955D01*
X1757117Y434747D01*
X1756700Y434580D01*
X1756325Y434538D01*
X1755950Y434622D01*
X1755700Y434747D01*
X1755450Y434997D01*
X1755283Y435288D01*
X1755200Y435580D01*
Y435872D01*
X1755283Y436163D01*
X1755408Y436413D01*
X1755575Y436622D01*
G01X1755200Y438680D02*
X1757700D01*
X1757200Y438180D01*
G01X1755200D02*
Y439180D01*
G01Y440697D02*
X1757700D01*
X1755617Y441780D01*
X1757700Y442863D01*
X1755200D01*
G01Y444880D02*
X1757700D01*
X1757200Y444380D01*
G01X1755200D02*
Y445380D01*
G01X1755492Y447272D02*
X1755283Y447563D01*
X1755200Y447897D01*
X1755283Y448230D01*
X1755533Y448522D01*
X1755908Y448730D01*
X1756283Y448813D01*
X1756742D01*
X1757117Y448730D01*
X1757450Y448522D01*
X1757617Y448272D01*
X1757700Y447980D01*
X1757617Y447647D01*
X1757450Y447397D01*
X1757200Y447230D01*
X1756867Y447147D01*
X1756575Y447230D01*
X1756283Y447438D01*
X1756117Y447688D01*
X1756075Y447980D01*
X1756158Y448313D01*
X1756367Y448563D01*
X1756742Y448813D01*
G01X1762533Y517167D02*
Y519667D01*
X1761492D01*
X1761158Y519542D01*
X1760950Y519375D01*
X1760867Y519042D01*
X1760950Y518709D01*
X1761200Y518500D01*
X1761492Y518375D01*
X1762533D01*
G01X1761492D02*
X1760867Y517167D01*
G01X1758600D02*
Y519667D01*
X1759100Y519167D01*
G01Y517167D02*
X1758100D01*
G01X1756583D02*
Y519667D01*
X1755500Y517584D01*
X1754417Y519667D01*
Y517167D01*
G01X1753192Y519250D02*
X1752942Y519500D01*
X1752650Y519625D01*
X1752317Y519667D01*
X1751900Y519584D01*
X1751608Y519375D01*
X1751525Y519125D01*
X1751567Y518875D01*
X1751733Y518667D01*
X1752567Y518250D01*
X1752942Y517959D01*
X1753192Y517542D01*
X1753275Y517167D01*
X1751525D01*
G01X1749300Y519667D02*
X1749633Y519584D01*
X1749883Y519375D01*
X1750050Y519125D01*
X1750175Y518792D01*
X1750217Y518417D01*
X1750175Y518042D01*
X1750050Y517709D01*
X1749883Y517459D01*
X1749633Y517250D01*
X1749300Y517167D01*
X1748967Y517250D01*
X1748717Y517459D01*
X1748550Y517709D01*
X1748425Y518042D01*
X1748383Y518417D01*
X1748425Y518792D01*
X1748550Y519125D01*
X1748717Y519375D01*
X1748967Y519584D01*
X1749300Y519667D01*
G01X1773450Y496517D02*
X1775950D01*
Y497558D01*
X1775825Y497892D01*
X1775658Y498100D01*
X1775325Y498183D01*
X1774992Y498100D01*
X1774783Y497850D01*
X1774658Y497558D01*
Y496517D01*
G01Y497558D02*
X1773450Y498183D01*
G01Y500450D02*
X1775950D01*
X1775450Y499950D01*
G01X1773450D02*
Y500950D01*
G01Y502467D02*
X1775950D01*
X1773867Y503550D01*
X1775950Y504633D01*
X1773450D01*
G01X1775533Y505858D02*
X1775783Y506108D01*
X1775908Y506400D01*
X1775950Y506733D01*
X1775867Y507150D01*
X1775658Y507442D01*
X1775408Y507525D01*
X1775158Y507483D01*
X1774950Y507317D01*
X1774533Y506483D01*
X1774242Y506108D01*
X1773825Y505858D01*
X1773450Y505775D01*
Y507525D01*
G01X1775533Y508958D02*
X1775783Y509208D01*
X1775908Y509500D01*
X1775950Y509833D01*
X1775867Y510250D01*
X1775658Y510542D01*
X1775408Y510625D01*
X1775158Y510583D01*
X1774950Y510417D01*
X1774533Y509583D01*
X1774242Y509208D01*
X1773825Y508958D01*
X1773450Y508875D01*
Y510625D01*
G01X1762759Y492517D02*
X1762884Y492267D01*
X1762967Y491975D01*
Y491642D01*
X1762842Y491267D01*
X1762634Y490975D01*
X1762384Y490767D01*
X1761967Y490600D01*
X1761592Y490558D01*
X1761217Y490642D01*
X1760967Y490767D01*
X1760717Y491017D01*
X1760550Y491308D01*
X1760467Y491600D01*
Y491892D01*
X1760550Y492183D01*
X1760675Y492433D01*
X1760842Y492642D01*
G01X1760467Y494700D02*
X1762967D01*
X1762467Y494200D01*
G01X1760467D02*
Y495200D01*
G01Y496717D02*
X1762967D01*
X1760884Y497800D01*
X1762967Y498883D01*
X1760467D01*
G01X1760967Y499983D02*
X1760675Y500233D01*
X1760509Y500567D01*
X1760467Y500942D01*
X1760509Y501275D01*
X1760717Y501608D01*
X1760967Y501817D01*
X1761217Y501858D01*
X1761509Y501775D01*
X1761717Y501483D01*
X1761800Y501192D01*
Y500817D01*
G01Y501192D02*
X1761925Y501442D01*
X1762134Y501650D01*
X1762384Y501733D01*
X1762634Y501650D01*
X1762842Y501442D01*
X1762967Y501067D01*
X1762925Y500692D01*
X1762759Y500317D01*
G01X1760842Y503083D02*
X1760634Y503333D01*
X1760509Y503625D01*
X1760467Y504000D01*
X1760550Y504375D01*
X1760717Y504667D01*
X1761009Y504875D01*
X1761342Y504917D01*
X1761675Y504833D01*
X1761884Y504625D01*
X1762050Y504333D01*
X1762092Y504042D01*
X1762050Y503750D01*
X1761884Y503375D01*
X1762967Y503500D01*
Y504625D01*
G01X1766059Y492417D02*
X1766184Y492167D01*
X1766267Y491875D01*
Y491542D01*
X1766142Y491167D01*
X1765934Y490875D01*
X1765684Y490667D01*
X1765267Y490500D01*
X1764892Y490458D01*
X1764517Y490542D01*
X1764267Y490667D01*
X1764017Y490917D01*
X1763850Y491208D01*
X1763767Y491500D01*
Y491792D01*
X1763850Y492083D01*
X1763975Y492333D01*
X1764142Y492542D01*
G01X1763767Y494600D02*
X1766267D01*
X1765767Y494100D01*
G01X1763767D02*
Y495100D01*
G01Y496617D02*
X1766267D01*
X1764184Y497700D01*
X1766267Y498783D01*
X1763767D01*
G01X1764267Y499883D02*
X1763975Y500133D01*
X1763809Y500467D01*
X1763767Y500842D01*
X1763809Y501175D01*
X1764017Y501508D01*
X1764267Y501717D01*
X1764517Y501758D01*
X1764809Y501675D01*
X1765017Y501383D01*
X1765100Y501092D01*
Y500717D01*
G01Y501092D02*
X1765225Y501342D01*
X1765434Y501550D01*
X1765684Y501633D01*
X1765934Y501550D01*
X1766142Y501342D01*
X1766267Y500967D01*
X1766225Y500592D01*
X1766059Y500217D01*
G01X1763767Y504400D02*
X1766267D01*
X1764475Y502858D01*
Y504942D01*
G01X1747100Y504333D02*
X1745308D01*
X1744933Y504500D01*
X1744683Y504833D01*
X1744600Y505250D01*
X1744683Y505667D01*
X1744933Y506000D01*
X1745308Y506167D01*
X1747100D01*
G01X1746683Y507558D02*
X1746933Y507808D01*
X1747058Y508100D01*
X1747100Y508433D01*
X1747017Y508850D01*
X1746808Y509142D01*
X1746558Y509225D01*
X1746308Y509183D01*
X1746100Y509017D01*
X1745683Y508183D01*
X1745392Y507808D01*
X1744975Y507558D01*
X1744600Y507475D01*
Y509225D01*
G01Y510367D02*
X1747100D01*
X1745017Y511450D01*
X1747100Y512533D01*
X1744600D01*
G01Y514550D02*
X1747100D01*
X1746600Y514050D01*
G01X1744600D02*
Y515050D01*
G01X1744550Y568900D02*
Y575900D01*
G01X1738950D02*
Y568900D01*
G01Y572400D02*
X1744550D01*
G01X1731200Y554300D02*
X1736600D01*
G01X1721400D02*
X1719700D01*
Y581000D01*
X1728000D01*
Y580000D01*
X1729000D01*
G01X1747500Y554300D02*
X1752000D01*
G01X1761300D02*
X1766000D01*
G01X1748500Y604700D02*
Y584000D01*
X1736500D01*
Y580000D01*
X1735500D01*
G01X1717692Y562317D02*
X1717817Y562067D01*
X1717900Y561775D01*
Y561442D01*
X1717775Y561067D01*
X1717567Y560775D01*
X1717317Y560567D01*
X1716900Y560400D01*
X1716525Y560358D01*
X1716150Y560442D01*
X1715900Y560567D01*
X1715650Y560817D01*
X1715483Y561108D01*
X1715400Y561400D01*
Y561692D01*
X1715483Y561983D01*
X1715608Y562233D01*
X1715775Y562442D01*
G01X1717483Y563708D02*
X1717733Y563958D01*
X1717858Y564250D01*
X1717900Y564583D01*
X1717817Y565000D01*
X1717608Y565292D01*
X1717358Y565375D01*
X1717108Y565333D01*
X1716900Y565167D01*
X1716483Y564333D01*
X1716192Y563958D01*
X1715775Y563708D01*
X1715400Y563625D01*
Y565375D01*
G01X1717900Y566767D02*
X1715400D01*
Y568433D01*
G01Y571200D02*
X1717900D01*
X1716108Y569658D01*
Y571742D01*
G01X1715692Y573092D02*
X1715483Y573383D01*
X1715400Y573717D01*
X1715483Y574050D01*
X1715733Y574342D01*
X1716108Y574550D01*
X1716483Y574633D01*
X1716942D01*
X1717317Y574550D01*
X1717650Y574342D01*
X1717817Y574092D01*
X1717900Y573800D01*
X1717817Y573467D01*
X1717650Y573217D01*
X1717400Y573050D01*
X1717067Y572967D01*
X1716775Y573050D01*
X1716483Y573258D01*
X1716317Y573508D01*
X1716275Y573800D01*
X1716358Y574133D01*
X1716567Y574383D01*
X1716942Y574633D01*
G01X1716492Y578367D02*
X1716617Y578117D01*
X1716700Y577825D01*
Y577492D01*
X1716575Y577117D01*
X1716367Y576825D01*
X1716117Y576617D01*
X1715700Y576450D01*
X1715325Y576408D01*
X1714950Y576492D01*
X1714700Y576617D01*
X1714450Y576867D01*
X1714283Y577158D01*
X1714200Y577450D01*
Y577742D01*
X1714283Y578033D01*
X1714408Y578283D01*
X1714575Y578492D01*
G01X1716283Y579758D02*
X1716533Y580008D01*
X1716658Y580300D01*
X1716700Y580633D01*
X1716617Y581050D01*
X1716408Y581342D01*
X1716158Y581425D01*
X1715908Y581383D01*
X1715700Y581217D01*
X1715283Y580383D01*
X1714992Y580008D01*
X1714575Y579758D01*
X1714200Y579675D01*
Y581425D01*
G01X1714575Y582733D02*
X1714367Y582983D01*
X1714242Y583275D01*
X1714200Y583650D01*
X1714283Y584025D01*
X1714450Y584317D01*
X1714742Y584525D01*
X1715075Y584567D01*
X1715408Y584483D01*
X1715617Y584275D01*
X1715783Y583983D01*
X1715825Y583692D01*
X1715783Y583400D01*
X1715617Y583025D01*
X1716700Y583150D01*
Y584275D01*
G01Y585500D02*
X1714200Y586083D01*
X1716700Y586750D01*
X1714200Y587417D01*
X1716700Y588000D01*
G01X1714492Y589142D02*
X1714283Y589433D01*
X1714200Y589767D01*
X1714283Y590100D01*
X1714533Y590392D01*
X1714908Y590600D01*
X1715283Y590683D01*
X1715742D01*
X1716117Y590600D01*
X1716450Y590392D01*
X1716617Y590142D01*
X1716700Y589850D01*
X1716617Y589517D01*
X1716450Y589267D01*
X1716200Y589100D01*
X1715867Y589017D01*
X1715575Y589100D01*
X1715283Y589308D01*
X1715117Y589558D01*
X1715075Y589850D01*
X1715158Y590183D01*
X1715367Y590433D01*
X1715742Y590683D01*
G01X1714200Y593450D02*
X1716700D01*
X1714908Y591908D01*
Y593992D01*
G01X1723134Y570614D02*
X1722134Y571614D01*
G01Y569614D02*
X1723134Y570614D01*
G01X1722134Y572814D02*
Y568414D01*
G01X1736934Y572814D02*
X1722134D01*
G01X1736934Y568414D02*
Y572814D01*
G01X1722134Y568414D02*
X1736934D01*
G01X1771350Y565650D02*
X1771650D01*
G01X1778750Y569650D02*
Y565650D01*
X1771350D01*
G01Y569695D02*
X1771650D01*
G01X1778750Y573695D02*
Y569695D01*
X1771350D01*
G01X1776000Y589500D02*
Y596500D01*
X1781000D01*
Y602500D01*
X1778500D01*
Y608500D01*
X1749600D01*
G01X1739392Y609018D02*
Y611518D01*
X1738351D01*
X1738017Y611393D01*
X1737809Y611226D01*
X1737726Y610893D01*
X1737809Y610560D01*
X1738059Y610351D01*
X1738351Y610226D01*
X1739392D01*
G01X1738351D02*
X1737726Y609018D01*
G01X1736251Y611101D02*
X1736001Y611351D01*
X1735709Y611476D01*
X1735376Y611518D01*
X1734959Y611435D01*
X1734667Y611226D01*
X1734584Y610976D01*
X1734626Y610726D01*
X1734792Y610518D01*
X1735626Y610101D01*
X1736001Y609810D01*
X1736251Y609393D01*
X1736334Y609018D01*
X1734584D01*
G01X1733276Y609393D02*
X1733026Y609185D01*
X1732734Y609060D01*
X1732359Y609018D01*
X1731984Y609101D01*
X1731692Y609268D01*
X1731484Y609560D01*
X1731442Y609893D01*
X1731526Y610226D01*
X1731734Y610435D01*
X1732026Y610601D01*
X1732317Y610643D01*
X1732609Y610601D01*
X1732984Y610435D01*
X1732859Y611518D01*
X1731734D01*
G01X1730509D02*
X1729926Y609018D01*
X1729259Y611518D01*
X1728592Y609018D01*
X1728009Y611518D01*
G01X1726159Y609018D02*
Y611518D01*
X1726659Y611018D01*
G01Y609018D02*
X1725659D01*
G01X1723851Y610060D02*
X1723559Y610351D01*
X1723309Y610518D01*
X1722976Y610601D01*
X1722684Y610518D01*
X1722476Y610351D01*
X1722309Y610101D01*
X1722267Y609810D01*
X1722309Y609560D01*
X1722476Y609310D01*
X1722726Y609101D01*
X1723017Y609018D01*
X1723351Y609101D01*
X1723642Y609351D01*
X1723809Y609726D01*
X1723851Y610143D01*
X1723767Y610685D01*
X1723642Y610976D01*
X1723434Y611268D01*
X1723142Y611476D01*
X1722851Y611518D01*
X1722559Y611435D01*
X1722351Y611226D01*
G01X1720042Y609018D02*
X1719959Y609560D01*
X1719834Y610018D01*
X1719667Y610435D01*
X1719459Y610893D01*
X1719126Y611518D01*
X1720792D01*
G01X1739559Y605419D02*
Y607919D01*
X1738518D01*
X1738184Y607794D01*
X1737976Y607627D01*
X1737893Y607294D01*
X1737976Y606961D01*
X1738226Y606752D01*
X1738518Y606627D01*
X1739559D01*
G01X1738518D02*
X1737893Y605419D01*
G01X1736418Y607502D02*
X1736168Y607752D01*
X1735876Y607877D01*
X1735543Y607919D01*
X1735126Y607836D01*
X1734834Y607627D01*
X1734751Y607377D01*
X1734793Y607127D01*
X1734959Y606919D01*
X1735793Y606502D01*
X1736168Y606211D01*
X1736418Y605794D01*
X1736501Y605419D01*
X1734751D01*
G01X1733443Y605794D02*
X1733193Y605586D01*
X1732901Y605461D01*
X1732526Y605419D01*
X1732151Y605502D01*
X1731859Y605669D01*
X1731651Y605961D01*
X1731609Y606294D01*
X1731693Y606627D01*
X1731901Y606836D01*
X1732193Y607002D01*
X1732484Y607044D01*
X1732776Y607002D01*
X1733151Y606836D01*
X1733026Y607919D01*
X1731901D01*
G01X1730676D02*
X1730093Y605419D01*
X1729426Y607919D01*
X1728759Y605419D01*
X1728176Y607919D01*
G01X1726326Y605419D02*
Y607919D01*
X1726826Y607419D01*
G01Y605419D02*
X1725826D01*
G01X1724018Y606461D02*
X1723726Y606752D01*
X1723476Y606919D01*
X1723143Y607002D01*
X1722851Y606919D01*
X1722643Y606752D01*
X1722476Y606502D01*
X1722434Y606211D01*
X1722476Y605961D01*
X1722643Y605711D01*
X1722893Y605502D01*
X1723184Y605419D01*
X1723518Y605502D01*
X1723809Y605752D01*
X1723976Y606127D01*
X1724018Y606544D01*
X1723934Y607086D01*
X1723809Y607377D01*
X1723601Y607669D01*
X1723309Y607877D01*
X1723018Y607919D01*
X1722726Y607836D01*
X1722518Y607627D01*
G01X1720834Y605711D02*
X1720543Y605502D01*
X1720209Y605419D01*
X1719876Y605502D01*
X1719584Y605752D01*
X1719376Y606127D01*
X1719293Y606502D01*
Y606961D01*
X1719376Y607336D01*
X1719584Y607669D01*
X1719834Y607836D01*
X1720126Y607919D01*
X1720459Y607836D01*
X1720709Y607669D01*
X1720876Y607419D01*
X1720959Y607086D01*
X1720876Y606794D01*
X1720668Y606502D01*
X1720418Y606336D01*
X1720126Y606294D01*
X1719793Y606377D01*
X1719543Y606586D01*
X1719293Y606961D01*
G01X1747568Y600691D02*
Y603191D01*
X1746527D01*
X1746193Y603066D01*
X1745985Y602899D01*
X1745902Y602566D01*
X1745985Y602233D01*
X1746235Y602024D01*
X1746527Y601899D01*
X1747568D01*
G01X1746527D02*
X1745902Y600691D01*
G01X1744427Y602774D02*
X1744177Y603024D01*
X1743885Y603149D01*
X1743552Y603191D01*
X1743135Y603108D01*
X1742843Y602899D01*
X1742760Y602649D01*
X1742802Y602399D01*
X1742968Y602191D01*
X1743802Y601774D01*
X1744177Y601483D01*
X1744427Y601066D01*
X1744510Y600691D01*
X1742760D01*
G01X1741452Y601066D02*
X1741202Y600858D01*
X1740910Y600733D01*
X1740535Y600691D01*
X1740160Y600774D01*
X1739868Y600941D01*
X1739660Y601233D01*
X1739618Y601566D01*
X1739702Y601899D01*
X1739910Y602108D01*
X1740202Y602274D01*
X1740493Y602316D01*
X1740785Y602274D01*
X1741160Y602108D01*
X1741035Y603191D01*
X1739910D01*
G01X1738685D02*
X1738102Y600691D01*
X1737435Y603191D01*
X1736768Y600691D01*
X1736185Y603191D01*
G01X1734335Y600691D02*
Y603191D01*
X1734835Y602691D01*
G01Y600691D02*
X1733835D01*
G01X1732027Y601733D02*
X1731735Y602024D01*
X1731485Y602191D01*
X1731152Y602274D01*
X1730860Y602191D01*
X1730652Y602024D01*
X1730485Y601774D01*
X1730443Y601483D01*
X1730485Y601233D01*
X1730652Y600983D01*
X1730902Y600774D01*
X1731193Y600691D01*
X1731527Y600774D01*
X1731818Y601024D01*
X1731985Y601399D01*
X1732027Y601816D01*
X1731943Y602358D01*
X1731818Y602649D01*
X1731610Y602941D01*
X1731318Y603149D01*
X1731027Y603191D01*
X1730735Y603108D01*
X1730527Y602899D01*
G01X1728135Y600691D02*
X1727843Y600733D01*
X1727510Y600858D01*
X1727302Y601066D01*
X1727218Y601358D01*
X1727302Y601649D01*
X1727552Y601899D01*
X1727927Y602024D01*
X1728343D01*
X1728593Y602108D01*
X1728802Y602316D01*
X1728885Y602608D01*
X1728760Y602899D01*
X1728468Y603108D01*
X1728135Y603191D01*
X1727802Y603108D01*
X1727510Y602899D01*
X1727385Y602608D01*
X1727468Y602316D01*
X1727677Y602108D01*
X1727927Y602024D01*
X1728343D01*
X1728718Y601899D01*
X1728968Y601649D01*
X1729052Y601358D01*
X1728968Y601066D01*
X1728760Y600858D01*
X1728427Y600733D01*
X1728135Y600691D01*
G01X1784959Y621898D02*
Y620106D01*
X1784792Y619731D01*
X1784459Y619481D01*
X1784042Y619398D01*
X1783625Y619481D01*
X1783292Y619731D01*
X1783125Y620106D01*
Y621898D01*
G01X1781734Y621481D02*
X1781484Y621731D01*
X1781192Y621856D01*
X1780859Y621898D01*
X1780442Y621815D01*
X1780150Y621606D01*
X1780067Y621356D01*
X1780109Y621106D01*
X1780275Y620898D01*
X1781109Y620481D01*
X1781484Y620190D01*
X1781734Y619773D01*
X1781817Y619398D01*
X1780067D01*
G01X1778759Y619773D02*
X1778509Y619565D01*
X1778217Y619440D01*
X1777842Y619398D01*
X1777467Y619481D01*
X1777175Y619648D01*
X1776967Y619940D01*
X1776925Y620273D01*
X1777009Y620606D01*
X1777217Y620815D01*
X1777509Y620981D01*
X1777800Y621023D01*
X1778092Y620981D01*
X1778467Y620815D01*
X1778342Y621898D01*
X1777217D01*
G01X1775992D02*
X1775409Y619398D01*
X1774742Y621898D01*
X1774075Y619398D01*
X1773492Y621898D01*
G01X1771642Y619398D02*
Y621898D01*
X1772142Y621398D01*
G01Y619398D02*
X1771142D01*
G01X1768542D02*
X1768250Y619440D01*
X1767917Y619565D01*
X1767709Y619773D01*
X1767625Y620065D01*
X1767709Y620356D01*
X1767959Y620606D01*
X1768334Y620731D01*
X1768750D01*
X1769000Y620815D01*
X1769209Y621023D01*
X1769292Y621315D01*
X1769167Y621606D01*
X1768875Y621815D01*
X1768542Y621898D01*
X1768209Y621815D01*
X1767917Y621606D01*
X1767792Y621315D01*
X1767875Y621023D01*
X1768084Y620815D01*
X1768334Y620731D01*
X1768750D01*
X1769125Y620606D01*
X1769375Y620356D01*
X1769459Y620065D01*
X1769375Y619773D01*
X1769167Y619565D01*
X1768834Y619440D01*
X1768542Y619398D01*
G01X1765406Y623540D02*
Y621748D01*
X1765239Y621373D01*
X1764906Y621123D01*
X1764489Y621040D01*
X1764072Y621123D01*
X1763739Y621373D01*
X1763572Y621748D01*
Y623540D01*
G01X1762181Y623123D02*
X1761931Y623373D01*
X1761639Y623498D01*
X1761306Y623540D01*
X1760889Y623457D01*
X1760597Y623248D01*
X1760514Y622998D01*
X1760556Y622748D01*
X1760722Y622540D01*
X1761556Y622123D01*
X1761931Y621832D01*
X1762181Y621415D01*
X1762264Y621040D01*
X1760514D01*
G01X1759206Y621415D02*
X1758956Y621207D01*
X1758664Y621082D01*
X1758289Y621040D01*
X1757914Y621123D01*
X1757622Y621290D01*
X1757414Y621582D01*
X1757372Y621915D01*
X1757456Y622248D01*
X1757664Y622457D01*
X1757956Y622623D01*
X1758247Y622665D01*
X1758539Y622623D01*
X1758914Y622457D01*
X1758789Y623540D01*
X1757664D01*
G01X1756439D02*
X1755856Y621040D01*
X1755189Y623540D01*
X1754522Y621040D01*
X1753939Y623540D01*
G01X1752089Y621040D02*
Y623540D01*
X1752589Y623040D01*
G01Y621040D02*
X1751589D01*
G01X1749072D02*
X1748989Y621582D01*
X1748864Y622040D01*
X1748697Y622457D01*
X1748489Y622915D01*
X1748156Y623540D01*
X1749822D01*
G01X1784824Y617760D02*
X1785074Y617885D01*
X1785366Y617968D01*
X1785699D01*
X1786074Y617843D01*
X1786366Y617635D01*
X1786574Y617385D01*
X1786741Y616968D01*
X1786783Y616593D01*
X1786699Y616218D01*
X1786574Y615968D01*
X1786324Y615718D01*
X1786033Y615551D01*
X1785741Y615468D01*
X1785449D01*
X1785158Y615551D01*
X1784908Y615676D01*
X1784699Y615843D01*
G01X1783433Y617551D02*
X1783183Y617801D01*
X1782891Y617926D01*
X1782558Y617968D01*
X1782141Y617885D01*
X1781849Y617676D01*
X1781766Y617426D01*
X1781808Y617176D01*
X1781974Y616968D01*
X1782808Y616551D01*
X1783183Y616260D01*
X1783433Y615843D01*
X1783516Y615468D01*
X1781766D01*
G01X1780458Y615843D02*
X1780208Y615635D01*
X1779916Y615510D01*
X1779541Y615468D01*
X1779166Y615551D01*
X1778874Y615718D01*
X1778666Y616010D01*
X1778624Y616343D01*
X1778708Y616676D01*
X1778916Y616885D01*
X1779208Y617051D01*
X1779499Y617093D01*
X1779791Y617051D01*
X1780166Y616885D01*
X1780041Y617968D01*
X1778916D01*
G01X1777691D02*
X1777108Y615468D01*
X1776441Y617968D01*
X1775774Y615468D01*
X1775191Y617968D01*
G01X1773341Y615468D02*
Y617968D01*
X1773841Y617468D01*
G01Y615468D02*
X1772841D01*
G01X1770241Y617968D02*
X1770574Y617885D01*
X1770824Y617676D01*
X1770991Y617426D01*
X1771116Y617093D01*
X1771158Y616718D01*
X1771116Y616343D01*
X1770991Y616010D01*
X1770824Y615760D01*
X1770574Y615551D01*
X1770241Y615468D01*
X1769908Y615551D01*
X1769658Y615760D01*
X1769491Y616010D01*
X1769366Y616343D01*
X1769324Y616718D01*
X1769366Y617093D01*
X1769491Y617426D01*
X1769658Y617676D01*
X1769908Y617885D01*
X1770241Y617968D01*
G01X1767141D02*
X1767474Y617885D01*
X1767724Y617676D01*
X1767891Y617426D01*
X1768016Y617093D01*
X1768058Y616718D01*
X1768016Y616343D01*
X1767891Y616010D01*
X1767724Y615760D01*
X1767474Y615551D01*
X1767141Y615468D01*
X1766808Y615551D01*
X1766558Y615760D01*
X1766391Y616010D01*
X1766266Y616343D01*
X1766224Y616718D01*
X1766266Y617093D01*
X1766391Y617426D01*
X1766558Y617676D01*
X1766808Y617885D01*
X1767141Y617968D01*
G01X1735612Y623481D02*
X1735862Y623606D01*
X1736154Y623689D01*
X1736487D01*
X1736862Y623564D01*
X1737154Y623356D01*
X1737362Y623106D01*
X1737529Y622689D01*
X1737571Y622314D01*
X1737487Y621939D01*
X1737362Y621689D01*
X1737112Y621439D01*
X1736821Y621272D01*
X1736529Y621189D01*
X1736237D01*
X1735946Y621272D01*
X1735696Y621397D01*
X1735487Y621564D01*
G01X1734221Y623272D02*
X1733971Y623522D01*
X1733679Y623647D01*
X1733346Y623689D01*
X1732929Y623606D01*
X1732637Y623397D01*
X1732554Y623147D01*
X1732596Y622897D01*
X1732762Y622689D01*
X1733596Y622272D01*
X1733971Y621981D01*
X1734221Y621564D01*
X1734304Y621189D01*
X1732554D01*
G01X1731246Y621564D02*
X1730996Y621356D01*
X1730704Y621231D01*
X1730329Y621189D01*
X1729954Y621272D01*
X1729662Y621439D01*
X1729454Y621731D01*
X1729412Y622064D01*
X1729496Y622397D01*
X1729704Y622606D01*
X1729996Y622772D01*
X1730287Y622814D01*
X1730579Y622772D01*
X1730954Y622606D01*
X1730829Y623689D01*
X1729704D01*
G01X1728479D02*
X1727896Y621189D01*
X1727229Y623689D01*
X1726562Y621189D01*
X1725979Y623689D01*
G01X1724837Y621481D02*
X1724546Y621272D01*
X1724212Y621189D01*
X1723879Y621272D01*
X1723587Y621522D01*
X1723379Y621897D01*
X1723296Y622272D01*
Y622731D01*
X1723379Y623106D01*
X1723587Y623439D01*
X1723837Y623606D01*
X1724129Y623689D01*
X1724462Y623606D01*
X1724712Y623439D01*
X1724879Y623189D01*
X1724962Y622856D01*
X1724879Y622564D01*
X1724671Y622272D01*
X1724421Y622106D01*
X1724129Y622064D01*
X1723796Y622147D01*
X1723546Y622356D01*
X1723296Y622731D01*
G01X1721737Y621481D02*
X1721446Y621272D01*
X1721112Y621189D01*
X1720779Y621272D01*
X1720487Y621522D01*
X1720279Y621897D01*
X1720196Y622272D01*
Y622731D01*
X1720279Y623106D01*
X1720487Y623439D01*
X1720737Y623606D01*
X1721029Y623689D01*
X1721362Y623606D01*
X1721612Y623439D01*
X1721779Y623189D01*
X1721862Y622856D01*
X1721779Y622564D01*
X1721571Y622272D01*
X1721321Y622106D01*
X1721029Y622064D01*
X1720696Y622147D01*
X1720446Y622356D01*
X1720196Y622731D01*
G01X1767900Y598500D02*
Y601000D01*
G01X1770150Y593750D02*
X1773400D01*
Y597250D01*
G01X1770150Y605750D02*
X1773400D01*
Y602250D01*
G01X1714680Y605168D02*
X1717180D01*
Y606752D01*
G01X1715972Y606168D02*
Y605168D01*
G01X1716013Y609393D02*
X1716138Y609560D01*
X1716347Y609685D01*
X1716638Y609768D01*
X1716888Y609685D01*
X1717055Y609518D01*
X1717180Y609227D01*
Y608102D01*
X1714680D01*
Y609477D01*
X1714847Y609768D01*
X1715097Y609935D01*
X1715388Y610018D01*
X1715680Y609935D01*
X1715930Y609685D01*
X1716013Y609393D01*
Y608102D01*
G01X1716763Y611368D02*
X1717013Y611618D01*
X1717138Y611910D01*
X1717180Y612243D01*
X1717097Y612660D01*
X1716888Y612952D01*
X1716638Y613035D01*
X1716388Y612993D01*
X1716180Y612827D01*
X1715763Y611993D01*
X1715472Y611618D01*
X1715055Y611368D01*
X1714680Y611285D01*
Y613035D01*
G01X1715055Y614343D02*
X1714847Y614593D01*
X1714722Y614885D01*
X1714680Y615260D01*
X1714763Y615635D01*
X1714930Y615927D01*
X1715222Y616135D01*
X1715555Y616177D01*
X1715888Y616093D01*
X1716097Y615885D01*
X1716263Y615593D01*
X1716305Y615302D01*
X1716263Y615010D01*
X1716097Y614635D01*
X1717180Y614760D01*
Y615885D01*
G01Y617110D02*
X1714680Y617693D01*
X1717180Y618360D01*
X1714680Y619027D01*
X1717180Y619610D01*
G01X1715180Y620543D02*
X1714888Y620793D01*
X1714722Y621127D01*
X1714680Y621502D01*
X1714722Y621835D01*
X1714930Y622168D01*
X1715180Y622377D01*
X1715430Y622418D01*
X1715722Y622335D01*
X1715930Y622043D01*
X1716013Y621752D01*
Y621377D01*
G01Y621752D02*
X1716138Y622002D01*
X1716347Y622210D01*
X1716597Y622293D01*
X1716847Y622210D01*
X1717055Y622002D01*
X1717180Y621627D01*
X1717138Y621252D01*
X1716972Y620877D01*
G01X1719808Y603405D02*
Y603105D01*
G01X1723808Y596005D02*
X1719808D01*
Y603405D01*
G01X1821128Y4870D02*
Y7370D01*
X1820087D01*
X1819753Y7245D01*
X1819545Y7078D01*
X1819462Y6745D01*
X1819545Y6412D01*
X1819795Y6203D01*
X1820087Y6078D01*
X1821128D01*
G01X1820087D02*
X1819462Y4870D01*
G01X1817987Y6953D02*
X1817737Y7203D01*
X1817445Y7328D01*
X1817112Y7370D01*
X1816695Y7287D01*
X1816403Y7078D01*
X1816320Y6828D01*
X1816362Y6578D01*
X1816528Y6370D01*
X1817362Y5953D01*
X1817737Y5662D01*
X1817987Y5245D01*
X1818070Y4870D01*
X1816320D01*
G01X1815012Y7370D02*
Y5578D01*
X1814845Y5203D01*
X1814512Y4953D01*
X1814095Y4870D01*
X1813678Y4953D01*
X1813345Y5203D01*
X1813178Y5578D01*
Y7370D01*
G01X1810495Y4870D02*
Y7370D01*
X1812037Y5578D01*
X1809953D01*
G01X1807895Y4870D02*
X1807603Y4912D01*
X1807270Y5037D01*
X1807062Y5245D01*
X1806978Y5537D01*
X1807062Y5828D01*
X1807312Y6078D01*
X1807687Y6203D01*
X1808103D01*
X1808353Y6287D01*
X1808562Y6495D01*
X1808645Y6787D01*
X1808520Y7078D01*
X1808228Y7287D01*
X1807895Y7370D01*
X1807562Y7287D01*
X1807270Y7078D01*
X1807145Y6787D01*
X1807228Y6495D01*
X1807437Y6287D01*
X1807687Y6203D01*
X1808103D01*
X1808478Y6078D01*
X1808728Y5828D01*
X1808812Y5537D01*
X1808728Y5245D01*
X1808520Y5037D01*
X1808187Y4912D01*
X1807895Y4870D01*
G01X1836833Y5767D02*
Y8267D01*
X1835792D01*
X1835458Y8142D01*
X1835250Y7975D01*
X1835167Y7642D01*
X1835250Y7309D01*
X1835500Y7100D01*
X1835792Y6975D01*
X1836833D01*
G01X1835792D02*
X1835167Y5767D01*
G01X1833692Y7850D02*
X1833442Y8100D01*
X1833150Y8225D01*
X1832817Y8267D01*
X1832400Y8184D01*
X1832108Y7975D01*
X1832025Y7725D01*
X1832067Y7475D01*
X1832233Y7267D01*
X1833067Y6850D01*
X1833442Y6559D01*
X1833692Y6142D01*
X1833775Y5767D01*
X1832025D01*
G01X1830717Y8267D02*
Y6475D01*
X1830550Y6100D01*
X1830217Y5850D01*
X1829800Y5767D01*
X1829383Y5850D01*
X1829050Y6100D01*
X1828883Y6475D01*
Y8267D01*
G01X1827617Y6142D02*
X1827367Y5934D01*
X1827075Y5809D01*
X1826700Y5767D01*
X1826325Y5850D01*
X1826033Y6017D01*
X1825825Y6309D01*
X1825783Y6642D01*
X1825867Y6975D01*
X1826075Y7184D01*
X1826367Y7350D01*
X1826658Y7392D01*
X1826950Y7350D01*
X1827325Y7184D01*
X1827200Y8267D01*
X1826075D01*
G01X1823600D02*
X1823933Y8184D01*
X1824183Y7975D01*
X1824350Y7725D01*
X1824475Y7392D01*
X1824517Y7017D01*
X1824475Y6642D01*
X1824350Y6309D01*
X1824183Y6059D01*
X1823933Y5850D01*
X1823600Y5767D01*
X1823267Y5850D01*
X1823017Y6059D01*
X1822850Y6309D01*
X1822725Y6642D01*
X1822683Y7017D01*
X1822725Y7392D01*
X1822850Y7725D01*
X1823017Y7975D01*
X1823267Y8184D01*
X1823600Y8267D01*
G01X1842133Y22700D02*
Y25200D01*
X1841092D01*
X1840758Y25075D01*
X1840550Y24908D01*
X1840467Y24575D01*
X1840550Y24242D01*
X1840800Y24033D01*
X1841092Y23908D01*
X1842133D01*
G01X1841092D02*
X1840467Y22700D01*
G01X1838283D02*
X1838200Y23242D01*
X1838075Y23700D01*
X1837908Y24117D01*
X1837700Y24575D01*
X1837367Y25200D01*
X1839033D01*
G01X1834267Y22700D02*
X1835933D01*
Y25200D01*
X1834267D01*
G01X1834933Y23992D02*
X1835933D01*
G01X1832792Y24783D02*
X1832542Y25033D01*
X1832250Y25158D01*
X1831917Y25200D01*
X1831500Y25117D01*
X1831208Y24908D01*
X1831125Y24658D01*
X1831167Y24408D01*
X1831333Y24200D01*
X1832167Y23783D01*
X1832542Y23492D01*
X1832792Y23075D01*
X1832875Y22700D01*
X1831125D01*
G01X1828900D02*
Y25200D01*
X1829400Y24700D01*
G01Y22700D02*
X1828400D01*
G01X1789115Y443D02*
Y2943D01*
X1788074D01*
X1787740Y2818D01*
X1787532Y2651D01*
X1787449Y2318D01*
X1787532Y1985D01*
X1787782Y1776D01*
X1788074Y1651D01*
X1789115D01*
G01X1788074D02*
X1787449Y443D01*
G01X1785182D02*
Y2943D01*
X1785682Y2443D01*
G01Y443D02*
X1784682D01*
G01X1782999Y2943D02*
Y1151D01*
X1782832Y776D01*
X1782499Y526D01*
X1782082Y443D01*
X1781665Y526D01*
X1781332Y776D01*
X1781165Y1151D01*
Y2943D01*
G01X1779774Y1485D02*
X1779482Y1776D01*
X1779232Y1943D01*
X1778899Y2026D01*
X1778607Y1943D01*
X1778399Y1776D01*
X1778232Y1526D01*
X1778190Y1235D01*
X1778232Y985D01*
X1778399Y735D01*
X1778649Y526D01*
X1778940Y443D01*
X1779274Y526D01*
X1779565Y776D01*
X1779732Y1151D01*
X1779774Y1568D01*
X1779690Y2110D01*
X1779565Y2401D01*
X1779357Y2693D01*
X1779065Y2901D01*
X1778774Y2943D01*
X1778482Y2860D01*
X1778274Y2651D01*
G01X1776799Y943D02*
X1776549Y651D01*
X1776215Y485D01*
X1775840Y443D01*
X1775507Y485D01*
X1775174Y693D01*
X1774965Y943D01*
X1774924Y1193D01*
X1775007Y1485D01*
X1775299Y1693D01*
X1775590Y1776D01*
X1775965D01*
G01X1775590D02*
X1775340Y1901D01*
X1775132Y2110D01*
X1775049Y2360D01*
X1775132Y2610D01*
X1775340Y2818D01*
X1775715Y2943D01*
X1776090Y2901D01*
X1776465Y2735D01*
G01X1789058Y4143D02*
Y6643D01*
X1788017D01*
X1787683Y6518D01*
X1787475Y6351D01*
X1787392Y6018D01*
X1787475Y5685D01*
X1787725Y5476D01*
X1788017Y5351D01*
X1789058D01*
G01X1788017D02*
X1787392Y4143D01*
G01X1785125D02*
Y6643D01*
X1785625Y6143D01*
G01Y4143D02*
X1784625D01*
G01X1782942Y6643D02*
Y4851D01*
X1782775Y4476D01*
X1782442Y4226D01*
X1782025Y4143D01*
X1781608Y4226D01*
X1781275Y4476D01*
X1781108Y4851D01*
Y6643D01*
G01X1779717Y5185D02*
X1779425Y5476D01*
X1779175Y5643D01*
X1778842Y5726D01*
X1778550Y5643D01*
X1778342Y5476D01*
X1778175Y5226D01*
X1778133Y4935D01*
X1778175Y4685D01*
X1778342Y4435D01*
X1778592Y4226D01*
X1778883Y4143D01*
X1779217Y4226D01*
X1779508Y4476D01*
X1779675Y4851D01*
X1779717Y5268D01*
X1779633Y5810D01*
X1779508Y6101D01*
X1779300Y6393D01*
X1779008Y6601D01*
X1778717Y6643D01*
X1778425Y6560D01*
X1778217Y6351D01*
G01X1775325Y4143D02*
Y6643D01*
X1776867Y4851D01*
X1774783D01*
G01X1803245Y23772D02*
X1805745D01*
Y24813D01*
X1805620Y25147D01*
X1805453Y25355D01*
X1805120Y25438D01*
X1804787Y25355D01*
X1804578Y25105D01*
X1804453Y24813D01*
Y23772D01*
G01Y24813D02*
X1803245Y25438D01*
G01X1805328Y26913D02*
X1805578Y27163D01*
X1805703Y27455D01*
X1805745Y27788D01*
X1805662Y28205D01*
X1805453Y28497D01*
X1805203Y28580D01*
X1804953Y28538D01*
X1804745Y28372D01*
X1804328Y27538D01*
X1804037Y27163D01*
X1803620Y26913D01*
X1803245Y26830D01*
Y28580D01*
G01X1805745Y29888D02*
X1803953D01*
X1803578Y30055D01*
X1803328Y30388D01*
X1803245Y30805D01*
X1803328Y31222D01*
X1803578Y31555D01*
X1803953Y31722D01*
X1805745D01*
G01X1803745Y32988D02*
X1803453Y33238D01*
X1803287Y33572D01*
X1803245Y33947D01*
X1803287Y34280D01*
X1803495Y34613D01*
X1803745Y34822D01*
X1803995Y34863D01*
X1804287Y34780D01*
X1804495Y34488D01*
X1804578Y34197D01*
Y33822D01*
G01Y34197D02*
X1804703Y34447D01*
X1804912Y34655D01*
X1805162Y34738D01*
X1805412Y34655D01*
X1805620Y34447D01*
X1805745Y34072D01*
X1805703Y33697D01*
X1805537Y33322D01*
G01X1803245Y36922D02*
X1803787Y37005D01*
X1804245Y37130D01*
X1804662Y37297D01*
X1805120Y37505D01*
X1805745Y37838D01*
Y36172D01*
G01X1799384Y19386D02*
X1801884D01*
Y20427D01*
X1801759Y20761D01*
X1801592Y20969D01*
X1801259Y21052D01*
X1800926Y20969D01*
X1800717Y20719D01*
X1800592Y20427D01*
Y19386D01*
G01Y20427D02*
X1799384Y21052D01*
G01Y23319D02*
X1801884D01*
X1801384Y22819D01*
G01X1799384D02*
Y23819D01*
G01X1801884Y25502D02*
X1800092D01*
X1799717Y25669D01*
X1799467Y26002D01*
X1799384Y26419D01*
X1799467Y26836D01*
X1799717Y27169D01*
X1800092Y27336D01*
X1801884D01*
G01X1799759Y28602D02*
X1799551Y28852D01*
X1799426Y29144D01*
X1799384Y29519D01*
X1799467Y29894D01*
X1799634Y30186D01*
X1799926Y30394D01*
X1800259Y30436D01*
X1800592Y30352D01*
X1800801Y30144D01*
X1800967Y29852D01*
X1801009Y29561D01*
X1800967Y29269D01*
X1800801Y28894D01*
X1801884Y29019D01*
Y30144D01*
G01Y32619D02*
X1801801Y32286D01*
X1801592Y32036D01*
X1801342Y31869D01*
X1801009Y31744D01*
X1800634Y31702D01*
X1800259Y31744D01*
X1799926Y31869D01*
X1799676Y32036D01*
X1799467Y32286D01*
X1799384Y32619D01*
X1799467Y32952D01*
X1799676Y33202D01*
X1799926Y33369D01*
X1800259Y33494D01*
X1800634Y33536D01*
X1801009Y33494D01*
X1801342Y33369D01*
X1801592Y33202D01*
X1801801Y32952D01*
X1801884Y32619D01*
G01X1793127Y19296D02*
X1795627D01*
Y20337D01*
X1795502Y20671D01*
X1795335Y20879D01*
X1795002Y20962D01*
X1794669Y20879D01*
X1794460Y20629D01*
X1794335Y20337D01*
Y19296D01*
G01Y20337D02*
X1793127Y20962D01*
G01Y23229D02*
X1795627D01*
X1795127Y22729D01*
G01X1793127D02*
Y23729D01*
G01X1795627Y25412D02*
X1793835D01*
X1793460Y25579D01*
X1793210Y25912D01*
X1793127Y26329D01*
X1793210Y26746D01*
X1793460Y27079D01*
X1793835Y27246D01*
X1795627D01*
G01X1793127Y29929D02*
X1795627D01*
X1793835Y28387D01*
Y30471D01*
G01X1793419Y31821D02*
X1793210Y32112D01*
X1793127Y32446D01*
X1793210Y32779D01*
X1793460Y33071D01*
X1793835Y33279D01*
X1794210Y33362D01*
X1794669D01*
X1795044Y33279D01*
X1795377Y33071D01*
X1795544Y32821D01*
X1795627Y32529D01*
X1795544Y32196D01*
X1795377Y31946D01*
X1795127Y31779D01*
X1794794Y31696D01*
X1794502Y31779D01*
X1794210Y31987D01*
X1794044Y32237D01*
X1794002Y32529D01*
X1794085Y32862D01*
X1794294Y33112D01*
X1794669Y33362D01*
G01X1821420Y18437D02*
X1821670Y18562D01*
X1821962Y18645D01*
X1822295D01*
X1822670Y18520D01*
X1822962Y18312D01*
X1823170Y18062D01*
X1823337Y17645D01*
X1823379Y17270D01*
X1823295Y16895D01*
X1823170Y16645D01*
X1822920Y16395D01*
X1822629Y16228D01*
X1822337Y16145D01*
X1822045D01*
X1821754Y16228D01*
X1821504Y16353D01*
X1821295Y16520D01*
G01X1820029Y18228D02*
X1819779Y18478D01*
X1819487Y18603D01*
X1819154Y18645D01*
X1818737Y18562D01*
X1818445Y18353D01*
X1818362Y18103D01*
X1818404Y17853D01*
X1818570Y17645D01*
X1819404Y17228D01*
X1819779Y16937D01*
X1820029Y16520D01*
X1820112Y16145D01*
X1818362D01*
G01X1817054Y18645D02*
Y16853D01*
X1816887Y16478D01*
X1816554Y16228D01*
X1816137Y16145D01*
X1815720Y16228D01*
X1815387Y16478D01*
X1815220Y16853D01*
Y18645D01*
G01X1813829Y18228D02*
X1813579Y18478D01*
X1813287Y18603D01*
X1812954Y18645D01*
X1812537Y18562D01*
X1812245Y18353D01*
X1812162Y18103D01*
X1812204Y17853D01*
X1812370Y17645D01*
X1813204Y17228D01*
X1813579Y16937D01*
X1813829Y16520D01*
X1813912Y16145D01*
X1812162D01*
G01X1810854Y16645D02*
X1810604Y16353D01*
X1810270Y16187D01*
X1809895Y16145D01*
X1809562Y16187D01*
X1809229Y16395D01*
X1809020Y16645D01*
X1808979Y16895D01*
X1809062Y17187D01*
X1809354Y17395D01*
X1809645Y17478D01*
X1810020D01*
G01X1809645D02*
X1809395Y17603D01*
X1809187Y17812D01*
X1809104Y18062D01*
X1809187Y18312D01*
X1809395Y18520D01*
X1809770Y18645D01*
X1810145Y18603D01*
X1810520Y18437D01*
G01X1821004Y-22350D02*
X1817904D01*
X1818524Y-21890D01*
G01X1821004D02*
Y-22810D01*
G01Y-25450D02*
X1817904D01*
X1818524Y-24990D01*
G01X1821004D02*
Y-25910D01*
G01X1827504Y-2900D02*
X1824404D01*
X1825024Y-2440D01*
G01X1827504D02*
Y-3360D01*
G01X1824921Y-5272D02*
X1824611Y-5502D01*
X1824456Y-5770D01*
X1824404Y-6077D01*
X1824507Y-6460D01*
X1824766Y-6728D01*
X1825076Y-6805D01*
X1825386Y-6767D01*
X1825644Y-6613D01*
X1826161Y-5847D01*
X1826522Y-5502D01*
X1827039Y-5272D01*
X1827504Y-5195D01*
Y-6805D01*
G01X1811245Y21372D02*
X1813745D01*
Y22413D01*
X1813620Y22747D01*
X1813453Y22955D01*
X1813120Y23038D01*
X1812787Y22955D01*
X1812578Y22705D01*
X1812453Y22413D01*
Y21372D01*
G01Y22413D02*
X1811245Y23038D01*
G01Y25305D02*
X1811287Y25597D01*
X1811412Y25930D01*
X1811620Y26138D01*
X1811912Y26222D01*
X1812203Y26138D01*
X1812453Y25888D01*
X1812578Y25513D01*
Y25097D01*
X1812662Y24847D01*
X1812870Y24638D01*
X1813162Y24555D01*
X1813453Y24680D01*
X1813662Y24972D01*
X1813745Y25305D01*
X1813662Y25638D01*
X1813453Y25930D01*
X1813162Y26055D01*
X1812870Y25972D01*
X1812662Y25763D01*
X1812578Y25513D01*
Y25097D01*
X1812453Y24722D01*
X1812203Y24472D01*
X1811912Y24388D01*
X1811620Y24472D01*
X1811412Y24680D01*
X1811287Y25013D01*
X1811245Y25305D01*
G01Y29238D02*
Y27572D01*
X1813745D01*
Y29238D01*
G01X1812537Y28572D02*
Y27572D01*
G01X1811745Y30588D02*
X1811453Y30838D01*
X1811287Y31172D01*
X1811245Y31547D01*
X1811287Y31880D01*
X1811495Y32213D01*
X1811745Y32422D01*
X1811995Y32463D01*
X1812287Y32380D01*
X1812495Y32088D01*
X1812578Y31797D01*
Y31422D01*
G01Y31797D02*
X1812703Y32047D01*
X1812912Y32255D01*
X1813162Y32338D01*
X1813412Y32255D01*
X1813620Y32047D01*
X1813745Y31672D01*
X1813703Y31297D01*
X1813537Y30922D01*
G01X1812287Y33813D02*
X1812578Y34105D01*
X1812745Y34355D01*
X1812828Y34688D01*
X1812745Y34980D01*
X1812578Y35188D01*
X1812328Y35355D01*
X1812037Y35397D01*
X1811787Y35355D01*
X1811537Y35188D01*
X1811328Y34938D01*
X1811245Y34647D01*
X1811328Y34313D01*
X1811578Y34022D01*
X1811953Y33855D01*
X1812370Y33813D01*
X1812912Y33897D01*
X1813203Y34022D01*
X1813495Y34230D01*
X1813703Y34522D01*
X1813745Y34813D01*
X1813662Y35105D01*
X1813453Y35313D01*
G01X1823700Y31700D02*
X1827700D01*
Y24300D01*
G01X1815606Y66603D02*
X1815731Y66353D01*
X1815814Y66061D01*
Y65728D01*
X1815689Y65353D01*
X1815481Y65061D01*
X1815231Y64853D01*
X1814814Y64686D01*
X1814439Y64644D01*
X1814064Y64728D01*
X1813814Y64853D01*
X1813564Y65103D01*
X1813397Y65394D01*
X1813314Y65686D01*
Y65978D01*
X1813397Y66269D01*
X1813522Y66519D01*
X1813689Y66728D01*
G01X1815397Y67994D02*
X1815647Y68244D01*
X1815772Y68536D01*
X1815814Y68869D01*
X1815731Y69286D01*
X1815522Y69578D01*
X1815272Y69661D01*
X1815022Y69619D01*
X1814814Y69453D01*
X1814397Y68619D01*
X1814106Y68244D01*
X1813689Y67994D01*
X1813314Y67911D01*
Y69661D01*
G01X1815814Y71886D02*
X1813314D01*
G01X1815814Y70928D02*
Y72844D01*
G01X1813606Y74278D02*
X1813397Y74569D01*
X1813314Y74903D01*
X1813397Y75236D01*
X1813647Y75528D01*
X1814022Y75736D01*
X1814397Y75819D01*
X1814856D01*
X1815231Y75736D01*
X1815564Y75528D01*
X1815731Y75278D01*
X1815814Y74986D01*
X1815731Y74653D01*
X1815564Y74403D01*
X1815314Y74236D01*
X1814981Y74153D01*
X1814689Y74236D01*
X1814397Y74444D01*
X1814231Y74694D01*
X1814189Y74986D01*
X1814272Y75319D01*
X1814481Y75569D01*
X1814856Y75819D01*
G01X1838433Y44892D02*
X1838683Y45017D01*
X1838975Y45100D01*
X1839308D01*
X1839683Y44975D01*
X1839975Y44767D01*
X1840183Y44517D01*
X1840350Y44100D01*
X1840392Y43725D01*
X1840308Y43350D01*
X1840183Y43100D01*
X1839933Y42850D01*
X1839642Y42683D01*
X1839350Y42600D01*
X1839058D01*
X1838767Y42683D01*
X1838517Y42808D01*
X1838308Y42975D01*
G01X1837042Y44683D02*
X1836792Y44933D01*
X1836500Y45058D01*
X1836167Y45100D01*
X1835750Y45017D01*
X1835458Y44808D01*
X1835375Y44558D01*
X1835417Y44308D01*
X1835583Y44100D01*
X1836417Y43683D01*
X1836792Y43392D01*
X1837042Y42975D01*
X1837125Y42600D01*
X1835375D01*
G01X1833150Y45100D02*
Y42600D01*
G01X1834108Y45100D02*
X1832192D01*
G01X1830133Y42600D02*
X1830050Y43142D01*
X1829925Y43600D01*
X1829758Y44017D01*
X1829550Y44475D01*
X1829217Y45100D01*
X1830883D01*
G01X1812102Y49346D02*
X1812352Y49471D01*
X1812644Y49554D01*
X1812977D01*
X1813352Y49429D01*
X1813644Y49221D01*
X1813852Y48971D01*
X1814019Y48554D01*
X1814061Y48179D01*
X1813977Y47804D01*
X1813852Y47554D01*
X1813602Y47304D01*
X1813311Y47137D01*
X1813019Y47054D01*
X1812727D01*
X1812436Y47137D01*
X1812186Y47262D01*
X1811977Y47429D01*
G01X1810711Y49137D02*
X1810461Y49387D01*
X1810169Y49512D01*
X1809836Y49554D01*
X1809419Y49471D01*
X1809127Y49262D01*
X1809044Y49012D01*
X1809086Y48762D01*
X1809252Y48554D01*
X1810086Y48137D01*
X1810461Y47846D01*
X1810711Y47429D01*
X1810794Y47054D01*
X1809044D01*
G01X1807736Y49554D02*
Y47762D01*
X1807569Y47387D01*
X1807236Y47137D01*
X1806819Y47054D01*
X1806402Y47137D01*
X1806069Y47387D01*
X1805902Y47762D01*
Y49554D01*
G01X1803719Y47054D02*
Y49554D01*
X1804219Y49054D01*
G01Y47054D02*
X1803219D01*
G01X1819140Y66603D02*
X1819265Y66353D01*
X1819348Y66061D01*
Y65728D01*
X1819223Y65353D01*
X1819015Y65061D01*
X1818765Y64853D01*
X1818348Y64686D01*
X1817973Y64644D01*
X1817598Y64728D01*
X1817348Y64853D01*
X1817098Y65103D01*
X1816931Y65394D01*
X1816848Y65686D01*
Y65978D01*
X1816931Y66269D01*
X1817056Y66519D01*
X1817223Y66728D01*
G01X1818931Y67994D02*
X1819181Y68244D01*
X1819306Y68536D01*
X1819348Y68869D01*
X1819265Y69286D01*
X1819056Y69578D01*
X1818806Y69661D01*
X1818556Y69619D01*
X1818348Y69453D01*
X1817931Y68619D01*
X1817640Y68244D01*
X1817223Y67994D01*
X1816848Y67911D01*
Y69661D01*
G01X1819348Y71886D02*
X1816848D01*
G01X1819348Y70928D02*
Y72844D01*
G01X1817890Y74194D02*
X1818181Y74486D01*
X1818348Y74736D01*
X1818431Y75069D01*
X1818348Y75361D01*
X1818181Y75569D01*
X1817931Y75736D01*
X1817640Y75778D01*
X1817390Y75736D01*
X1817140Y75569D01*
X1816931Y75319D01*
X1816848Y75028D01*
X1816931Y74694D01*
X1817181Y74403D01*
X1817556Y74236D01*
X1817973Y74194D01*
X1818515Y74278D01*
X1818806Y74403D01*
X1819098Y74611D01*
X1819306Y74903D01*
X1819348Y75194D01*
X1819265Y75486D01*
X1819056Y75694D01*
G01X1823000Y86417D02*
X1825500D01*
Y87458D01*
X1825375Y87792D01*
X1825208Y88000D01*
X1824875Y88083D01*
X1824542Y88000D01*
X1824333Y87750D01*
X1824208Y87458D01*
Y86417D01*
G01Y87458D02*
X1823000Y88083D01*
G01X1824042Y89558D02*
X1824333Y89850D01*
X1824500Y90100D01*
X1824583Y90433D01*
X1824500Y90725D01*
X1824333Y90933D01*
X1824083Y91100D01*
X1823792Y91142D01*
X1823542Y91100D01*
X1823292Y90933D01*
X1823083Y90683D01*
X1823000Y90392D01*
X1823083Y90058D01*
X1823333Y89767D01*
X1823708Y89600D01*
X1824125Y89558D01*
X1824667Y89642D01*
X1824958Y89767D01*
X1825250Y89975D01*
X1825458Y90267D01*
X1825500Y90558D01*
X1825417Y90850D01*
X1825208Y91058D01*
G01X1825500Y92200D02*
X1823000Y92783D01*
X1825500Y93450D01*
X1823000Y94117D01*
X1825500Y94700D01*
G01X1825083Y95758D02*
X1825333Y96008D01*
X1825458Y96300D01*
X1825500Y96633D01*
X1825417Y97050D01*
X1825208Y97342D01*
X1824958Y97425D01*
X1824708Y97383D01*
X1824500Y97217D01*
X1824083Y96383D01*
X1823792Y96008D01*
X1823375Y95758D01*
X1823000Y95675D01*
Y97425D01*
G01Y99650D02*
X1825500D01*
X1825000Y99150D01*
G01X1823000D02*
Y100150D01*
G01X1814033Y51550D02*
Y54050D01*
X1812992D01*
X1812658Y53925D01*
X1812450Y53758D01*
X1812367Y53425D01*
X1812450Y53092D01*
X1812700Y52883D01*
X1812992Y52758D01*
X1814033D01*
G01X1812992D02*
X1812367Y51550D01*
G01X1810892Y53633D02*
X1810642Y53883D01*
X1810350Y54008D01*
X1810017Y54050D01*
X1809600Y53967D01*
X1809308Y53758D01*
X1809225Y53508D01*
X1809267Y53258D01*
X1809433Y53050D01*
X1810267Y52633D01*
X1810642Y52342D01*
X1810892Y51925D01*
X1810975Y51550D01*
X1809225D01*
G01X1807000Y54050D02*
Y51550D01*
G01X1807958Y54050D02*
X1806042D01*
G01X1803400Y51550D02*
Y54050D01*
X1804942Y52258D01*
X1802858D01*
G01X1793383Y54395D02*
Y56895D01*
X1792342D01*
X1792008Y56770D01*
X1791800Y56603D01*
X1791717Y56270D01*
X1791800Y55937D01*
X1792050Y55728D01*
X1792342Y55603D01*
X1793383D01*
G01X1792342D02*
X1791717Y54395D01*
G01X1790367Y54895D02*
X1790117Y54603D01*
X1789783Y54437D01*
X1789408Y54395D01*
X1789075Y54437D01*
X1788742Y54645D01*
X1788533Y54895D01*
X1788492Y55145D01*
X1788575Y55437D01*
X1788867Y55645D01*
X1789158Y55728D01*
X1789533D01*
G01X1789158D02*
X1788908Y55853D01*
X1788700Y56062D01*
X1788617Y56312D01*
X1788700Y56562D01*
X1788908Y56770D01*
X1789283Y56895D01*
X1789658Y56853D01*
X1790033Y56687D01*
G01X1787600Y56895D02*
X1787017Y54395D01*
X1786350Y56895D01*
X1785683Y54395D01*
X1785100Y56895D01*
G01X1783250Y54395D02*
Y56895D01*
X1783750Y56395D01*
G01Y54395D02*
X1782750D01*
G01X1793683Y60345D02*
Y62845D01*
X1792642D01*
X1792308Y62720D01*
X1792100Y62553D01*
X1792017Y62220D01*
X1792100Y61887D01*
X1792350Y61678D01*
X1792642Y61553D01*
X1793683D01*
G01X1792642D02*
X1792017Y60345D01*
G01X1790667Y60845D02*
X1790417Y60553D01*
X1790083Y60387D01*
X1789708Y60345D01*
X1789375Y60387D01*
X1789042Y60595D01*
X1788833Y60845D01*
X1788792Y61095D01*
X1788875Y61387D01*
X1789167Y61595D01*
X1789458Y61678D01*
X1789833D01*
G01X1789458D02*
X1789208Y61803D01*
X1789000Y62012D01*
X1788917Y62262D01*
X1789000Y62512D01*
X1789208Y62720D01*
X1789583Y62845D01*
X1789958Y62803D01*
X1790333Y62637D01*
G01X1787900Y62845D02*
X1787317Y60345D01*
X1786650Y62845D01*
X1785983Y60345D01*
X1785400Y62845D01*
G01X1784342Y62428D02*
X1784092Y62678D01*
X1783800Y62803D01*
X1783467Y62845D01*
X1783050Y62762D01*
X1782758Y62553D01*
X1782675Y62303D01*
X1782717Y62053D01*
X1782883Y61845D01*
X1783717Y61428D01*
X1784092Y61137D01*
X1784342Y60720D01*
X1784425Y60345D01*
X1782675D01*
G01X1833483Y37692D02*
X1833733Y37817D01*
X1834025Y37900D01*
X1834358D01*
X1834733Y37775D01*
X1835025Y37567D01*
X1835233Y37317D01*
X1835400Y36900D01*
X1835442Y36525D01*
X1835358Y36150D01*
X1835233Y35900D01*
X1834983Y35650D01*
X1834692Y35483D01*
X1834400Y35400D01*
X1834108D01*
X1833817Y35483D01*
X1833567Y35608D01*
X1833358Y35775D01*
G01X1832092Y37483D02*
X1831842Y37733D01*
X1831550Y37858D01*
X1831217Y37900D01*
X1830800Y37817D01*
X1830508Y37608D01*
X1830425Y37358D01*
X1830467Y37108D01*
X1830633Y36900D01*
X1831467Y36483D01*
X1831842Y36192D01*
X1832092Y35775D01*
X1832175Y35400D01*
X1830425D01*
G01X1829117Y37900D02*
Y36108D01*
X1828950Y35733D01*
X1828617Y35483D01*
X1828200Y35400D01*
X1827783Y35483D01*
X1827450Y35733D01*
X1827283Y36108D01*
Y37900D01*
G01X1825892Y37483D02*
X1825642Y37733D01*
X1825350Y37858D01*
X1825017Y37900D01*
X1824600Y37817D01*
X1824308Y37608D01*
X1824225Y37358D01*
X1824267Y37108D01*
X1824433Y36900D01*
X1825267Y36483D01*
X1825642Y36192D01*
X1825892Y35775D01*
X1825975Y35400D01*
X1824225D01*
G01X1822792Y37483D02*
X1822542Y37733D01*
X1822250Y37858D01*
X1821917Y37900D01*
X1821500Y37817D01*
X1821208Y37608D01*
X1821125Y37358D01*
X1821167Y37108D01*
X1821333Y36900D01*
X1822167Y36483D01*
X1822542Y36192D01*
X1822792Y35775D01*
X1822875Y35400D01*
X1821125D01*
G01X1815933Y84892D02*
X1816183Y85017D01*
X1816475Y85100D01*
X1816808D01*
X1817183Y84975D01*
X1817475Y84767D01*
X1817683Y84517D01*
X1817850Y84100D01*
X1817892Y83725D01*
X1817808Y83350D01*
X1817683Y83100D01*
X1817433Y82850D01*
X1817142Y82683D01*
X1816850Y82600D01*
X1816558D01*
X1816267Y82683D01*
X1816017Y82808D01*
X1815808Y82975D01*
G01X1814458Y82892D02*
X1814167Y82683D01*
X1813833Y82600D01*
X1813500Y82683D01*
X1813208Y82933D01*
X1813000Y83308D01*
X1812917Y83683D01*
Y84142D01*
X1813000Y84517D01*
X1813208Y84850D01*
X1813458Y85017D01*
X1813750Y85100D01*
X1814083Y85017D01*
X1814333Y84850D01*
X1814500Y84600D01*
X1814583Y84267D01*
X1814500Y83975D01*
X1814292Y83683D01*
X1814042Y83517D01*
X1813750Y83475D01*
X1813417Y83558D01*
X1813167Y83767D01*
X1812917Y84142D01*
G01X1811900Y85100D02*
X1811317Y82600D01*
X1810650Y85100D01*
X1809983Y82600D01*
X1809400Y85100D01*
G01X1808342Y83642D02*
X1808050Y83933D01*
X1807800Y84100D01*
X1807467Y84183D01*
X1807175Y84100D01*
X1806967Y83933D01*
X1806800Y83683D01*
X1806758Y83392D01*
X1806800Y83142D01*
X1806967Y82892D01*
X1807217Y82683D01*
X1807508Y82600D01*
X1807842Y82683D01*
X1808133Y82933D01*
X1808300Y83308D01*
X1808342Y83725D01*
X1808258Y84267D01*
X1808133Y84558D01*
X1807925Y84850D01*
X1807633Y85058D01*
X1807342Y85100D01*
X1807050Y85017D01*
X1806842Y84808D01*
G01X1795692Y74767D02*
X1795817Y74517D01*
X1795900Y74225D01*
Y73892D01*
X1795775Y73517D01*
X1795567Y73225D01*
X1795317Y73017D01*
X1794900Y72850D01*
X1794525Y72808D01*
X1794150Y72892D01*
X1793900Y73017D01*
X1793650Y73267D01*
X1793483Y73558D01*
X1793400Y73850D01*
Y74142D01*
X1793483Y74433D01*
X1793608Y74683D01*
X1793775Y74892D01*
G01X1793900Y76033D02*
X1793608Y76283D01*
X1793442Y76617D01*
X1793400Y76992D01*
X1793442Y77325D01*
X1793650Y77658D01*
X1793900Y77867D01*
X1794150Y77908D01*
X1794442Y77825D01*
X1794650Y77533D01*
X1794733Y77242D01*
Y76867D01*
G01Y77242D02*
X1794858Y77492D01*
X1795067Y77700D01*
X1795317Y77783D01*
X1795567Y77700D01*
X1795775Y77492D01*
X1795900Y77117D01*
X1795858Y76742D01*
X1795692Y76367D01*
G01X1795900Y78800D02*
X1793400Y79383D01*
X1795900Y80050D01*
X1793400Y80717D01*
X1795900Y81300D01*
G01X1795483Y82358D02*
X1795733Y82608D01*
X1795858Y82900D01*
X1795900Y83233D01*
X1795817Y83650D01*
X1795608Y83942D01*
X1795358Y84025D01*
X1795108Y83983D01*
X1794900Y83817D01*
X1794483Y82983D01*
X1794192Y82608D01*
X1793775Y82358D01*
X1793400Y82275D01*
Y84025D01*
G01X1813883Y44259D02*
X1814133Y44384D01*
X1814425Y44467D01*
X1814758D01*
X1815133Y44342D01*
X1815425Y44134D01*
X1815633Y43884D01*
X1815800Y43467D01*
X1815842Y43092D01*
X1815758Y42717D01*
X1815633Y42467D01*
X1815383Y42217D01*
X1815092Y42050D01*
X1814800Y41967D01*
X1814508D01*
X1814217Y42050D01*
X1813967Y42175D01*
X1813758Y42342D01*
G01X1812492Y44050D02*
X1812242Y44300D01*
X1811950Y44425D01*
X1811617Y44467D01*
X1811200Y44384D01*
X1810908Y44175D01*
X1810825Y43925D01*
X1810867Y43675D01*
X1811033Y43467D01*
X1811867Y43050D01*
X1812242Y42759D01*
X1812492Y42342D01*
X1812575Y41967D01*
X1810825D01*
G01X1808600Y44467D02*
Y41967D01*
G01X1809558Y44467D02*
X1807642D01*
G01X1806417Y42467D02*
X1806167Y42175D01*
X1805833Y42009D01*
X1805458Y41967D01*
X1805125Y42009D01*
X1804792Y42217D01*
X1804583Y42467D01*
X1804542Y42717D01*
X1804625Y43009D01*
X1804917Y43217D01*
X1805208Y43300D01*
X1805583D01*
G01X1805208D02*
X1804958Y43425D01*
X1804750Y43634D01*
X1804667Y43884D01*
X1804750Y44134D01*
X1804958Y44342D01*
X1805333Y44467D01*
X1805708Y44425D01*
X1806083Y44259D01*
G01X1803192Y43009D02*
X1802900Y43300D01*
X1802650Y43467D01*
X1802317Y43550D01*
X1802025Y43467D01*
X1801817Y43300D01*
X1801650Y43050D01*
X1801608Y42759D01*
X1801650Y42509D01*
X1801817Y42259D01*
X1802067Y42050D01*
X1802358Y41967D01*
X1802692Y42050D01*
X1802983Y42300D01*
X1803150Y42675D01*
X1803192Y43092D01*
X1803108Y43634D01*
X1802983Y43925D01*
X1802775Y44217D01*
X1802483Y44425D01*
X1802192Y44467D01*
X1801900Y44384D01*
X1801692Y44175D01*
G01X1797200Y106850D02*
X1785800D01*
Y87150D01*
X1797200D01*
Y106850D01*
G01X1793733Y52965D02*
X1793983Y53090D01*
X1794275Y53173D01*
X1794608D01*
X1794983Y53048D01*
X1795275Y52840D01*
X1795483Y52590D01*
X1795650Y52173D01*
X1795692Y51798D01*
X1795608Y51423D01*
X1795483Y51173D01*
X1795233Y50923D01*
X1794942Y50756D01*
X1794650Y50673D01*
X1794358D01*
X1794067Y50756D01*
X1793817Y50881D01*
X1793608Y51048D01*
G01X1792383Y50673D02*
Y53173D01*
X1791342D01*
X1791008Y53048D01*
X1790800Y52881D01*
X1790717Y52548D01*
X1790800Y52215D01*
X1791050Y52006D01*
X1791342Y51881D01*
X1792383D01*
G01X1791342D02*
X1790717Y50673D01*
G01X1789367Y51173D02*
X1789117Y50881D01*
X1788783Y50715D01*
X1788408Y50673D01*
X1788075Y50715D01*
X1787742Y50923D01*
X1787533Y51173D01*
X1787492Y51423D01*
X1787575Y51715D01*
X1787867Y51923D01*
X1788158Y52006D01*
X1788533D01*
G01X1788158D02*
X1787908Y52131D01*
X1787700Y52340D01*
X1787617Y52590D01*
X1787700Y52840D01*
X1787908Y53048D01*
X1788283Y53173D01*
X1788658Y53131D01*
X1789033Y52965D01*
G01X1786600Y53173D02*
X1786017Y50673D01*
X1785350Y53173D01*
X1784683Y50673D01*
X1784100Y53173D01*
G01X1782250Y50673D02*
Y53173D01*
X1782750Y52673D01*
G01Y50673D02*
X1781750D01*
G01X1774354Y59031D02*
Y55245D01*
G01X1778777Y57138D02*
X1774354D01*
G01X1838067Y52850D02*
X1838400Y52892D01*
X1838692Y53058D01*
X1838942Y53308D01*
X1839109Y53600D01*
X1839192Y53933D01*
Y54267D01*
X1839109Y54600D01*
X1838942Y54892D01*
X1838692Y55142D01*
X1838400Y55308D01*
X1838067Y55350D01*
X1837734Y55308D01*
X1837442Y55142D01*
X1837192Y54892D01*
X1837025Y54600D01*
X1836942Y54267D01*
Y53933D01*
X1837025Y53600D01*
X1837192Y53308D01*
X1837442Y53058D01*
X1837734Y52892D01*
X1838067Y52850D01*
G01X1837734Y53517D02*
X1837234Y52850D01*
G01X1834967D02*
X1834675Y52892D01*
X1834342Y53017D01*
X1834134Y53225D01*
X1834050Y53517D01*
X1834134Y53808D01*
X1834384Y54058D01*
X1834759Y54183D01*
X1835175D01*
X1835425Y54267D01*
X1835634Y54475D01*
X1835717Y54767D01*
X1835592Y55058D01*
X1835300Y55267D01*
X1834967Y55350D01*
X1834634Y55267D01*
X1834342Y55058D01*
X1834217Y54767D01*
X1834300Y54475D01*
X1834509Y54267D01*
X1834759Y54183D01*
X1835175D01*
X1835550Y54058D01*
X1835800Y53808D01*
X1835884Y53517D01*
X1835800Y53225D01*
X1835592Y53017D01*
X1835259Y52892D01*
X1834967Y52850D01*
G01X1831617Y54100D02*
X1830784D01*
Y53350D01*
X1831034Y53100D01*
X1831325Y52933D01*
X1831742Y52850D01*
X1832159Y52933D01*
X1832450Y53100D01*
X1832700Y53350D01*
X1832867Y53642D01*
X1832950Y53975D01*
Y54267D01*
X1832867Y54517D01*
X1832700Y54808D01*
X1832450Y55058D01*
X1832200Y55225D01*
X1831867Y55350D01*
X1831575D01*
X1831242Y55267D01*
X1830992Y55100D01*
G01X1828767Y52850D02*
Y55350D01*
X1829267Y54850D01*
G01Y52850D02*
X1828267D01*
G01X1840356Y69969D02*
X1826970D01*
G01X1840356Y56583D02*
X1826970D01*
G01X1789513Y43874D02*
X1789763Y43999D01*
X1790055Y44082D01*
X1790388D01*
X1790763Y43957D01*
X1791055Y43749D01*
X1791263Y43499D01*
X1791430Y43082D01*
X1791472Y42707D01*
X1791388Y42332D01*
X1791263Y42082D01*
X1791013Y41832D01*
X1790722Y41665D01*
X1790430Y41582D01*
X1790138D01*
X1789847Y41665D01*
X1789597Y41790D01*
X1789388Y41957D01*
G01X1788163Y41582D02*
Y44082D01*
X1787122D01*
X1786788Y43957D01*
X1786580Y43790D01*
X1786497Y43457D01*
X1786580Y43124D01*
X1786830Y42915D01*
X1787122Y42790D01*
X1788163D01*
G01X1787122D02*
X1786497Y41582D01*
G01X1785022Y43665D02*
X1784772Y43915D01*
X1784480Y44040D01*
X1784147Y44082D01*
X1783730Y43999D01*
X1783438Y43790D01*
X1783355Y43540D01*
X1783397Y43290D01*
X1783563Y43082D01*
X1784397Y42665D01*
X1784772Y42374D01*
X1785022Y41957D01*
X1785105Y41582D01*
X1783355D01*
G01X1782047Y44082D02*
Y42290D01*
X1781880Y41915D01*
X1781547Y41665D01*
X1781130Y41582D01*
X1780713Y41665D01*
X1780380Y41915D01*
X1780213Y42290D01*
Y44082D01*
G01X1778030Y41582D02*
Y44082D01*
X1778530Y43582D01*
G01Y41582D02*
X1777530D01*
G01X1789900Y73850D02*
X1789942Y73517D01*
X1790108Y73225D01*
X1790358Y72975D01*
X1790650Y72808D01*
X1790983Y72725D01*
X1791317D01*
X1791650Y72808D01*
X1791942Y72975D01*
X1792192Y73225D01*
X1792358Y73517D01*
X1792400Y73850D01*
X1792358Y74183D01*
X1792192Y74475D01*
X1791942Y74725D01*
X1791650Y74892D01*
X1791317Y74975D01*
X1790983D01*
X1790650Y74892D01*
X1790358Y74725D01*
X1790108Y74475D01*
X1789942Y74183D01*
X1789900Y73850D01*
G01X1790567Y74183D02*
X1789900Y74683D01*
G01X1790192Y76242D02*
X1789983Y76533D01*
X1789900Y76867D01*
X1789983Y77200D01*
X1790233Y77492D01*
X1790608Y77700D01*
X1790983Y77783D01*
X1791442D01*
X1791817Y77700D01*
X1792150Y77492D01*
X1792317Y77242D01*
X1792400Y76950D01*
X1792317Y76617D01*
X1792150Y76367D01*
X1791900Y76200D01*
X1791567Y76117D01*
X1791275Y76200D01*
X1790983Y76408D01*
X1790817Y76658D01*
X1790775Y76950D01*
X1790858Y77283D01*
X1791067Y77533D01*
X1791442Y77783D01*
G01X1792400Y78800D02*
X1789900Y79383D01*
X1792400Y80050D01*
X1789900Y80717D01*
X1792400Y81300D01*
G01X1789900Y83150D02*
X1792400D01*
X1791900Y82650D01*
G01X1789900D02*
Y83650D01*
G01X1779250Y77000D02*
X1776750D01*
G01X1784000Y79250D02*
Y82500D01*
X1780500D01*
G01X1797133Y67792D02*
X1797383Y67917D01*
X1797675Y68000D01*
X1798008D01*
X1798383Y67875D01*
X1798675Y67667D01*
X1798883Y67417D01*
X1799050Y67000D01*
X1799092Y66625D01*
X1799008Y66250D01*
X1798883Y66000D01*
X1798633Y65750D01*
X1798342Y65583D01*
X1798050Y65500D01*
X1797758D01*
X1797467Y65583D01*
X1797217Y65708D01*
X1797008Y65875D01*
G01X1794950Y65500D02*
X1794658Y65542D01*
X1794325Y65667D01*
X1794117Y65875D01*
X1794033Y66167D01*
X1794117Y66458D01*
X1794367Y66708D01*
X1794742Y66833D01*
X1795158D01*
X1795408Y66917D01*
X1795617Y67125D01*
X1795700Y67417D01*
X1795575Y67708D01*
X1795283Y67917D01*
X1794950Y68000D01*
X1794617Y67917D01*
X1794325Y67708D01*
X1794200Y67417D01*
X1794283Y67125D01*
X1794492Y66917D01*
X1794742Y66833D01*
X1795158D01*
X1795533Y66708D01*
X1795783Y66458D01*
X1795867Y66167D01*
X1795783Y65875D01*
X1795575Y65667D01*
X1795242Y65542D01*
X1794950Y65500D01*
G01X1793100Y68000D02*
X1792517Y65500D01*
X1791850Y68000D01*
X1791183Y65500D01*
X1790600Y68000D01*
G01X1788750Y65500D02*
Y68000D01*
X1789250Y67500D01*
G01Y65500D02*
X1788250D01*
G01X1833372Y82237D02*
X1833497Y81987D01*
X1833580Y81695D01*
Y81362D01*
X1833455Y80987D01*
X1833247Y80695D01*
X1832997Y80487D01*
X1832580Y80320D01*
X1832205Y80278D01*
X1831830Y80362D01*
X1831580Y80487D01*
X1831330Y80737D01*
X1831163Y81028D01*
X1831080Y81320D01*
Y81612D01*
X1831163Y81903D01*
X1831288Y82153D01*
X1831455Y82362D01*
G01X1833163Y83628D02*
X1833413Y83878D01*
X1833538Y84170D01*
X1833580Y84503D01*
X1833497Y84920D01*
X1833288Y85212D01*
X1833038Y85295D01*
X1832788Y85253D01*
X1832580Y85087D01*
X1832163Y84253D01*
X1831872Y83878D01*
X1831455Y83628D01*
X1831080Y83545D01*
Y85295D01*
G01Y86687D02*
X1833580D01*
Y87728D01*
X1833455Y88062D01*
X1833288Y88270D01*
X1832955Y88353D01*
X1832622Y88270D01*
X1832413Y88020D01*
X1832288Y87728D01*
Y86687D01*
G01Y87728D02*
X1831080Y88353D01*
G01Y90620D02*
X1833580D01*
X1833080Y90120D01*
G01X1831080D02*
Y91120D01*
G01Y93720D02*
X1833580D01*
X1833080Y93220D01*
G01X1831080D02*
Y94220D01*
G01X1825959Y128717D02*
X1826084Y128467D01*
X1826167Y128175D01*
Y127842D01*
X1826042Y127467D01*
X1825834Y127175D01*
X1825584Y126967D01*
X1825167Y126800D01*
X1824792Y126758D01*
X1824417Y126842D01*
X1824167Y126967D01*
X1823917Y127217D01*
X1823750Y127508D01*
X1823667Y127800D01*
Y128092D01*
X1823750Y128383D01*
X1823875Y128633D01*
X1824042Y128842D01*
G01X1823667Y130900D02*
X1826167D01*
X1825667Y130400D01*
G01X1823667D02*
Y131400D01*
G01X1826167Y132750D02*
X1823667Y133333D01*
X1826167Y134000D01*
X1823667Y134667D01*
X1826167Y135250D01*
G01X1823667Y137100D02*
X1826167D01*
X1825667Y136600D01*
G01X1823667D02*
Y137600D01*
G01Y140117D02*
X1824209Y140200D01*
X1824667Y140325D01*
X1825084Y140492D01*
X1825542Y140700D01*
X1826167Y141033D01*
Y139367D01*
G01X1801300Y125967D02*
X1803800D01*
Y127008D01*
X1803675Y127342D01*
X1803508Y127550D01*
X1803175Y127633D01*
X1802842Y127550D01*
X1802633Y127300D01*
X1802508Y127008D01*
Y125967D01*
G01Y127008D02*
X1801300Y127633D01*
G01Y129900D02*
X1801342Y130192D01*
X1801467Y130525D01*
X1801675Y130733D01*
X1801967Y130817D01*
X1802258Y130733D01*
X1802508Y130483D01*
X1802633Y130108D01*
Y129692D01*
X1802717Y129442D01*
X1802925Y129233D01*
X1803217Y129150D01*
X1803508Y129275D01*
X1803717Y129567D01*
X1803800Y129900D01*
X1803717Y130233D01*
X1803508Y130525D01*
X1803217Y130650D01*
X1802925Y130567D01*
X1802717Y130358D01*
X1802633Y130108D01*
Y129692D01*
X1802508Y129317D01*
X1802258Y129067D01*
X1801967Y128983D01*
X1801675Y129067D01*
X1801467Y129275D01*
X1801342Y129608D01*
X1801300Y129900D01*
G01Y132083D02*
X1803800D01*
Y132917D01*
X1803675Y133250D01*
X1803508Y133500D01*
X1803258Y133708D01*
X1802967Y133875D01*
X1802550Y133917D01*
X1802133Y133875D01*
X1801842Y133708D01*
X1801592Y133500D01*
X1801425Y133250D01*
X1801300Y132917D01*
Y132083D01*
G01X1803383Y135308D02*
X1803633Y135558D01*
X1803758Y135850D01*
X1803800Y136183D01*
X1803717Y136600D01*
X1803508Y136892D01*
X1803258Y136975D01*
X1803008Y136933D01*
X1802800Y136767D01*
X1802383Y135933D01*
X1802092Y135558D01*
X1801675Y135308D01*
X1801300Y135225D01*
Y136975D01*
G01X1803383Y138408D02*
X1803633Y138658D01*
X1803758Y138950D01*
X1803800Y139283D01*
X1803717Y139700D01*
X1803508Y139992D01*
X1803258Y140075D01*
X1803008Y140033D01*
X1802800Y139867D01*
X1802383Y139033D01*
X1802092Y138658D01*
X1801675Y138408D01*
X1801300Y138325D01*
Y140075D01*
G01X1804800Y125967D02*
X1807300D01*
Y127008D01*
X1807175Y127342D01*
X1807008Y127550D01*
X1806675Y127633D01*
X1806342Y127550D01*
X1806133Y127300D01*
X1806008Y127008D01*
Y125967D01*
G01Y127008D02*
X1804800Y127633D01*
G01X1805092Y129192D02*
X1804883Y129483D01*
X1804800Y129817D01*
X1804883Y130150D01*
X1805133Y130442D01*
X1805508Y130650D01*
X1805883Y130733D01*
X1806342D01*
X1806717Y130650D01*
X1807050Y130442D01*
X1807217Y130192D01*
X1807300Y129900D01*
X1807217Y129567D01*
X1807050Y129317D01*
X1806800Y129150D01*
X1806467Y129067D01*
X1806175Y129150D01*
X1805883Y129358D01*
X1805717Y129608D01*
X1805675Y129900D01*
X1805758Y130233D01*
X1805967Y130483D01*
X1806342Y130733D01*
G01X1804800Y133833D02*
Y132167D01*
X1807300D01*
Y133833D01*
G01X1806092Y133167D02*
Y132167D01*
G01X1804800Y136100D02*
X1807300D01*
X1806800Y135600D01*
G01X1804800D02*
Y136600D01*
G01Y139700D02*
X1807300D01*
X1805508Y138158D01*
Y140242D01*
G01X1812549Y118444D02*
Y120944D01*
X1811508D01*
X1811174Y120819D01*
X1810966Y120652D01*
X1810883Y120319D01*
X1810966Y119986D01*
X1811216Y119777D01*
X1811508Y119652D01*
X1812549D01*
G01X1811508D02*
X1810883Y118444D01*
G01X1808616D02*
X1808324Y118486D01*
X1807991Y118611D01*
X1807783Y118819D01*
X1807699Y119111D01*
X1807783Y119402D01*
X1808033Y119652D01*
X1808408Y119777D01*
X1808824D01*
X1809074Y119861D01*
X1809283Y120069D01*
X1809366Y120361D01*
X1809241Y120652D01*
X1808949Y120861D01*
X1808616Y120944D01*
X1808283Y120861D01*
X1807991Y120652D01*
X1807866Y120361D01*
X1807949Y120069D01*
X1808158Y119861D01*
X1808408Y119777D01*
X1808824D01*
X1809199Y119652D01*
X1809449Y119402D01*
X1809533Y119111D01*
X1809449Y118819D01*
X1809241Y118611D01*
X1808908Y118486D01*
X1808616Y118444D01*
G01X1806433D02*
Y120944D01*
X1805599D01*
X1805266Y120819D01*
X1805016Y120652D01*
X1804808Y120402D01*
X1804641Y120111D01*
X1804599Y119694D01*
X1804641Y119277D01*
X1804808Y118986D01*
X1805016Y118736D01*
X1805266Y118569D01*
X1805599Y118444D01*
X1806433D01*
G01X1803208Y120527D02*
X1802958Y120777D01*
X1802666Y120902D01*
X1802333Y120944D01*
X1801916Y120861D01*
X1801624Y120652D01*
X1801541Y120402D01*
X1801583Y120152D01*
X1801749Y119944D01*
X1802583Y119527D01*
X1802958Y119236D01*
X1803208Y118819D01*
X1803291Y118444D01*
X1801541D01*
G01X1800233Y118819D02*
X1799983Y118611D01*
X1799691Y118486D01*
X1799316Y118444D01*
X1798941Y118527D01*
X1798649Y118694D01*
X1798441Y118986D01*
X1798399Y119319D01*
X1798483Y119652D01*
X1798691Y119861D01*
X1798983Y120027D01*
X1799274Y120069D01*
X1799566Y120027D01*
X1799941Y119861D01*
X1799816Y120944D01*
X1798691D01*
G01X1812449Y114844D02*
Y117344D01*
X1811408D01*
X1811074Y117219D01*
X1810866Y117052D01*
X1810783Y116719D01*
X1810866Y116386D01*
X1811116Y116177D01*
X1811408Y116052D01*
X1812449D01*
G01X1811408D02*
X1810783Y114844D01*
G01X1808516D02*
X1808224Y114886D01*
X1807891Y115011D01*
X1807683Y115219D01*
X1807599Y115511D01*
X1807683Y115802D01*
X1807933Y116052D01*
X1808308Y116177D01*
X1808724D01*
X1808974Y116261D01*
X1809183Y116469D01*
X1809266Y116761D01*
X1809141Y117052D01*
X1808849Y117261D01*
X1808516Y117344D01*
X1808183Y117261D01*
X1807891Y117052D01*
X1807766Y116761D01*
X1807849Y116469D01*
X1808058Y116261D01*
X1808308Y116177D01*
X1808724D01*
X1809099Y116052D01*
X1809349Y115802D01*
X1809433Y115511D01*
X1809349Y115219D01*
X1809141Y115011D01*
X1808808Y114886D01*
X1808516Y114844D01*
G01X1806333D02*
Y117344D01*
X1805499D01*
X1805166Y117219D01*
X1804916Y117052D01*
X1804708Y116802D01*
X1804541Y116511D01*
X1804499Y116094D01*
X1804541Y115677D01*
X1804708Y115386D01*
X1804916Y115136D01*
X1805166Y114969D01*
X1805499Y114844D01*
X1806333D01*
G01X1803233Y115344D02*
X1802983Y115052D01*
X1802649Y114886D01*
X1802274Y114844D01*
X1801941Y114886D01*
X1801608Y115094D01*
X1801399Y115344D01*
X1801358Y115594D01*
X1801441Y115886D01*
X1801733Y116094D01*
X1802024Y116177D01*
X1802399D01*
G01X1802024D02*
X1801774Y116302D01*
X1801566Y116511D01*
X1801483Y116761D01*
X1801566Y117011D01*
X1801774Y117219D01*
X1802149Y117344D01*
X1802524Y117302D01*
X1802899Y117136D01*
G01X1800008Y115886D02*
X1799716Y116177D01*
X1799466Y116344D01*
X1799133Y116427D01*
X1798841Y116344D01*
X1798633Y116177D01*
X1798466Y115927D01*
X1798424Y115636D01*
X1798466Y115386D01*
X1798633Y115136D01*
X1798883Y114927D01*
X1799174Y114844D01*
X1799508Y114927D01*
X1799799Y115177D01*
X1799966Y115552D01*
X1800008Y115969D01*
X1799924Y116511D01*
X1799799Y116802D01*
X1799591Y117094D01*
X1799299Y117302D01*
X1799008Y117344D01*
X1798716Y117261D01*
X1798508Y117052D01*
G01X1823033Y145100D02*
Y147600D01*
X1821992D01*
X1821658Y147475D01*
X1821450Y147308D01*
X1821367Y146975D01*
X1821450Y146642D01*
X1821700Y146433D01*
X1821992Y146308D01*
X1823033D01*
G01X1821992D02*
X1821367Y145100D01*
G01X1819100D02*
Y147600D01*
X1819600Y147100D01*
G01Y145100D02*
X1818600D01*
G01X1816917Y147600D02*
Y145808D01*
X1816750Y145433D01*
X1816417Y145183D01*
X1816000Y145100D01*
X1815583Y145183D01*
X1815250Y145433D01*
X1815083Y145808D01*
Y147600D01*
G01X1812900Y145100D02*
Y147600D01*
X1813400Y147100D01*
G01Y145100D02*
X1812400D01*
G01X1810717Y145475D02*
X1810467Y145267D01*
X1810175Y145142D01*
X1809800Y145100D01*
X1809425Y145183D01*
X1809133Y145350D01*
X1808925Y145642D01*
X1808883Y145975D01*
X1808967Y146308D01*
X1809175Y146517D01*
X1809467Y146683D01*
X1809758Y146725D01*
X1810050Y146683D01*
X1810425Y146517D01*
X1810300Y147600D01*
X1809175D01*
G01X1823033Y148600D02*
Y151100D01*
X1821992D01*
X1821658Y150975D01*
X1821450Y150808D01*
X1821367Y150475D01*
X1821450Y150142D01*
X1821700Y149933D01*
X1821992Y149808D01*
X1823033D01*
G01X1821992D02*
X1821367Y148600D01*
G01X1819100D02*
Y151100D01*
X1819600Y150600D01*
G01Y148600D02*
X1818600D01*
G01X1816917Y151100D02*
Y149308D01*
X1816750Y148933D01*
X1816417Y148683D01*
X1816000Y148600D01*
X1815583Y148683D01*
X1815250Y148933D01*
X1815083Y149308D01*
Y151100D01*
G01X1813692Y150683D02*
X1813442Y150933D01*
X1813150Y151058D01*
X1812817Y151100D01*
X1812400Y151017D01*
X1812108Y150808D01*
X1812025Y150558D01*
X1812067Y150308D01*
X1812233Y150100D01*
X1813067Y149683D01*
X1813442Y149392D01*
X1813692Y148975D01*
X1813775Y148600D01*
X1812025D01*
G01X1809800D02*
Y151100D01*
X1810300Y150600D01*
G01Y148600D02*
X1809300D01*
G01X1844307Y140072D02*
X1844557Y140197D01*
X1844849Y140280D01*
X1845182D01*
X1845557Y140155D01*
X1845849Y139947D01*
X1846057Y139697D01*
X1846224Y139280D01*
X1846266Y138905D01*
X1846182Y138530D01*
X1846057Y138280D01*
X1845807Y138030D01*
X1845516Y137863D01*
X1845224Y137780D01*
X1844932D01*
X1844641Y137863D01*
X1844391Y137988D01*
X1844182Y138155D01*
G01X1842124Y137780D02*
Y140280D01*
X1842624Y139780D01*
G01Y137780D02*
X1841624D01*
G01X1839024Y140280D02*
Y137780D01*
G01X1839982Y140280D02*
X1838066D01*
G01X1835924Y137780D02*
Y140280D01*
X1836424Y139780D01*
G01Y137780D02*
X1835424D01*
G01X1833741Y138155D02*
X1833491Y137947D01*
X1833199Y137822D01*
X1832824Y137780D01*
X1832449Y137863D01*
X1832157Y138030D01*
X1831949Y138322D01*
X1831907Y138655D01*
X1831991Y138988D01*
X1832199Y139197D01*
X1832491Y139363D01*
X1832782Y139405D01*
X1833074Y139363D01*
X1833449Y139197D01*
X1833324Y140280D01*
X1832199D01*
G01X1824972Y154637D02*
X1825097Y154387D01*
X1825180Y154095D01*
Y153762D01*
X1825055Y153387D01*
X1824847Y153095D01*
X1824597Y152887D01*
X1824180Y152720D01*
X1823805Y152678D01*
X1823430Y152762D01*
X1823180Y152887D01*
X1822930Y153137D01*
X1822763Y153428D01*
X1822680Y153720D01*
Y154012D01*
X1822763Y154303D01*
X1822888Y154553D01*
X1823055Y154762D01*
G01X1822972Y156112D02*
X1822763Y156403D01*
X1822680Y156737D01*
X1822763Y157070D01*
X1823013Y157362D01*
X1823388Y157570D01*
X1823763Y157653D01*
X1824222D01*
X1824597Y157570D01*
X1824930Y157362D01*
X1825097Y157112D01*
X1825180Y156820D01*
X1825097Y156487D01*
X1824930Y156237D01*
X1824680Y156070D01*
X1824347Y155987D01*
X1824055Y156070D01*
X1823763Y156278D01*
X1823597Y156528D01*
X1823555Y156820D01*
X1823638Y157153D01*
X1823847Y157403D01*
X1824222Y157653D01*
G01X1825180Y158670D02*
X1822680Y159253D01*
X1825180Y159920D01*
X1822680Y160587D01*
X1825180Y161170D01*
G01X1822680Y163020D02*
X1825180D01*
X1824680Y162520D01*
G01X1822680D02*
Y163520D01*
G01Y166620D02*
X1825180D01*
X1823388Y165078D01*
Y167162D01*
G01X1801167Y144400D02*
Y142608D01*
X1801000Y142233D01*
X1800667Y141983D01*
X1800250Y141900D01*
X1799833Y141983D01*
X1799500Y142233D01*
X1799333Y142608D01*
Y144400D01*
G01X1797150Y141900D02*
X1796858Y141942D01*
X1796525Y142067D01*
X1796317Y142275D01*
X1796233Y142567D01*
X1796317Y142858D01*
X1796567Y143108D01*
X1796942Y143233D01*
X1797358D01*
X1797608Y143317D01*
X1797817Y143525D01*
X1797900Y143817D01*
X1797775Y144108D01*
X1797483Y144317D01*
X1797150Y144400D01*
X1796817Y144317D01*
X1796525Y144108D01*
X1796400Y143817D01*
X1796483Y143525D01*
X1796692Y143317D01*
X1796942Y143233D01*
X1797358D01*
X1797733Y143108D01*
X1797983Y142858D01*
X1798067Y142567D01*
X1797983Y142275D01*
X1797775Y142067D01*
X1797442Y141942D01*
X1797150Y141900D01*
G01X1794967D02*
Y144400D01*
X1794133D01*
X1793800Y144275D01*
X1793550Y144108D01*
X1793342Y143858D01*
X1793175Y143567D01*
X1793133Y143150D01*
X1793175Y142733D01*
X1793342Y142442D01*
X1793550Y142192D01*
X1793800Y142025D01*
X1794133Y141900D01*
X1794967D01*
G01X1791742Y143983D02*
X1791492Y144233D01*
X1791200Y144358D01*
X1790867Y144400D01*
X1790450Y144317D01*
X1790158Y144108D01*
X1790075Y143858D01*
X1790117Y143608D01*
X1790283Y143400D01*
X1791117Y142983D01*
X1791492Y142692D01*
X1791742Y142275D01*
X1791825Y141900D01*
X1790075D01*
G01X1840983Y134859D02*
X1841233Y134984D01*
X1841525Y135067D01*
X1841858D01*
X1842233Y134942D01*
X1842525Y134734D01*
X1842733Y134484D01*
X1842900Y134067D01*
X1842942Y133692D01*
X1842858Y133317D01*
X1842733Y133067D01*
X1842483Y132817D01*
X1842192Y132650D01*
X1841900Y132567D01*
X1841608D01*
X1841317Y132650D01*
X1841067Y132775D01*
X1840858Y132942D01*
G01X1839592Y134650D02*
X1839342Y134900D01*
X1839050Y135025D01*
X1838717Y135067D01*
X1838300Y134984D01*
X1838008Y134775D01*
X1837925Y134525D01*
X1837967Y134275D01*
X1838133Y134067D01*
X1838967Y133650D01*
X1839342Y133359D01*
X1839592Y132942D01*
X1839675Y132567D01*
X1837925D01*
G01X1835700Y135067D02*
Y132567D01*
G01X1836658Y135067D02*
X1834742D01*
G01X1833517Y133067D02*
X1833267Y132775D01*
X1832933Y132609D01*
X1832558Y132567D01*
X1832225Y132609D01*
X1831892Y132817D01*
X1831683Y133067D01*
X1831642Y133317D01*
X1831725Y133609D01*
X1832017Y133817D01*
X1832308Y133900D01*
X1832683D01*
G01X1832308D02*
X1832058Y134025D01*
X1831850Y134234D01*
X1831767Y134484D01*
X1831850Y134734D01*
X1832058Y134942D01*
X1832433Y135067D01*
X1832808Y135025D01*
X1833183Y134859D01*
G01X1829500Y132567D02*
X1829208Y132609D01*
X1828875Y132734D01*
X1828667Y132942D01*
X1828583Y133234D01*
X1828667Y133525D01*
X1828917Y133775D01*
X1829292Y133900D01*
X1829708D01*
X1829958Y133984D01*
X1830167Y134192D01*
X1830250Y134484D01*
X1830125Y134775D01*
X1829833Y134984D01*
X1829500Y135067D01*
X1829167Y134984D01*
X1828875Y134775D01*
X1828750Y134484D01*
X1828833Y134192D01*
X1829042Y133984D01*
X1829292Y133900D01*
X1829708D01*
X1830083Y133775D01*
X1830333Y133525D01*
X1830417Y133234D01*
X1830333Y132942D01*
X1830125Y132734D01*
X1829792Y132609D01*
X1829500Y132567D01*
G01X1784792Y112167D02*
X1784917Y111917D01*
X1785000Y111625D01*
Y111292D01*
X1784875Y110917D01*
X1784667Y110625D01*
X1784417Y110417D01*
X1784000Y110250D01*
X1783625Y110208D01*
X1783250Y110292D01*
X1783000Y110417D01*
X1782750Y110667D01*
X1782583Y110958D01*
X1782500Y111250D01*
Y111542D01*
X1782583Y111833D01*
X1782708Y112083D01*
X1782875Y112292D01*
G01X1782500Y114350D02*
X1782542Y114642D01*
X1782667Y114975D01*
X1782875Y115183D01*
X1783167Y115267D01*
X1783458Y115183D01*
X1783708Y114933D01*
X1783833Y114558D01*
Y114142D01*
X1783917Y113892D01*
X1784125Y113683D01*
X1784417Y113600D01*
X1784708Y113725D01*
X1784917Y114017D01*
X1785000Y114350D01*
X1784917Y114683D01*
X1784708Y114975D01*
X1784417Y115100D01*
X1784125Y115017D01*
X1783917Y114808D01*
X1783833Y114558D01*
Y114142D01*
X1783708Y113767D01*
X1783458Y113517D01*
X1783167Y113433D01*
X1782875Y113517D01*
X1782667Y113725D01*
X1782542Y114058D01*
X1782500Y114350D01*
G01Y116533D02*
X1785000D01*
Y117367D01*
X1784875Y117700D01*
X1784708Y117950D01*
X1784458Y118158D01*
X1784167Y118325D01*
X1783750Y118367D01*
X1783333Y118325D01*
X1783042Y118158D01*
X1782792Y117950D01*
X1782625Y117700D01*
X1782500Y117367D01*
Y116533D01*
G01Y120550D02*
X1785000D01*
X1784500Y120050D01*
G01X1782500D02*
Y121050D01*
G01X1797567Y110667D02*
Y108875D01*
X1797400Y108500D01*
X1797067Y108250D01*
X1796650Y108167D01*
X1796233Y108250D01*
X1795900Y108500D01*
X1795733Y108875D01*
Y110667D01*
G01X1794342Y109209D02*
X1794050Y109500D01*
X1793800Y109667D01*
X1793467Y109750D01*
X1793175Y109667D01*
X1792967Y109500D01*
X1792800Y109250D01*
X1792758Y108959D01*
X1792800Y108709D01*
X1792967Y108459D01*
X1793217Y108250D01*
X1793508Y108167D01*
X1793842Y108250D01*
X1794133Y108500D01*
X1794300Y108875D01*
X1794342Y109292D01*
X1794258Y109834D01*
X1794133Y110125D01*
X1793925Y110417D01*
X1793633Y110625D01*
X1793342Y110667D01*
X1793050Y110584D01*
X1792842Y110375D01*
G01X1791700Y110667D02*
X1791117Y108167D01*
X1790450Y110667D01*
X1789783Y108167D01*
X1789200Y110667D01*
G01X1788267Y108667D02*
X1788017Y108375D01*
X1787683Y108209D01*
X1787308Y108167D01*
X1786975Y108209D01*
X1786642Y108417D01*
X1786433Y108667D01*
X1786392Y108917D01*
X1786475Y109209D01*
X1786767Y109417D01*
X1787058Y109500D01*
X1787433D01*
G01X1787058D02*
X1786808Y109625D01*
X1786600Y109834D01*
X1786517Y110084D01*
X1786600Y110334D01*
X1786808Y110542D01*
X1787183Y110667D01*
X1787558Y110625D01*
X1787933Y110459D01*
G01X1794000Y106800D02*
Y101850D01*
X1789000D01*
Y106800D01*
G01X1778392Y112967D02*
X1778517Y112717D01*
X1778600Y112425D01*
Y112092D01*
X1778475Y111717D01*
X1778267Y111425D01*
X1778017Y111217D01*
X1777600Y111050D01*
X1777225Y111008D01*
X1776850Y111092D01*
X1776600Y111217D01*
X1776350Y111467D01*
X1776183Y111758D01*
X1776100Y112050D01*
Y112342D01*
X1776183Y112633D01*
X1776308Y112883D01*
X1776475Y113092D01*
G01X1778183Y114358D02*
X1778433Y114608D01*
X1778558Y114900D01*
X1778600Y115233D01*
X1778517Y115650D01*
X1778308Y115942D01*
X1778058Y116025D01*
X1777808Y115983D01*
X1777600Y115817D01*
X1777183Y114983D01*
X1776892Y114608D01*
X1776475Y114358D01*
X1776100Y114275D01*
Y116025D01*
G01X1776475Y117333D02*
X1776267Y117583D01*
X1776142Y117875D01*
X1776100Y118250D01*
X1776183Y118625D01*
X1776350Y118917D01*
X1776642Y119125D01*
X1776975Y119167D01*
X1777308Y119083D01*
X1777517Y118875D01*
X1777683Y118583D01*
X1777725Y118292D01*
X1777683Y118000D01*
X1777517Y117625D01*
X1778600Y117750D01*
Y118875D01*
G01Y120100D02*
X1776100Y120683D01*
X1778600Y121350D01*
X1776100Y122017D01*
X1778600Y122600D01*
G01X1776100Y124450D02*
X1778600D01*
X1778100Y123950D01*
G01X1776100D02*
Y124950D01*
G01Y127467D02*
X1776642Y127550D01*
X1777100Y127675D01*
X1777517Y127842D01*
X1777975Y128050D01*
X1778600Y128383D01*
Y126717D01*
G01X1793160Y174250D02*
Y178200D01*
X1790150D01*
Y195900D01*
X1794900D01*
G01X1797500D02*
X1799600D01*
G01X1803100D02*
X1808000D01*
G01X1835220Y189585D02*
X1837720D01*
Y190626D01*
X1837595Y190960D01*
X1837428Y191168D01*
X1837095Y191251D01*
X1836762Y191168D01*
X1836553Y190918D01*
X1836428Y190626D01*
Y189585D01*
G01Y190626D02*
X1835220Y191251D01*
G01X1835512Y192810D02*
X1835303Y193101D01*
X1835220Y193435D01*
X1835303Y193768D01*
X1835553Y194060D01*
X1835928Y194268D01*
X1836303Y194351D01*
X1836762D01*
X1837137Y194268D01*
X1837470Y194060D01*
X1837637Y193810D01*
X1837720Y193518D01*
X1837637Y193185D01*
X1837470Y192935D01*
X1837220Y192768D01*
X1836887Y192685D01*
X1836595Y192768D01*
X1836303Y192976D01*
X1836137Y193226D01*
X1836095Y193518D01*
X1836178Y193851D01*
X1836387Y194101D01*
X1836762Y194351D01*
G01X1835220Y197451D02*
Y195785D01*
X1837720D01*
Y197451D01*
G01X1836512Y196785D02*
Y195785D01*
G01X1835220Y199718D02*
X1837720D01*
X1837220Y199218D01*
G01X1835220D02*
Y200218D01*
G01X1837720Y202818D02*
X1837637Y202485D01*
X1837428Y202235D01*
X1837178Y202068D01*
X1836845Y201943D01*
X1836470Y201901D01*
X1836095Y201943D01*
X1835762Y202068D01*
X1835512Y202235D01*
X1835303Y202485D01*
X1835220Y202818D01*
X1835303Y203151D01*
X1835512Y203401D01*
X1835762Y203568D01*
X1836095Y203693D01*
X1836470Y203735D01*
X1836845Y203693D01*
X1837178Y203568D01*
X1837428Y203401D01*
X1837637Y203151D01*
X1837720Y202818D01*
G01X1843833Y208700D02*
Y211200D01*
X1842792D01*
X1842458Y211075D01*
X1842250Y210908D01*
X1842167Y210575D01*
X1842250Y210242D01*
X1842500Y210033D01*
X1842792Y209908D01*
X1843833D01*
G01X1842792D02*
X1842167Y208700D01*
G01X1839900D02*
Y211200D01*
X1840400Y210700D01*
G01Y208700D02*
X1839400D01*
G01X1837633D02*
Y211200D01*
X1836592D01*
X1836258Y211075D01*
X1836050Y210908D01*
X1835967Y210575D01*
X1836050Y210242D01*
X1836300Y210033D01*
X1836592Y209908D01*
X1837633D01*
G01X1836592D02*
X1835967Y208700D01*
G01X1834492Y210783D02*
X1834242Y211033D01*
X1833950Y211158D01*
X1833617Y211200D01*
X1833200Y211117D01*
X1832908Y210908D01*
X1832825Y210658D01*
X1832867Y210408D01*
X1833033Y210200D01*
X1833867Y209783D01*
X1834242Y209492D01*
X1834492Y209075D01*
X1834575Y208700D01*
X1832825D01*
G01X1831517Y209200D02*
X1831267Y208908D01*
X1830933Y208742D01*
X1830558Y208700D01*
X1830225Y208742D01*
X1829892Y208950D01*
X1829683Y209200D01*
X1829642Y209450D01*
X1829725Y209742D01*
X1830017Y209950D01*
X1830308Y210033D01*
X1830683D01*
G01X1830308D02*
X1830058Y210158D01*
X1829850Y210367D01*
X1829767Y210617D01*
X1829850Y210867D01*
X1830058Y211075D01*
X1830433Y211200D01*
X1830808Y211158D01*
X1831183Y210992D01*
G01X1843833Y212200D02*
Y214700D01*
X1842792D01*
X1842458Y214575D01*
X1842250Y214408D01*
X1842167Y214075D01*
X1842250Y213742D01*
X1842500Y213533D01*
X1842792Y213408D01*
X1843833D01*
G01X1842792D02*
X1842167Y212200D01*
G01X1839900D02*
Y214700D01*
X1840400Y214200D01*
G01Y212200D02*
X1839400D01*
G01X1837633D02*
Y214700D01*
X1836592D01*
X1836258Y214575D01*
X1836050Y214408D01*
X1835967Y214075D01*
X1836050Y213742D01*
X1836300Y213533D01*
X1836592Y213408D01*
X1837633D01*
G01X1836592D02*
X1835967Y212200D01*
G01X1834492Y214283D02*
X1834242Y214533D01*
X1833950Y214658D01*
X1833617Y214700D01*
X1833200Y214617D01*
X1832908Y214408D01*
X1832825Y214158D01*
X1832867Y213908D01*
X1833033Y213700D01*
X1833867Y213283D01*
X1834242Y212992D01*
X1834492Y212575D01*
X1834575Y212200D01*
X1832825D01*
G01X1831392Y214283D02*
X1831142Y214533D01*
X1830850Y214658D01*
X1830517Y214700D01*
X1830100Y214617D01*
X1829808Y214408D01*
X1829725Y214158D01*
X1829767Y213908D01*
X1829933Y213700D01*
X1830767Y213283D01*
X1831142Y212992D01*
X1831392Y212575D01*
X1831475Y212200D01*
X1829725D01*
G01X1843833Y215700D02*
Y218200D01*
X1842792D01*
X1842458Y218075D01*
X1842250Y217908D01*
X1842167Y217575D01*
X1842250Y217242D01*
X1842500Y217033D01*
X1842792Y216908D01*
X1843833D01*
G01X1842792D02*
X1842167Y215700D01*
G01X1839900D02*
Y218200D01*
X1840400Y217700D01*
G01Y215700D02*
X1839400D01*
G01X1837633D02*
Y218200D01*
X1836592D01*
X1836258Y218075D01*
X1836050Y217908D01*
X1835967Y217575D01*
X1836050Y217242D01*
X1836300Y217033D01*
X1836592Y216908D01*
X1837633D01*
G01X1836592D02*
X1835967Y215700D01*
G01X1834492Y217783D02*
X1834242Y218033D01*
X1833950Y218158D01*
X1833617Y218200D01*
X1833200Y218117D01*
X1832908Y217908D01*
X1832825Y217658D01*
X1832867Y217408D01*
X1833033Y217200D01*
X1833867Y216783D01*
X1834242Y216492D01*
X1834492Y216075D01*
X1834575Y215700D01*
X1832825D01*
G01X1830600D02*
Y218200D01*
X1831100Y217700D01*
G01Y215700D02*
X1830100D01*
G01X1785900Y173117D02*
X1788400D01*
Y174158D01*
X1788275Y174492D01*
X1788108Y174700D01*
X1787775Y174783D01*
X1787442Y174700D01*
X1787233Y174450D01*
X1787108Y174158D01*
Y173117D01*
G01Y174158D02*
X1785900Y174783D01*
G01X1787983Y176258D02*
X1788233Y176508D01*
X1788358Y176800D01*
X1788400Y177133D01*
X1788317Y177550D01*
X1788108Y177842D01*
X1787858Y177925D01*
X1787608Y177883D01*
X1787400Y177717D01*
X1786983Y176883D01*
X1786692Y176508D01*
X1786275Y176258D01*
X1785900Y176175D01*
Y177925D01*
G01X1786275Y179233D02*
X1786067Y179483D01*
X1785942Y179775D01*
X1785900Y180150D01*
X1785983Y180525D01*
X1786150Y180817D01*
X1786442Y181025D01*
X1786775Y181067D01*
X1787108Y180983D01*
X1787317Y180775D01*
X1787483Y180483D01*
X1787525Y180192D01*
X1787483Y179900D01*
X1787317Y179525D01*
X1788400Y179650D01*
Y180775D01*
G01Y182000D02*
X1785900Y182583D01*
X1788400Y183250D01*
X1785900Y183917D01*
X1788400Y184500D01*
G01X1785900Y186350D02*
X1788400D01*
X1787900Y185850D01*
G01X1785900D02*
Y186850D01*
G01Y189950D02*
X1788400D01*
X1786608Y188408D01*
Y190492D01*
G01X1786275Y191633D02*
X1786067Y191883D01*
X1785942Y192175D01*
X1785900Y192550D01*
X1785983Y192925D01*
X1786150Y193217D01*
X1786442Y193425D01*
X1786775Y193467D01*
X1787108Y193383D01*
X1787317Y193175D01*
X1787483Y192883D01*
X1787525Y192592D01*
X1787483Y192300D01*
X1787317Y191925D01*
X1788400Y192050D01*
Y193175D01*
G01X1806473Y159662D02*
X1806723Y159787D01*
X1807015Y159870D01*
X1807348D01*
X1807723Y159745D01*
X1808015Y159537D01*
X1808223Y159287D01*
X1808390Y158870D01*
X1808432Y158495D01*
X1808348Y158120D01*
X1808223Y157870D01*
X1807973Y157620D01*
X1807682Y157453D01*
X1807390Y157370D01*
X1807098D01*
X1806807Y157453D01*
X1806557Y157578D01*
X1806348Y157745D01*
G01X1804998Y157662D02*
X1804707Y157453D01*
X1804373Y157370D01*
X1804040Y157453D01*
X1803748Y157703D01*
X1803540Y158078D01*
X1803457Y158453D01*
Y158912D01*
X1803540Y159287D01*
X1803748Y159620D01*
X1803998Y159787D01*
X1804290Y159870D01*
X1804623Y159787D01*
X1804873Y159620D01*
X1805040Y159370D01*
X1805123Y159037D01*
X1805040Y158745D01*
X1804832Y158453D01*
X1804582Y158287D01*
X1804290Y158245D01*
X1803957Y158328D01*
X1803707Y158537D01*
X1803457Y158912D01*
G01X1802440Y159870D02*
X1801857Y157370D01*
X1801190Y159870D01*
X1800523Y157370D01*
X1799940Y159870D01*
G01X1798090Y157370D02*
Y159870D01*
X1798590Y159370D01*
G01Y157370D02*
X1797590D01*
G01X1795782Y158412D02*
X1795490Y158703D01*
X1795240Y158870D01*
X1794907Y158953D01*
X1794615Y158870D01*
X1794407Y158703D01*
X1794240Y158453D01*
X1794198Y158162D01*
X1794240Y157912D01*
X1794407Y157662D01*
X1794657Y157453D01*
X1794948Y157370D01*
X1795282Y157453D01*
X1795573Y157703D01*
X1795740Y158078D01*
X1795782Y158495D01*
X1795698Y159037D01*
X1795573Y159328D01*
X1795365Y159620D01*
X1795073Y159828D01*
X1794782Y159870D01*
X1794490Y159787D01*
X1794282Y159578D01*
G01X1827114Y186249D02*
X1827239Y185999D01*
X1827322Y185707D01*
Y185374D01*
X1827197Y184999D01*
X1826989Y184707D01*
X1826739Y184499D01*
X1826322Y184332D01*
X1825947Y184290D01*
X1825572Y184374D01*
X1825322Y184499D01*
X1825072Y184749D01*
X1824905Y185040D01*
X1824822Y185332D01*
Y185624D01*
X1824905Y185915D01*
X1825030Y186165D01*
X1825197Y186374D01*
G01X1824822Y188432D02*
X1827322D01*
X1826822Y187932D01*
G01X1824822D02*
Y188932D01*
G01Y190699D02*
X1827322D01*
Y191740D01*
X1827197Y192074D01*
X1827030Y192282D01*
X1826697Y192365D01*
X1826364Y192282D01*
X1826155Y192032D01*
X1826030Y191740D01*
Y190699D01*
G01Y191740D02*
X1824822Y192365D01*
G01Y194632D02*
X1827322D01*
X1826822Y194132D01*
G01X1824822D02*
Y195132D01*
G01X1823114Y186249D02*
X1823239Y185999D01*
X1823322Y185707D01*
Y185374D01*
X1823197Y184999D01*
X1822989Y184707D01*
X1822739Y184499D01*
X1822322Y184332D01*
X1821947Y184290D01*
X1821572Y184374D01*
X1821322Y184499D01*
X1821072Y184749D01*
X1820905Y185040D01*
X1820822Y185332D01*
Y185624D01*
X1820905Y185915D01*
X1821030Y186165D01*
X1821197Y186374D01*
G01X1820822Y188432D02*
X1823322D01*
X1822822Y187932D01*
G01X1820822D02*
Y188932D01*
G01Y190699D02*
X1823322D01*
Y191740D01*
X1823197Y192074D01*
X1823030Y192282D01*
X1822697Y192365D01*
X1822364Y192282D01*
X1822155Y192032D01*
X1822030Y191740D01*
Y190699D01*
G01Y191740D02*
X1820822Y192365D01*
G01X1822905Y193840D02*
X1823155Y194090D01*
X1823280Y194382D01*
X1823322Y194715D01*
X1823239Y195132D01*
X1823030Y195424D01*
X1822780Y195507D01*
X1822530Y195465D01*
X1822322Y195299D01*
X1821905Y194465D01*
X1821614Y194090D01*
X1821197Y193840D01*
X1820822Y193757D01*
Y195507D01*
G01X1786922Y214538D02*
X1787047Y214288D01*
X1787130Y213996D01*
Y213663D01*
X1787005Y213288D01*
X1786797Y212996D01*
X1786547Y212788D01*
X1786130Y212621D01*
X1785755Y212579D01*
X1785380Y212663D01*
X1785130Y212788D01*
X1784880Y213038D01*
X1784713Y213329D01*
X1784630Y213621D01*
Y213913D01*
X1784713Y214204D01*
X1784838Y214454D01*
X1785005Y214663D01*
G01X1784630Y216721D02*
X1787130D01*
X1786630Y216221D01*
G01X1784630D02*
Y217221D01*
G01Y218988D02*
X1787130D01*
Y220029D01*
X1787005Y220363D01*
X1786838Y220571D01*
X1786505Y220654D01*
X1786172Y220571D01*
X1785963Y220321D01*
X1785838Y220029D01*
Y218988D01*
G01Y220029D02*
X1784630Y220654D01*
G01Y222838D02*
X1785172Y222921D01*
X1785630Y223046D01*
X1786047Y223213D01*
X1786505Y223421D01*
X1787130Y223754D01*
Y222088D01*
G01X1795993Y215359D02*
X1796118Y215109D01*
X1796201Y214817D01*
Y214484D01*
X1796076Y214109D01*
X1795868Y213817D01*
X1795618Y213609D01*
X1795201Y213442D01*
X1794826Y213400D01*
X1794451Y213484D01*
X1794201Y213609D01*
X1793951Y213859D01*
X1793784Y214150D01*
X1793701Y214442D01*
Y214734D01*
X1793784Y215025D01*
X1793909Y215275D01*
X1794076Y215484D01*
G01X1793701Y217542D02*
X1796201D01*
X1795701Y217042D01*
G01X1793701D02*
Y218042D01*
G01Y219809D02*
X1796201D01*
Y220850D01*
X1796076Y221184D01*
X1795909Y221392D01*
X1795576Y221475D01*
X1795243Y221392D01*
X1795034Y221142D01*
X1794909Y220850D01*
Y219809D01*
G01Y220850D02*
X1793701Y221475D01*
G01X1794743Y222950D02*
X1795034Y223242D01*
X1795201Y223492D01*
X1795284Y223825D01*
X1795201Y224117D01*
X1795034Y224325D01*
X1794784Y224492D01*
X1794493Y224534D01*
X1794243Y224492D01*
X1793993Y224325D01*
X1793784Y224075D01*
X1793701Y223784D01*
X1793784Y223450D01*
X1794034Y223159D01*
X1794409Y222992D01*
X1794826Y222950D01*
X1795368Y223034D01*
X1795659Y223159D01*
X1795951Y223367D01*
X1796159Y223659D01*
X1796201Y223950D01*
X1796118Y224242D01*
X1795909Y224450D01*
G01X1799993Y215359D02*
X1800118Y215109D01*
X1800201Y214817D01*
Y214484D01*
X1800076Y214109D01*
X1799868Y213817D01*
X1799618Y213609D01*
X1799201Y213442D01*
X1798826Y213400D01*
X1798451Y213484D01*
X1798201Y213609D01*
X1797951Y213859D01*
X1797784Y214150D01*
X1797701Y214442D01*
Y214734D01*
X1797784Y215025D01*
X1797909Y215275D01*
X1798076Y215484D01*
G01X1797701Y217542D02*
X1800201D01*
X1799701Y217042D01*
G01X1797701D02*
Y218042D01*
G01Y219809D02*
X1800201D01*
Y220850D01*
X1800076Y221184D01*
X1799909Y221392D01*
X1799576Y221475D01*
X1799243Y221392D01*
X1799034Y221142D01*
X1798909Y220850D01*
Y219809D01*
G01Y220850D02*
X1797701Y221475D01*
G01X1798076Y222825D02*
X1797868Y223075D01*
X1797743Y223367D01*
X1797701Y223742D01*
X1797784Y224117D01*
X1797951Y224409D01*
X1798243Y224617D01*
X1798576Y224659D01*
X1798909Y224575D01*
X1799118Y224367D01*
X1799284Y224075D01*
X1799326Y223784D01*
X1799284Y223492D01*
X1799118Y223117D01*
X1800201Y223242D01*
Y224367D01*
G01X1808778Y215262D02*
X1808903Y215012D01*
X1808986Y214720D01*
Y214387D01*
X1808861Y214012D01*
X1808653Y213720D01*
X1808403Y213512D01*
X1807986Y213345D01*
X1807611Y213303D01*
X1807236Y213387D01*
X1806986Y213512D01*
X1806736Y213762D01*
X1806569Y214053D01*
X1806486Y214345D01*
Y214637D01*
X1806569Y214928D01*
X1806694Y215178D01*
X1806861Y215387D01*
G01X1806486Y217445D02*
X1808986D01*
X1808486Y216945D01*
G01X1806486D02*
Y217945D01*
G01Y219712D02*
X1808986D01*
Y220753D01*
X1808861Y221087D01*
X1808694Y221295D01*
X1808361Y221378D01*
X1808028Y221295D01*
X1807819Y221045D01*
X1807694Y220753D01*
Y219712D01*
G01Y220753D02*
X1806486Y221378D01*
G01Y224145D02*
X1808986D01*
X1807194Y222603D01*
Y224687D01*
G01X1812778Y215262D02*
X1812903Y215012D01*
X1812986Y214720D01*
Y214387D01*
X1812861Y214012D01*
X1812653Y213720D01*
X1812403Y213512D01*
X1811986Y213345D01*
X1811611Y213303D01*
X1811236Y213387D01*
X1810986Y213512D01*
X1810736Y213762D01*
X1810569Y214053D01*
X1810486Y214345D01*
Y214637D01*
X1810569Y214928D01*
X1810694Y215178D01*
X1810861Y215387D01*
G01X1810486Y217445D02*
X1812986D01*
X1812486Y216945D01*
G01X1810486D02*
Y217945D01*
G01Y219712D02*
X1812986D01*
Y220753D01*
X1812861Y221087D01*
X1812694Y221295D01*
X1812361Y221378D01*
X1812028Y221295D01*
X1811819Y221045D01*
X1811694Y220753D01*
Y219712D01*
G01Y220753D02*
X1810486Y221378D01*
G01X1810986Y222728D02*
X1810694Y222978D01*
X1810528Y223312D01*
X1810486Y223687D01*
X1810528Y224020D01*
X1810736Y224353D01*
X1810986Y224562D01*
X1811236Y224603D01*
X1811528Y224520D01*
X1811736Y224228D01*
X1811819Y223937D01*
Y223562D01*
G01Y223937D02*
X1811944Y224187D01*
X1812153Y224395D01*
X1812403Y224478D01*
X1812653Y224395D01*
X1812861Y224187D01*
X1812986Y223812D01*
X1812944Y223437D01*
X1812778Y223062D01*
G01X1782922Y214538D02*
X1783047Y214288D01*
X1783130Y213996D01*
Y213663D01*
X1783005Y213288D01*
X1782797Y212996D01*
X1782547Y212788D01*
X1782130Y212621D01*
X1781755Y212579D01*
X1781380Y212663D01*
X1781130Y212788D01*
X1780880Y213038D01*
X1780713Y213329D01*
X1780630Y213621D01*
Y213913D01*
X1780713Y214204D01*
X1780838Y214454D01*
X1781005Y214663D01*
G01X1780630Y216721D02*
X1783130D01*
X1782630Y216221D01*
G01X1780630D02*
Y217221D01*
G01Y218988D02*
X1783130D01*
Y220029D01*
X1783005Y220363D01*
X1782838Y220571D01*
X1782505Y220654D01*
X1782172Y220571D01*
X1781963Y220321D01*
X1781838Y220029D01*
Y218988D01*
G01Y220029D02*
X1780630Y220654D01*
G01Y222921D02*
X1780672Y223213D01*
X1780797Y223546D01*
X1781005Y223754D01*
X1781297Y223838D01*
X1781588Y223754D01*
X1781838Y223504D01*
X1781963Y223129D01*
Y222713D01*
X1782047Y222463D01*
X1782255Y222254D01*
X1782547Y222171D01*
X1782838Y222296D01*
X1783047Y222588D01*
X1783130Y222921D01*
X1783047Y223254D01*
X1782838Y223546D01*
X1782547Y223671D01*
X1782255Y223588D01*
X1782047Y223379D01*
X1781963Y223129D01*
Y222713D01*
X1781838Y222338D01*
X1781588Y222088D01*
X1781297Y222004D01*
X1781005Y222088D01*
X1780797Y222296D01*
X1780672Y222629D01*
X1780630Y222921D01*
G01X1809373Y181690D02*
Y184190D01*
X1808332D01*
X1807998Y184065D01*
X1807790Y183898D01*
X1807707Y183565D01*
X1807790Y183232D01*
X1808040Y183023D01*
X1808332Y182898D01*
X1809373D01*
G01X1808332D02*
X1807707Y181690D01*
G01X1806232Y183773D02*
X1805982Y184023D01*
X1805690Y184148D01*
X1805357Y184190D01*
X1804940Y184107D01*
X1804648Y183898D01*
X1804565Y183648D01*
X1804607Y183398D01*
X1804773Y183190D01*
X1805607Y182773D01*
X1805982Y182482D01*
X1806232Y182065D01*
X1806315Y181690D01*
X1804565D01*
G01X1803257Y182065D02*
X1803007Y181857D01*
X1802715Y181732D01*
X1802340Y181690D01*
X1801965Y181773D01*
X1801673Y181940D01*
X1801465Y182232D01*
X1801423Y182565D01*
X1801507Y182898D01*
X1801715Y183107D01*
X1802007Y183273D01*
X1802298Y183315D01*
X1802590Y183273D01*
X1802965Y183107D01*
X1802840Y184190D01*
X1801715D01*
G01X1800490D02*
X1799907Y181690D01*
X1799240Y184190D01*
X1798573Y181690D01*
X1797990Y184190D01*
G01X1796932Y183773D02*
X1796682Y184023D01*
X1796390Y184148D01*
X1796057Y184190D01*
X1795640Y184107D01*
X1795348Y183898D01*
X1795265Y183648D01*
X1795307Y183398D01*
X1795473Y183190D01*
X1796307Y182773D01*
X1796682Y182482D01*
X1796932Y182065D01*
X1797015Y181690D01*
X1795265D01*
G01X1809373Y178190D02*
Y180690D01*
X1808332D01*
X1807998Y180565D01*
X1807790Y180398D01*
X1807707Y180065D01*
X1807790Y179732D01*
X1808040Y179523D01*
X1808332Y179398D01*
X1809373D01*
G01X1808332D02*
X1807707Y178190D01*
G01X1806232Y180273D02*
X1805982Y180523D01*
X1805690Y180648D01*
X1805357Y180690D01*
X1804940Y180607D01*
X1804648Y180398D01*
X1804565Y180148D01*
X1804607Y179898D01*
X1804773Y179690D01*
X1805607Y179273D01*
X1805982Y178982D01*
X1806232Y178565D01*
X1806315Y178190D01*
X1804565D01*
G01X1803257Y178565D02*
X1803007Y178357D01*
X1802715Y178232D01*
X1802340Y178190D01*
X1801965Y178273D01*
X1801673Y178440D01*
X1801465Y178732D01*
X1801423Y179065D01*
X1801507Y179398D01*
X1801715Y179607D01*
X1802007Y179773D01*
X1802298Y179815D01*
X1802590Y179773D01*
X1802965Y179607D01*
X1802840Y180690D01*
X1801715D01*
G01X1800490D02*
X1799907Y178190D01*
X1799240Y180690D01*
X1798573Y178190D01*
X1797990Y180690D01*
G01X1796140Y178190D02*
Y180690D01*
X1796640Y180190D01*
G01Y178190D02*
X1795640D01*
G01X1809033Y188660D02*
Y191160D01*
X1807992D01*
X1807658Y191035D01*
X1807450Y190868D01*
X1807367Y190535D01*
X1807450Y190202D01*
X1807700Y189993D01*
X1807992Y189868D01*
X1809033D01*
G01X1807992D02*
X1807367Y188660D01*
G01X1805892Y190743D02*
X1805642Y190993D01*
X1805350Y191118D01*
X1805017Y191160D01*
X1804600Y191077D01*
X1804308Y190868D01*
X1804225Y190618D01*
X1804267Y190368D01*
X1804433Y190160D01*
X1805267Y189743D01*
X1805642Y189452D01*
X1805892Y189035D01*
X1805975Y188660D01*
X1804225D01*
G01X1802917Y189035D02*
X1802667Y188827D01*
X1802375Y188702D01*
X1802000Y188660D01*
X1801625Y188743D01*
X1801333Y188910D01*
X1801125Y189202D01*
X1801083Y189535D01*
X1801167Y189868D01*
X1801375Y190077D01*
X1801667Y190243D01*
X1801958Y190285D01*
X1802250Y190243D01*
X1802625Y190077D01*
X1802500Y191160D01*
X1801375D01*
G01X1800150D02*
X1799567Y188660D01*
X1798900Y191160D01*
X1798233Y188660D01*
X1797650Y191160D01*
G01X1796592Y189702D02*
X1796300Y189993D01*
X1796050Y190160D01*
X1795717Y190243D01*
X1795425Y190160D01*
X1795217Y189993D01*
X1795050Y189743D01*
X1795008Y189452D01*
X1795050Y189202D01*
X1795217Y188952D01*
X1795467Y188743D01*
X1795758Y188660D01*
X1796092Y188743D01*
X1796383Y188993D01*
X1796550Y189368D01*
X1796592Y189785D01*
X1796508Y190327D01*
X1796383Y190618D01*
X1796175Y190910D01*
X1795883Y191118D01*
X1795592Y191160D01*
X1795300Y191077D01*
X1795092Y190868D01*
G01X1809373Y185190D02*
Y187690D01*
X1808332D01*
X1807998Y187565D01*
X1807790Y187398D01*
X1807707Y187065D01*
X1807790Y186732D01*
X1808040Y186523D01*
X1808332Y186398D01*
X1809373D01*
G01X1808332D02*
X1807707Y185190D01*
G01X1806232Y187273D02*
X1805982Y187523D01*
X1805690Y187648D01*
X1805357Y187690D01*
X1804940Y187607D01*
X1804648Y187398D01*
X1804565Y187148D01*
X1804607Y186898D01*
X1804773Y186690D01*
X1805607Y186273D01*
X1805982Y185982D01*
X1806232Y185565D01*
X1806315Y185190D01*
X1804565D01*
G01X1803257Y185565D02*
X1803007Y185357D01*
X1802715Y185232D01*
X1802340Y185190D01*
X1801965Y185273D01*
X1801673Y185440D01*
X1801465Y185732D01*
X1801423Y186065D01*
X1801507Y186398D01*
X1801715Y186607D01*
X1802007Y186773D01*
X1802298Y186815D01*
X1802590Y186773D01*
X1802965Y186607D01*
X1802840Y187690D01*
X1801715D01*
G01X1800490D02*
X1799907Y185190D01*
X1799240Y187690D01*
X1798573Y185190D01*
X1797990Y187690D01*
G01X1796932Y187273D02*
X1796682Y187523D01*
X1796390Y187648D01*
X1796057Y187690D01*
X1795640Y187607D01*
X1795348Y187398D01*
X1795265Y187148D01*
X1795307Y186898D01*
X1795473Y186690D01*
X1796307Y186273D01*
X1796682Y185982D01*
X1796932Y185565D01*
X1797015Y185190D01*
X1795265D01*
G01X1793832Y187273D02*
X1793582Y187523D01*
X1793290Y187648D01*
X1792957Y187690D01*
X1792540Y187607D01*
X1792248Y187398D01*
X1792165Y187148D01*
X1792207Y186898D01*
X1792373Y186690D01*
X1793207Y186273D01*
X1793582Y185982D01*
X1793832Y185565D01*
X1793915Y185190D01*
X1792165D01*
G01X1809033Y192160D02*
Y194660D01*
X1807992D01*
X1807658Y194535D01*
X1807450Y194368D01*
X1807367Y194035D01*
X1807450Y193702D01*
X1807700Y193493D01*
X1807992Y193368D01*
X1809033D01*
G01X1807992D02*
X1807367Y192160D01*
G01X1805892Y194243D02*
X1805642Y194493D01*
X1805350Y194618D01*
X1805017Y194660D01*
X1804600Y194577D01*
X1804308Y194368D01*
X1804225Y194118D01*
X1804267Y193868D01*
X1804433Y193660D01*
X1805267Y193243D01*
X1805642Y192952D01*
X1805892Y192535D01*
X1805975Y192160D01*
X1804225D01*
G01X1802917Y192535D02*
X1802667Y192327D01*
X1802375Y192202D01*
X1802000Y192160D01*
X1801625Y192243D01*
X1801333Y192410D01*
X1801125Y192702D01*
X1801083Y193035D01*
X1801167Y193368D01*
X1801375Y193577D01*
X1801667Y193743D01*
X1801958Y193785D01*
X1802250Y193743D01*
X1802625Y193577D01*
X1802500Y194660D01*
X1801375D01*
G01X1800150D02*
X1799567Y192160D01*
X1798900Y194660D01*
X1798233Y192160D01*
X1797650Y194660D01*
G01X1795800Y192160D02*
Y194660D01*
X1796300Y194160D01*
G01Y192160D02*
X1795300D01*
G01X1793492Y194243D02*
X1793242Y194493D01*
X1792950Y194618D01*
X1792617Y194660D01*
X1792200Y194577D01*
X1791908Y194368D01*
X1791825Y194118D01*
X1791867Y193868D01*
X1792033Y193660D01*
X1792867Y193243D01*
X1793242Y192952D01*
X1793492Y192535D01*
X1793575Y192160D01*
X1791825D01*
G01X1780300Y157717D02*
X1782800D01*
Y158758D01*
X1782675Y159092D01*
X1782508Y159300D01*
X1782175Y159383D01*
X1781842Y159300D01*
X1781633Y159050D01*
X1781508Y158758D01*
Y157717D01*
G01Y158758D02*
X1780300Y159383D01*
G01X1782383Y160858D02*
X1782633Y161108D01*
X1782758Y161400D01*
X1782800Y161733D01*
X1782717Y162150D01*
X1782508Y162442D01*
X1782258Y162525D01*
X1782008Y162483D01*
X1781800Y162317D01*
X1781383Y161483D01*
X1781092Y161108D01*
X1780675Y160858D01*
X1780300Y160775D01*
Y162525D01*
G01X1780675Y163833D02*
X1780467Y164083D01*
X1780342Y164375D01*
X1780300Y164750D01*
X1780383Y165125D01*
X1780550Y165417D01*
X1780842Y165625D01*
X1781175Y165667D01*
X1781508Y165583D01*
X1781717Y165375D01*
X1781883Y165083D01*
X1781925Y164792D01*
X1781883Y164500D01*
X1781717Y164125D01*
X1782800Y164250D01*
Y165375D01*
G01Y166600D02*
X1780300Y167183D01*
X1782800Y167850D01*
X1780300Y168517D01*
X1782800Y169100D01*
G01X1780300Y170950D02*
X1782800D01*
X1782300Y170450D01*
G01X1780300D02*
Y171450D01*
G01Y174050D02*
X1780342Y174342D01*
X1780467Y174675D01*
X1780675Y174883D01*
X1780967Y174967D01*
X1781258Y174883D01*
X1781508Y174633D01*
X1781633Y174258D01*
Y173842D01*
X1781717Y173592D01*
X1781925Y173383D01*
X1782217Y173300D01*
X1782508Y173425D01*
X1782717Y173717D01*
X1782800Y174050D01*
X1782717Y174383D01*
X1782508Y174675D01*
X1782217Y174800D01*
X1781925Y174717D01*
X1781717Y174508D01*
X1781633Y174258D01*
Y173842D01*
X1781508Y173467D01*
X1781258Y173217D01*
X1780967Y173133D01*
X1780675Y173217D01*
X1780467Y173425D01*
X1780342Y173758D01*
X1780300Y174050D01*
G01X1838233Y240300D02*
Y242800D01*
X1837192D01*
X1836858Y242675D01*
X1836650Y242508D01*
X1836567Y242175D01*
X1836650Y241842D01*
X1836900Y241633D01*
X1837192Y241508D01*
X1838233D01*
G01X1837192D02*
X1836567Y240300D01*
G01X1834300D02*
Y242800D01*
X1834800Y242300D01*
G01Y240300D02*
X1833800D01*
G01X1832033D02*
Y242800D01*
X1830992D01*
X1830658Y242675D01*
X1830450Y242508D01*
X1830367Y242175D01*
X1830450Y241842D01*
X1830700Y241633D01*
X1830992Y241508D01*
X1832033D01*
G01X1830992D02*
X1830367Y240300D01*
G01X1828100D02*
Y242800D01*
X1828600Y242300D01*
G01Y240300D02*
X1827600D01*
G01X1825000D02*
X1824708Y240342D01*
X1824375Y240467D01*
X1824167Y240675D01*
X1824083Y240967D01*
X1824167Y241258D01*
X1824417Y241508D01*
X1824792Y241633D01*
X1825208D01*
X1825458Y241717D01*
X1825667Y241925D01*
X1825750Y242217D01*
X1825625Y242508D01*
X1825333Y242717D01*
X1825000Y242800D01*
X1824667Y242717D01*
X1824375Y242508D01*
X1824250Y242217D01*
X1824333Y241925D01*
X1824542Y241717D01*
X1824792Y241633D01*
X1825208D01*
X1825583Y241508D01*
X1825833Y241258D01*
X1825917Y240967D01*
X1825833Y240675D01*
X1825625Y240467D01*
X1825292Y240342D01*
X1825000Y240300D01*
G01X1843833Y219200D02*
Y221700D01*
X1842792D01*
X1842458Y221575D01*
X1842250Y221408D01*
X1842167Y221075D01*
X1842250Y220742D01*
X1842500Y220533D01*
X1842792Y220408D01*
X1843833D01*
G01X1842792D02*
X1842167Y219200D01*
G01X1839900D02*
Y221700D01*
X1840400Y221200D01*
G01Y219200D02*
X1839400D01*
G01X1837633D02*
Y221700D01*
X1836592D01*
X1836258Y221575D01*
X1836050Y221408D01*
X1835967Y221075D01*
X1836050Y220742D01*
X1836300Y220533D01*
X1836592Y220408D01*
X1837633D01*
G01X1836592D02*
X1835967Y219200D01*
G01X1834492Y221283D02*
X1834242Y221533D01*
X1833950Y221658D01*
X1833617Y221700D01*
X1833200Y221617D01*
X1832908Y221408D01*
X1832825Y221158D01*
X1832867Y220908D01*
X1833033Y220700D01*
X1833867Y220283D01*
X1834242Y219992D01*
X1834492Y219575D01*
X1834575Y219200D01*
X1832825D01*
G01X1830600Y221700D02*
X1830933Y221617D01*
X1831183Y221408D01*
X1831350Y221158D01*
X1831475Y220825D01*
X1831517Y220450D01*
X1831475Y220075D01*
X1831350Y219742D01*
X1831183Y219492D01*
X1830933Y219283D01*
X1830600Y219200D01*
X1830267Y219283D01*
X1830017Y219492D01*
X1829850Y219742D01*
X1829725Y220075D01*
X1829683Y220450D01*
X1829725Y220825D01*
X1829850Y221158D01*
X1830017Y221408D01*
X1830267Y221617D01*
X1830600Y221700D01*
G01X1838233Y236800D02*
Y239300D01*
X1837192D01*
X1836858Y239175D01*
X1836650Y239008D01*
X1836567Y238675D01*
X1836650Y238342D01*
X1836900Y238133D01*
X1837192Y238008D01*
X1838233D01*
G01X1837192D02*
X1836567Y236800D01*
G01X1834300D02*
Y239300D01*
X1834800Y238800D01*
G01Y236800D02*
X1833800D01*
G01X1832033D02*
Y239300D01*
X1830992D01*
X1830658Y239175D01*
X1830450Y239008D01*
X1830367Y238675D01*
X1830450Y238342D01*
X1830700Y238133D01*
X1830992Y238008D01*
X1832033D01*
G01X1830992D02*
X1830367Y236800D01*
G01X1828100D02*
Y239300D01*
X1828600Y238800D01*
G01Y236800D02*
X1827600D01*
G01X1825708Y237092D02*
X1825417Y236883D01*
X1825083Y236800D01*
X1824750Y236883D01*
X1824458Y237133D01*
X1824250Y237508D01*
X1824167Y237883D01*
Y238342D01*
X1824250Y238717D01*
X1824458Y239050D01*
X1824708Y239217D01*
X1825000Y239300D01*
X1825333Y239217D01*
X1825583Y239050D01*
X1825750Y238800D01*
X1825833Y238467D01*
X1825750Y238175D01*
X1825542Y237883D01*
X1825292Y237717D01*
X1825000Y237675D01*
X1824667Y237758D01*
X1824417Y237967D01*
X1824167Y238342D01*
G01X1843533Y227500D02*
Y230000D01*
X1842492D01*
X1842158Y229875D01*
X1841950Y229708D01*
X1841867Y229375D01*
X1841950Y229042D01*
X1842200Y228833D01*
X1842492Y228708D01*
X1843533D01*
G01X1842492D02*
X1841867Y227500D01*
G01X1839600D02*
Y230000D01*
X1840100Y229500D01*
G01Y227500D02*
X1839100D01*
G01X1837750Y230000D02*
X1837167Y227500D01*
X1836500Y230000D01*
X1835833Y227500D01*
X1835250Y230000D01*
G01X1832900Y227500D02*
Y230000D01*
X1834442Y228208D01*
X1832358D01*
G01X1829800Y227500D02*
Y230000D01*
X1831342Y228208D01*
X1829258D01*
G01X1843533Y224000D02*
Y226500D01*
X1842492D01*
X1842158Y226375D01*
X1841950Y226208D01*
X1841867Y225875D01*
X1841950Y225542D01*
X1842200Y225333D01*
X1842492Y225208D01*
X1843533D01*
G01X1842492D02*
X1841867Y224000D01*
G01X1839600D02*
Y226500D01*
X1840100Y226000D01*
G01Y224000D02*
X1839100D01*
G01X1837750Y226500D02*
X1837167Y224000D01*
X1836500Y226500D01*
X1835833Y224000D01*
X1835250Y226500D01*
G01X1832900Y224000D02*
Y226500D01*
X1834442Y224708D01*
X1832358D01*
G01X1831217Y224375D02*
X1830967Y224167D01*
X1830675Y224042D01*
X1830300Y224000D01*
X1829925Y224083D01*
X1829633Y224250D01*
X1829425Y224542D01*
X1829383Y224875D01*
X1829467Y225208D01*
X1829675Y225417D01*
X1829967Y225583D01*
X1830258Y225625D01*
X1830550Y225583D01*
X1830925Y225417D01*
X1830800Y226500D01*
X1829675D01*
G01X1779892Y250917D02*
X1780017Y250667D01*
X1780100Y250375D01*
Y250042D01*
X1779975Y249667D01*
X1779767Y249375D01*
X1779517Y249167D01*
X1779100Y249000D01*
X1778725Y248958D01*
X1778350Y249042D01*
X1778100Y249167D01*
X1777850Y249417D01*
X1777683Y249708D01*
X1777600Y250000D01*
Y250292D01*
X1777683Y250583D01*
X1777808Y250833D01*
X1777975Y251042D01*
G01X1779683Y252308D02*
X1779933Y252558D01*
X1780058Y252850D01*
X1780100Y253183D01*
X1780017Y253600D01*
X1779808Y253892D01*
X1779558Y253975D01*
X1779308Y253933D01*
X1779100Y253767D01*
X1778683Y252933D01*
X1778392Y252558D01*
X1777975Y252308D01*
X1777600Y252225D01*
Y253975D01*
G01Y255367D02*
X1780100D01*
Y256367D01*
X1779975Y256700D01*
X1779683Y256950D01*
X1779350Y257033D01*
X1779017Y256950D01*
X1778767Y256742D01*
X1778642Y256367D01*
Y255367D01*
G01X1777600Y259300D02*
X1780100D01*
X1779600Y258800D01*
G01X1777600D02*
Y259800D01*
G01X1779683Y261608D02*
X1779933Y261858D01*
X1780058Y262150D01*
X1780100Y262483D01*
X1780017Y262900D01*
X1779808Y263192D01*
X1779558Y263275D01*
X1779308Y263233D01*
X1779100Y263067D01*
X1778683Y262233D01*
X1778392Y261858D01*
X1777975Y261608D01*
X1777600Y261525D01*
Y263275D01*
G01X1783392Y250917D02*
X1783517Y250667D01*
X1783600Y250375D01*
Y250042D01*
X1783475Y249667D01*
X1783267Y249375D01*
X1783017Y249167D01*
X1782600Y249000D01*
X1782225Y248958D01*
X1781850Y249042D01*
X1781600Y249167D01*
X1781350Y249417D01*
X1781183Y249708D01*
X1781100Y250000D01*
Y250292D01*
X1781183Y250583D01*
X1781308Y250833D01*
X1781475Y251042D01*
G01X1783183Y252308D02*
X1783433Y252558D01*
X1783558Y252850D01*
X1783600Y253183D01*
X1783517Y253600D01*
X1783308Y253892D01*
X1783058Y253975D01*
X1782808Y253933D01*
X1782600Y253767D01*
X1782183Y252933D01*
X1781892Y252558D01*
X1781475Y252308D01*
X1781100Y252225D01*
Y253975D01*
G01Y255367D02*
X1783600D01*
Y256367D01*
X1783475Y256700D01*
X1783183Y256950D01*
X1782850Y257033D01*
X1782517Y256950D01*
X1782267Y256742D01*
X1782142Y256367D01*
Y255367D01*
G01X1781100Y259300D02*
X1783600D01*
X1783100Y258800D01*
G01X1781100D02*
Y259800D01*
G01Y262400D02*
X1783600D01*
X1783100Y261900D01*
G01X1781100D02*
Y262900D01*
G01X1827400Y461567D02*
X1829900D01*
Y462608D01*
X1829775Y462942D01*
X1829608Y463150D01*
X1829275Y463233D01*
X1828942Y463150D01*
X1828733Y462900D01*
X1828608Y462608D01*
Y461567D01*
G01Y462608D02*
X1827400Y463233D01*
G01Y465500D02*
X1829900D01*
X1829400Y465000D01*
G01X1827400D02*
Y466000D01*
G01X1829900Y467350D02*
X1827400Y467933D01*
X1829900Y468600D01*
X1827400Y469267D01*
X1829900Y469850D01*
G01X1827400Y471700D02*
X1829900D01*
X1829400Y471200D01*
G01X1827400D02*
Y472200D01*
G01X1827900Y473883D02*
X1827608Y474133D01*
X1827442Y474467D01*
X1827400Y474842D01*
X1827442Y475175D01*
X1827650Y475508D01*
X1827900Y475717D01*
X1828150Y475758D01*
X1828442Y475675D01*
X1828650Y475383D01*
X1828733Y475092D01*
Y474717D01*
G01Y475092D02*
X1828858Y475342D01*
X1829067Y475550D01*
X1829317Y475633D01*
X1829567Y475550D01*
X1829775Y475342D01*
X1829900Y474967D01*
X1829858Y474592D01*
X1829692Y474217D01*
G01X1831400Y461667D02*
X1833900D01*
Y462708D01*
X1833775Y463042D01*
X1833608Y463250D01*
X1833275Y463333D01*
X1832942Y463250D01*
X1832733Y463000D01*
X1832608Y462708D01*
Y461667D01*
G01Y462708D02*
X1831400Y463333D01*
G01Y465600D02*
X1833900D01*
X1833400Y465100D01*
G01X1831400D02*
Y466100D01*
G01X1833900Y467450D02*
X1831400Y468033D01*
X1833900Y468700D01*
X1831400Y469367D01*
X1833900Y469950D01*
G01X1831400Y471800D02*
X1833900D01*
X1833400Y471300D01*
G01X1831400D02*
Y472300D01*
G01X1833483Y474108D02*
X1833733Y474358D01*
X1833858Y474650D01*
X1833900Y474983D01*
X1833817Y475400D01*
X1833608Y475692D01*
X1833358Y475775D01*
X1833108Y475733D01*
X1832900Y475567D01*
X1832483Y474733D01*
X1832192Y474358D01*
X1831775Y474108D01*
X1831400Y474025D01*
Y475775D01*
G01X1824592Y439647D02*
X1824717Y439397D01*
X1824800Y439105D01*
Y438772D01*
X1824675Y438397D01*
X1824467Y438105D01*
X1824217Y437897D01*
X1823800Y437730D01*
X1823425Y437688D01*
X1823050Y437772D01*
X1822800Y437897D01*
X1822550Y438147D01*
X1822383Y438438D01*
X1822300Y438730D01*
Y439022D01*
X1822383Y439313D01*
X1822508Y439563D01*
X1822675Y439772D01*
G01X1822300Y441830D02*
X1824800D01*
X1824300Y441330D01*
G01X1822300D02*
Y442330D01*
G01Y443847D02*
X1824800D01*
X1822717Y444930D01*
X1824800Y446013D01*
X1822300D01*
G01Y448030D02*
X1822342Y448322D01*
X1822467Y448655D01*
X1822675Y448863D01*
X1822967Y448947D01*
X1823258Y448863D01*
X1823508Y448613D01*
X1823633Y448238D01*
Y447822D01*
X1823717Y447572D01*
X1823925Y447363D01*
X1824217Y447280D01*
X1824508Y447405D01*
X1824717Y447697D01*
X1824800Y448030D01*
X1824717Y448363D01*
X1824508Y448655D01*
X1824217Y448780D01*
X1823925Y448697D01*
X1823717Y448488D01*
X1823633Y448238D01*
Y447822D01*
X1823508Y447447D01*
X1823258Y447197D01*
X1822967Y447113D01*
X1822675Y447197D01*
X1822467Y447405D01*
X1822342Y447738D01*
X1822300Y448030D01*
G01X1837192Y439847D02*
X1837317Y439597D01*
X1837400Y439305D01*
Y438972D01*
X1837275Y438597D01*
X1837067Y438305D01*
X1836817Y438097D01*
X1836400Y437930D01*
X1836025Y437888D01*
X1835650Y437972D01*
X1835400Y438097D01*
X1835150Y438347D01*
X1834983Y438638D01*
X1834900Y438930D01*
Y439222D01*
X1834983Y439513D01*
X1835108Y439763D01*
X1835275Y439972D01*
G01X1834900Y442030D02*
X1837400D01*
X1836900Y441530D01*
G01X1834900D02*
Y442530D01*
G01Y444047D02*
X1837400D01*
X1835317Y445130D01*
X1837400Y446213D01*
X1834900D01*
G01X1835942Y447438D02*
X1836233Y447730D01*
X1836400Y447980D01*
X1836483Y448313D01*
X1836400Y448605D01*
X1836233Y448813D01*
X1835983Y448980D01*
X1835692Y449022D01*
X1835442Y448980D01*
X1835192Y448813D01*
X1834983Y448563D01*
X1834900Y448272D01*
X1834983Y447938D01*
X1835233Y447647D01*
X1835608Y447480D01*
X1836025Y447438D01*
X1836567Y447522D01*
X1836858Y447647D01*
X1837150Y447855D01*
X1837358Y448147D01*
X1837400Y448438D01*
X1837317Y448730D01*
X1837108Y448938D01*
G01X1833192Y439847D02*
X1833317Y439597D01*
X1833400Y439305D01*
Y438972D01*
X1833275Y438597D01*
X1833067Y438305D01*
X1832817Y438097D01*
X1832400Y437930D01*
X1832025Y437888D01*
X1831650Y437972D01*
X1831400Y438097D01*
X1831150Y438347D01*
X1830983Y438638D01*
X1830900Y438930D01*
Y439222D01*
X1830983Y439513D01*
X1831108Y439763D01*
X1831275Y439972D01*
G01X1830900Y442030D02*
X1833400D01*
X1832900Y441530D01*
G01X1830900D02*
Y442530D01*
G01Y444047D02*
X1833400D01*
X1831317Y445130D01*
X1833400Y446213D01*
X1830900D01*
G01Y448147D02*
X1831442Y448230D01*
X1831900Y448355D01*
X1832317Y448522D01*
X1832775Y448730D01*
X1833400Y449063D01*
Y447397D01*
G01X1820592Y439647D02*
X1820717Y439397D01*
X1820800Y439105D01*
Y438772D01*
X1820675Y438397D01*
X1820467Y438105D01*
X1820217Y437897D01*
X1819800Y437730D01*
X1819425Y437688D01*
X1819050Y437772D01*
X1818800Y437897D01*
X1818550Y438147D01*
X1818383Y438438D01*
X1818300Y438730D01*
Y439022D01*
X1818383Y439313D01*
X1818508Y439563D01*
X1818675Y439772D01*
G01X1818300Y441830D02*
X1820800D01*
X1820300Y441330D01*
G01X1818300D02*
Y442330D01*
G01Y443847D02*
X1820800D01*
X1818717Y444930D01*
X1820800Y446013D01*
X1818300D01*
G01X1818592Y447322D02*
X1818383Y447613D01*
X1818300Y447947D01*
X1818383Y448280D01*
X1818633Y448572D01*
X1819008Y448780D01*
X1819383Y448863D01*
X1819842D01*
X1820217Y448780D01*
X1820550Y448572D01*
X1820717Y448322D01*
X1820800Y448030D01*
X1820717Y447697D01*
X1820550Y447447D01*
X1820300Y447280D01*
X1819967Y447197D01*
X1819675Y447280D01*
X1819383Y447488D01*
X1819217Y447738D01*
X1819175Y448030D01*
X1819258Y448363D01*
X1819467Y448613D01*
X1819842Y448863D01*
G01X1807692Y436697D02*
X1807817Y436447D01*
X1807900Y436155D01*
Y435822D01*
X1807775Y435447D01*
X1807567Y435155D01*
X1807317Y434947D01*
X1806900Y434780D01*
X1806525Y434738D01*
X1806150Y434822D01*
X1805900Y434947D01*
X1805650Y435197D01*
X1805483Y435488D01*
X1805400Y435780D01*
Y436072D01*
X1805483Y436363D01*
X1805608Y436613D01*
X1805775Y436822D01*
G01X1805400Y438880D02*
X1807900D01*
X1807400Y438380D01*
G01X1805400D02*
Y439380D01*
G01Y440897D02*
X1807900D01*
X1805817Y441980D01*
X1807900Y443063D01*
X1805400D01*
G01Y445080D02*
X1807900D01*
X1807400Y444580D01*
G01X1805400D02*
Y445580D01*
G01Y448180D02*
X1807900D01*
X1807400Y447680D01*
G01X1805400D02*
Y448680D01*
G01X1811692Y436697D02*
X1811817Y436447D01*
X1811900Y436155D01*
Y435822D01*
X1811775Y435447D01*
X1811567Y435155D01*
X1811317Y434947D01*
X1810900Y434780D01*
X1810525Y434738D01*
X1810150Y434822D01*
X1809900Y434947D01*
X1809650Y435197D01*
X1809483Y435488D01*
X1809400Y435780D01*
Y436072D01*
X1809483Y436363D01*
X1809608Y436613D01*
X1809775Y436822D01*
G01X1809400Y438880D02*
X1811900D01*
X1811400Y438380D01*
G01X1809400D02*
Y439380D01*
G01Y440897D02*
X1811900D01*
X1809817Y441980D01*
X1811900Y443063D01*
X1809400D01*
G01Y445080D02*
X1811900D01*
X1811400Y444580D01*
G01X1809400D02*
Y445580D01*
G01X1811900Y448180D02*
X1811817Y447847D01*
X1811608Y447597D01*
X1811358Y447430D01*
X1811025Y447305D01*
X1810650Y447263D01*
X1810275Y447305D01*
X1809942Y447430D01*
X1809692Y447597D01*
X1809483Y447847D01*
X1809400Y448180D01*
X1809483Y448513D01*
X1809692Y448763D01*
X1809942Y448930D01*
X1810275Y449055D01*
X1810650Y449097D01*
X1811025Y449055D01*
X1811358Y448930D01*
X1811608Y448763D01*
X1811817Y448513D01*
X1811900Y448180D01*
G01X1782692Y436597D02*
X1782817Y436347D01*
X1782900Y436055D01*
Y435722D01*
X1782775Y435347D01*
X1782567Y435055D01*
X1782317Y434847D01*
X1781900Y434680D01*
X1781525Y434638D01*
X1781150Y434722D01*
X1780900Y434847D01*
X1780650Y435097D01*
X1780483Y435388D01*
X1780400Y435680D01*
Y435972D01*
X1780483Y436263D01*
X1780608Y436513D01*
X1780775Y436722D01*
G01X1780400Y438780D02*
X1782900D01*
X1782400Y438280D01*
G01X1780400D02*
Y439280D01*
G01Y440797D02*
X1782900D01*
X1780817Y441880D01*
X1782900Y442963D01*
X1780400D01*
G01Y444980D02*
X1782900D01*
X1782400Y444480D01*
G01X1780400D02*
Y445480D01*
G01X1780775Y447163D02*
X1780567Y447413D01*
X1780442Y447705D01*
X1780400Y448080D01*
X1780483Y448455D01*
X1780650Y448747D01*
X1780942Y448955D01*
X1781275Y448997D01*
X1781608Y448913D01*
X1781817Y448705D01*
X1781983Y448413D01*
X1782025Y448122D01*
X1781983Y447830D01*
X1781817Y447455D01*
X1782900Y447580D01*
Y448705D01*
G01X1799192Y436597D02*
X1799317Y436347D01*
X1799400Y436055D01*
Y435722D01*
X1799275Y435347D01*
X1799067Y435055D01*
X1798817Y434847D01*
X1798400Y434680D01*
X1798025Y434638D01*
X1797650Y434722D01*
X1797400Y434847D01*
X1797150Y435097D01*
X1796983Y435388D01*
X1796900Y435680D01*
Y435972D01*
X1796983Y436263D01*
X1797108Y436513D01*
X1797275Y436722D01*
G01X1796900Y438780D02*
X1799400D01*
X1798900Y438280D01*
G01X1796900D02*
Y439280D01*
G01Y440797D02*
X1799400D01*
X1797317Y441880D01*
X1799400Y442963D01*
X1796900D01*
G01Y444980D02*
X1799400D01*
X1798900Y444480D01*
G01X1796900D02*
Y445480D01*
G01X1798983Y447288D02*
X1799233Y447538D01*
X1799358Y447830D01*
X1799400Y448163D01*
X1799317Y448580D01*
X1799108Y448872D01*
X1798858Y448955D01*
X1798608Y448913D01*
X1798400Y448747D01*
X1797983Y447913D01*
X1797692Y447538D01*
X1797275Y447288D01*
X1796900Y447205D01*
Y448955D01*
G01X1795192Y436597D02*
X1795317Y436347D01*
X1795400Y436055D01*
Y435722D01*
X1795275Y435347D01*
X1795067Y435055D01*
X1794817Y434847D01*
X1794400Y434680D01*
X1794025Y434638D01*
X1793650Y434722D01*
X1793400Y434847D01*
X1793150Y435097D01*
X1792983Y435388D01*
X1792900Y435680D01*
Y435972D01*
X1792983Y436263D01*
X1793108Y436513D01*
X1793275Y436722D01*
G01X1792900Y438780D02*
X1795400D01*
X1794900Y438280D01*
G01X1792900D02*
Y439280D01*
G01Y440797D02*
X1795400D01*
X1793317Y441880D01*
X1795400Y442963D01*
X1792900D01*
G01Y444980D02*
X1795400D01*
X1794900Y444480D01*
G01X1792900D02*
Y445480D01*
G01X1793400Y447163D02*
X1793108Y447413D01*
X1792942Y447747D01*
X1792900Y448122D01*
X1792942Y448455D01*
X1793150Y448788D01*
X1793400Y448997D01*
X1793650Y449038D01*
X1793942Y448955D01*
X1794150Y448663D01*
X1794233Y448372D01*
Y447997D01*
G01Y448372D02*
X1794358Y448622D01*
X1794567Y448830D01*
X1794817Y448913D01*
X1795067Y448830D01*
X1795275Y448622D01*
X1795400Y448247D01*
X1795358Y447872D01*
X1795192Y447497D01*
G01X1786692Y436597D02*
X1786817Y436347D01*
X1786900Y436055D01*
Y435722D01*
X1786775Y435347D01*
X1786567Y435055D01*
X1786317Y434847D01*
X1785900Y434680D01*
X1785525Y434638D01*
X1785150Y434722D01*
X1784900Y434847D01*
X1784650Y435097D01*
X1784483Y435388D01*
X1784400Y435680D01*
Y435972D01*
X1784483Y436263D01*
X1784608Y436513D01*
X1784775Y436722D01*
G01X1784400Y438780D02*
X1786900D01*
X1786400Y438280D01*
G01X1784400D02*
Y439280D01*
G01Y440797D02*
X1786900D01*
X1784817Y441880D01*
X1786900Y442963D01*
X1784400D01*
G01Y444980D02*
X1786900D01*
X1786400Y444480D01*
G01X1784400D02*
Y445480D01*
G01Y448580D02*
X1786900D01*
X1785108Y447038D01*
Y449122D01*
G01X1834494Y524716D02*
Y527216D01*
X1833453D01*
X1833119Y527091D01*
X1832911Y526924D01*
X1832828Y526591D01*
X1832911Y526258D01*
X1833161Y526049D01*
X1833453Y525924D01*
X1834494D01*
G01X1833453D02*
X1832828Y524716D01*
G01X1831269Y525008D02*
X1830978Y524799D01*
X1830644Y524716D01*
X1830311Y524799D01*
X1830019Y525049D01*
X1829811Y525424D01*
X1829728Y525799D01*
Y526258D01*
X1829811Y526633D01*
X1830019Y526966D01*
X1830269Y527133D01*
X1830561Y527216D01*
X1830894Y527133D01*
X1831144Y526966D01*
X1831311Y526716D01*
X1831394Y526383D01*
X1831311Y526091D01*
X1831103Y525799D01*
X1830853Y525633D01*
X1830561Y525591D01*
X1830228Y525674D01*
X1829978Y525883D01*
X1829728Y526258D01*
G01X1827128Y526049D02*
X1826961Y526174D01*
X1826836Y526383D01*
X1826753Y526674D01*
X1826836Y526924D01*
X1827003Y527091D01*
X1827294Y527216D01*
X1828419D01*
Y524716D01*
X1827044D01*
X1826753Y524883D01*
X1826586Y525133D01*
X1826503Y525424D01*
X1826586Y525716D01*
X1826836Y525966D01*
X1827128Y526049D01*
X1828419D01*
G01X1824361Y524716D02*
Y527216D01*
X1824861Y526716D01*
G01Y524716D02*
X1823861D01*
G01X1821261Y527216D02*
X1821594Y527133D01*
X1821844Y526924D01*
X1822011Y526674D01*
X1822136Y526341D01*
X1822178Y525966D01*
X1822136Y525591D01*
X1822011Y525258D01*
X1821844Y525008D01*
X1821594Y524799D01*
X1821261Y524716D01*
X1820928Y524799D01*
X1820678Y525008D01*
X1820511Y525258D01*
X1820386Y525591D01*
X1820344Y525966D01*
X1820386Y526341D01*
X1820511Y526674D01*
X1820678Y526924D01*
X1820928Y527133D01*
X1821261Y527216D01*
G01X1820367Y502467D02*
X1822867D01*
Y503508D01*
X1822742Y503842D01*
X1822575Y504050D01*
X1822242Y504133D01*
X1821909Y504050D01*
X1821700Y503800D01*
X1821575Y503508D01*
Y502467D01*
G01Y503508D02*
X1820367Y504133D01*
G01Y506400D02*
X1822867D01*
X1822367Y505900D01*
G01X1820367D02*
Y506900D01*
G01Y508417D02*
X1822867D01*
X1820784Y509500D01*
X1822867Y510583D01*
X1820367D01*
G01X1822450Y511808D02*
X1822700Y512058D01*
X1822825Y512350D01*
X1822867Y512683D01*
X1822784Y513100D01*
X1822575Y513392D01*
X1822325Y513475D01*
X1822075Y513433D01*
X1821867Y513267D01*
X1821450Y512433D01*
X1821159Y512058D01*
X1820742Y511808D01*
X1820367Y511725D01*
Y513475D01*
G01Y516200D02*
X1822867D01*
X1821075Y514658D01*
Y516742D01*
G01X1793333Y524167D02*
Y526667D01*
X1792292D01*
X1791958Y526542D01*
X1791750Y526375D01*
X1791667Y526042D01*
X1791750Y525709D01*
X1792000Y525500D01*
X1792292Y525375D01*
X1793333D01*
G01X1792292D02*
X1791667Y524167D01*
G01X1789400D02*
Y526667D01*
X1789900Y526167D01*
G01Y524167D02*
X1788900D01*
G01X1787383D02*
Y526667D01*
X1786300Y524584D01*
X1785217Y526667D01*
Y524167D01*
G01X1783200D02*
Y526667D01*
X1783700Y526167D01*
G01Y524167D02*
X1782700D01*
G01X1780808Y524459D02*
X1780517Y524250D01*
X1780183Y524167D01*
X1779850Y524250D01*
X1779558Y524500D01*
X1779350Y524875D01*
X1779267Y525250D01*
Y525709D01*
X1779350Y526084D01*
X1779558Y526417D01*
X1779808Y526584D01*
X1780100Y526667D01*
X1780433Y526584D01*
X1780683Y526417D01*
X1780850Y526167D01*
X1780933Y525834D01*
X1780850Y525542D01*
X1780642Y525250D01*
X1780392Y525084D01*
X1780100Y525042D01*
X1779767Y525125D01*
X1779517Y525334D01*
X1779267Y525709D01*
G01X1810683Y517267D02*
Y519767D01*
X1809642D01*
X1809308Y519642D01*
X1809100Y519475D01*
X1809017Y519142D01*
X1809100Y518809D01*
X1809350Y518600D01*
X1809642Y518475D01*
X1810683D01*
G01X1809642D02*
X1809017Y517267D01*
G01X1806750D02*
Y519767D01*
X1807250Y519267D01*
G01Y517267D02*
X1806250D01*
G01X1804733D02*
Y519767D01*
X1803650Y517684D01*
X1802567Y519767D01*
Y517267D01*
G01X1800050D02*
Y519767D01*
X1801592Y517975D01*
X1799508D01*
G01X1824705Y519007D02*
Y521507D01*
X1823664D01*
X1823330Y521382D01*
X1823122Y521215D01*
X1823039Y520882D01*
X1823122Y520549D01*
X1823372Y520340D01*
X1823664Y520215D01*
X1824705D01*
G01X1823664D02*
X1823039Y519007D01*
G01X1820772D02*
Y521507D01*
X1821272Y521007D01*
G01Y519007D02*
X1820272D01*
G01X1818755D02*
Y521507D01*
X1817672Y519424D01*
X1816589Y521507D01*
Y519007D01*
G01X1815489Y519507D02*
X1815239Y519215D01*
X1814905Y519049D01*
X1814530Y519007D01*
X1814197Y519049D01*
X1813864Y519257D01*
X1813655Y519507D01*
X1813614Y519757D01*
X1813697Y520049D01*
X1813989Y520257D01*
X1814280Y520340D01*
X1814655D01*
G01X1814280D02*
X1814030Y520465D01*
X1813822Y520674D01*
X1813739Y520924D01*
X1813822Y521174D01*
X1814030Y521382D01*
X1814405Y521507D01*
X1814780Y521465D01*
X1815155Y521299D01*
G01X1794754Y506564D02*
X1792962D01*
X1792587Y506731D01*
X1792337Y507064D01*
X1792254Y507481D01*
X1792337Y507898D01*
X1792587Y508231D01*
X1792962Y508398D01*
X1794754D01*
G01X1792254Y510581D02*
X1794754D01*
X1794254Y510081D01*
G01X1792254D02*
Y511081D01*
G01Y512598D02*
X1794754D01*
X1792671Y513681D01*
X1794754Y514764D01*
X1792254D01*
G01X1792629Y515864D02*
X1792421Y516114D01*
X1792296Y516406D01*
X1792254Y516781D01*
X1792337Y517156D01*
X1792504Y517448D01*
X1792796Y517656D01*
X1793129Y517698D01*
X1793462Y517614D01*
X1793671Y517406D01*
X1793837Y517114D01*
X1793879Y516823D01*
X1793837Y516531D01*
X1793671Y516156D01*
X1794754Y516281D01*
Y517406D01*
G01X1806367Y495967D02*
Y494175D01*
X1806200Y493800D01*
X1805867Y493550D01*
X1805450Y493467D01*
X1805033Y493550D01*
X1804700Y493800D01*
X1804533Y494175D01*
Y495967D01*
G01X1802350Y493467D02*
Y495967D01*
X1802850Y495467D01*
G01Y493467D02*
X1801850D01*
G01X1800333D02*
Y495967D01*
X1799250Y493884D01*
X1798167Y495967D01*
Y493467D01*
G01X1795650D02*
Y495967D01*
X1797192Y494175D01*
X1795108D01*
G01X1822383Y487159D02*
X1822633Y487284D01*
X1822925Y487367D01*
X1823258D01*
X1823633Y487242D01*
X1823925Y487034D01*
X1824133Y486784D01*
X1824300Y486367D01*
X1824342Y485992D01*
X1824258Y485617D01*
X1824133Y485367D01*
X1823883Y485117D01*
X1823592Y484950D01*
X1823300Y484867D01*
X1823008D01*
X1822717Y484950D01*
X1822467Y485075D01*
X1822258Y485242D01*
G01X1820200Y484867D02*
Y487367D01*
X1820700Y486867D01*
G01Y484867D02*
X1819700D01*
G01X1818183D02*
Y487367D01*
X1817100Y485284D01*
X1816017Y487367D01*
Y484867D01*
G01X1814917Y485367D02*
X1814667Y485075D01*
X1814333Y484909D01*
X1813958Y484867D01*
X1813625Y484909D01*
X1813292Y485117D01*
X1813083Y485367D01*
X1813042Y485617D01*
X1813125Y485909D01*
X1813417Y486117D01*
X1813708Y486200D01*
X1814083D01*
G01X1813708D02*
X1813458Y486325D01*
X1813250Y486534D01*
X1813167Y486784D01*
X1813250Y487034D01*
X1813458Y487242D01*
X1813833Y487367D01*
X1814208Y487325D01*
X1814583Y487159D01*
G01X1810900Y484867D02*
X1810608Y484909D01*
X1810275Y485034D01*
X1810067Y485242D01*
X1809983Y485534D01*
X1810067Y485825D01*
X1810317Y486075D01*
X1810692Y486200D01*
X1811108D01*
X1811358Y486284D01*
X1811567Y486492D01*
X1811650Y486784D01*
X1811525Y487075D01*
X1811233Y487284D01*
X1810900Y487367D01*
X1810567Y487284D01*
X1810275Y487075D01*
X1810150Y486784D01*
X1810233Y486492D01*
X1810442Y486284D01*
X1810692Y486200D01*
X1811108D01*
X1811483Y486075D01*
X1811733Y485825D01*
X1811817Y485534D01*
X1811733Y485242D01*
X1811525Y485034D01*
X1811192Y484909D01*
X1810900Y484867D01*
G01X1805059Y475617D02*
X1805184Y475367D01*
X1805267Y475075D01*
Y474742D01*
X1805142Y474367D01*
X1804934Y474075D01*
X1804684Y473867D01*
X1804267Y473700D01*
X1803892Y473658D01*
X1803517Y473742D01*
X1803267Y473867D01*
X1803017Y474117D01*
X1802850Y474408D01*
X1802767Y474700D01*
Y474992D01*
X1802850Y475283D01*
X1802975Y475533D01*
X1803142Y475742D01*
G01X1802767Y477800D02*
X1805267D01*
X1804767Y477300D01*
G01X1802767D02*
Y478300D01*
G01Y479817D02*
X1805267D01*
X1803184Y480900D01*
X1805267Y481983D01*
X1802767D01*
G01X1803267Y483083D02*
X1802975Y483333D01*
X1802809Y483667D01*
X1802767Y484042D01*
X1802809Y484375D01*
X1803017Y484708D01*
X1803267Y484917D01*
X1803517Y484958D01*
X1803809Y484875D01*
X1804017Y484583D01*
X1804100Y484292D01*
Y483917D01*
G01Y484292D02*
X1804225Y484542D01*
X1804434Y484750D01*
X1804684Y484833D01*
X1804934Y484750D01*
X1805142Y484542D01*
X1805267Y484167D01*
X1805225Y483792D01*
X1805059Y483417D01*
G01X1803809Y486308D02*
X1804100Y486600D01*
X1804267Y486850D01*
X1804350Y487183D01*
X1804267Y487475D01*
X1804100Y487683D01*
X1803850Y487850D01*
X1803559Y487892D01*
X1803309Y487850D01*
X1803059Y487683D01*
X1802850Y487433D01*
X1802767Y487142D01*
X1802850Y486808D01*
X1803100Y486517D01*
X1803475Y486350D01*
X1803892Y486308D01*
X1804434Y486392D01*
X1804725Y486517D01*
X1805017Y486725D01*
X1805225Y487017D01*
X1805267Y487308D01*
X1805184Y487600D01*
X1804975Y487808D01*
G01X1799359Y475017D02*
X1799484Y474767D01*
X1799567Y474475D01*
Y474142D01*
X1799442Y473767D01*
X1799234Y473475D01*
X1798984Y473267D01*
X1798567Y473100D01*
X1798192Y473058D01*
X1797817Y473142D01*
X1797567Y473267D01*
X1797317Y473517D01*
X1797150Y473808D01*
X1797067Y474100D01*
Y474392D01*
X1797150Y474683D01*
X1797275Y474933D01*
X1797442Y475142D01*
G01X1797067Y477200D02*
X1799567D01*
X1799067Y476700D01*
G01X1797067D02*
Y477700D01*
G01Y479217D02*
X1799567D01*
X1797484Y480300D01*
X1799567Y481383D01*
X1797067D01*
G01X1797567Y482483D02*
X1797275Y482733D01*
X1797109Y483067D01*
X1797067Y483442D01*
X1797109Y483775D01*
X1797317Y484108D01*
X1797567Y484317D01*
X1797817Y484358D01*
X1798109Y484275D01*
X1798317Y483983D01*
X1798400Y483692D01*
Y483317D01*
G01Y483692D02*
X1798525Y483942D01*
X1798734Y484150D01*
X1798984Y484233D01*
X1799234Y484150D01*
X1799442Y483942D01*
X1799567Y483567D01*
X1799525Y483192D01*
X1799359Y482817D01*
G01X1797067Y486417D02*
X1797609Y486500D01*
X1798067Y486625D01*
X1798484Y486792D01*
X1798942Y487000D01*
X1799567Y487333D01*
Y485667D01*
G01X1779159Y493517D02*
X1779284Y493267D01*
X1779367Y492975D01*
Y492642D01*
X1779242Y492267D01*
X1779034Y491975D01*
X1778784Y491767D01*
X1778367Y491600D01*
X1777992Y491558D01*
X1777617Y491642D01*
X1777367Y491767D01*
X1777117Y492017D01*
X1776950Y492308D01*
X1776867Y492600D01*
Y492892D01*
X1776950Y493183D01*
X1777075Y493433D01*
X1777242Y493642D01*
G01X1776867Y495700D02*
X1779367D01*
X1778867Y495200D01*
G01X1776867D02*
Y496200D01*
G01Y497717D02*
X1779367D01*
X1777284Y498800D01*
X1779367Y499883D01*
X1776867D01*
G01X1777367Y500983D02*
X1777075Y501233D01*
X1776909Y501567D01*
X1776867Y501942D01*
X1776909Y502275D01*
X1777117Y502608D01*
X1777367Y502817D01*
X1777617Y502858D01*
X1777909Y502775D01*
X1778117Y502483D01*
X1778200Y502192D01*
Y501817D01*
G01Y502192D02*
X1778325Y502442D01*
X1778534Y502650D01*
X1778784Y502733D01*
X1779034Y502650D01*
X1779242Y502442D01*
X1779367Y502067D01*
X1779325Y501692D01*
X1779159Y501317D01*
G01X1777367Y504083D02*
X1777075Y504333D01*
X1776909Y504667D01*
X1776867Y505042D01*
X1776909Y505375D01*
X1777117Y505708D01*
X1777367Y505917D01*
X1777617Y505958D01*
X1777909Y505875D01*
X1778117Y505583D01*
X1778200Y505292D01*
Y504917D01*
G01Y505292D02*
X1778325Y505542D01*
X1778534Y505750D01*
X1778784Y505833D01*
X1779034Y505750D01*
X1779242Y505542D01*
X1779367Y505167D01*
X1779325Y504792D01*
X1779159Y504417D01*
G01X1794680Y500961D02*
X1794930Y501086D01*
X1795222Y501169D01*
X1795555D01*
X1795930Y501044D01*
X1796222Y500836D01*
X1796430Y500586D01*
X1796597Y500169D01*
X1796639Y499794D01*
X1796555Y499419D01*
X1796430Y499169D01*
X1796180Y498919D01*
X1795889Y498752D01*
X1795597Y498669D01*
X1795305D01*
X1795014Y498752D01*
X1794764Y498877D01*
X1794555Y499044D01*
G01X1792497Y498669D02*
Y501169D01*
X1792997Y500669D01*
G01Y498669D02*
X1791997D01*
G01X1790480D02*
Y501169D01*
X1789397Y499086D01*
X1788314Y501169D01*
Y498669D01*
G01X1787214Y499169D02*
X1786964Y498877D01*
X1786630Y498711D01*
X1786255Y498669D01*
X1785922Y498711D01*
X1785589Y498919D01*
X1785380Y499169D01*
X1785339Y499419D01*
X1785422Y499711D01*
X1785714Y499919D01*
X1786005Y500002D01*
X1786380D01*
G01X1786005D02*
X1785755Y500127D01*
X1785547Y500336D01*
X1785464Y500586D01*
X1785547Y500836D01*
X1785755Y501044D01*
X1786130Y501169D01*
X1786505Y501127D01*
X1786880Y500961D01*
G01X1783197Y501169D02*
X1783530Y501086D01*
X1783780Y500877D01*
X1783947Y500627D01*
X1784072Y500294D01*
X1784114Y499919D01*
X1784072Y499544D01*
X1783947Y499211D01*
X1783780Y498961D01*
X1783530Y498752D01*
X1783197Y498669D01*
X1782864Y498752D01*
X1782614Y498961D01*
X1782447Y499211D01*
X1782322Y499544D01*
X1782280Y499919D01*
X1782322Y500294D01*
X1782447Y500627D01*
X1782614Y500877D01*
X1782864Y501086D01*
X1783197Y501169D01*
G01X1839067Y523600D02*
Y521808D01*
X1838900Y521433D01*
X1838567Y521183D01*
X1838150Y521100D01*
X1837733Y521183D01*
X1837400Y521433D01*
X1837233Y521808D01*
Y523600D01*
G01X1835050Y521100D02*
Y523600D01*
X1835550Y523100D01*
G01Y521100D02*
X1834550D01*
G01X1833033D02*
Y523600D01*
X1831950Y521517D01*
X1830867Y523600D01*
Y521100D01*
G01X1829767Y521600D02*
X1829517Y521308D01*
X1829183Y521142D01*
X1828808Y521100D01*
X1828475Y521142D01*
X1828142Y521350D01*
X1827933Y521600D01*
X1827892Y521850D01*
X1827975Y522142D01*
X1828267Y522350D01*
X1828558Y522433D01*
X1828933D01*
G01X1828558D02*
X1828308Y522558D01*
X1828100Y522767D01*
X1828017Y523017D01*
X1828100Y523267D01*
X1828308Y523475D01*
X1828683Y523600D01*
X1829058Y523558D01*
X1829433Y523392D01*
G01X1822890Y473710D02*
Y476210D01*
X1821849D01*
X1821515Y476085D01*
X1821307Y475918D01*
X1821224Y475585D01*
X1821307Y475252D01*
X1821557Y475043D01*
X1821849Y474918D01*
X1822890D01*
G01X1821849D02*
X1821224Y473710D01*
G01X1818957D02*
Y476210D01*
X1819457Y475710D01*
G01Y473710D02*
X1818457D01*
G01X1817107Y476210D02*
X1816524Y473710D01*
X1815857Y476210D01*
X1815190Y473710D01*
X1814607Y476210D01*
G01X1812757Y473710D02*
Y476210D01*
X1813257Y475710D01*
G01Y473710D02*
X1812257D01*
G01X1809657D02*
Y476210D01*
X1810157Y475710D01*
G01Y473710D02*
X1809157D01*
G01X1822790Y470310D02*
Y472810D01*
X1821749D01*
X1821415Y472685D01*
X1821207Y472518D01*
X1821124Y472185D01*
X1821207Y471852D01*
X1821457Y471643D01*
X1821749Y471518D01*
X1822790D01*
G01X1821749D02*
X1821124Y470310D01*
G01X1818857D02*
Y472810D01*
X1819357Y472310D01*
G01Y470310D02*
X1818357D01*
G01X1817007Y472810D02*
X1816424Y470310D01*
X1815757Y472810D01*
X1815090Y470310D01*
X1814507Y472810D01*
G01X1812657Y470310D02*
Y472810D01*
X1813157Y472310D01*
G01Y470310D02*
X1812157D01*
G01X1809557Y472810D02*
X1809890Y472727D01*
X1810140Y472518D01*
X1810307Y472268D01*
X1810432Y471935D01*
X1810474Y471560D01*
X1810432Y471185D01*
X1810307Y470852D01*
X1810140Y470602D01*
X1809890Y470393D01*
X1809557Y470310D01*
X1809224Y470393D01*
X1808974Y470602D01*
X1808807Y470852D01*
X1808682Y471185D01*
X1808640Y471560D01*
X1808682Y471935D01*
X1808807Y472268D01*
X1808974Y472518D01*
X1809224Y472727D01*
X1809557Y472810D01*
G01X1792167Y495300D02*
Y493508D01*
X1792000Y493133D01*
X1791667Y492883D01*
X1791250Y492800D01*
X1790833Y492883D01*
X1790500Y493133D01*
X1790333Y493508D01*
Y495300D01*
G01X1788150Y492800D02*
Y495300D01*
X1788650Y494800D01*
G01Y492800D02*
X1787650D01*
G01X1786133D02*
Y495300D01*
X1785050Y493217D01*
X1783967Y495300D01*
Y492800D01*
G01X1782033D02*
X1781950Y493342D01*
X1781825Y493800D01*
X1781658Y494217D01*
X1781450Y494675D01*
X1781117Y495300D01*
X1782783D01*
G01X1781600Y565900D02*
Y573800D01*
G01Y562100D02*
Y564100D01*
G01X1775700Y554300D02*
X1781600D01*
Y560300D01*
G01X1777500Y575500D02*
X1776000D01*
Y576500D01*
G01Y580500D02*
Y582000D01*
G01Y586000D02*
Y587000D01*
G01X1844383Y536383D02*
Y538883D01*
X1843342D01*
X1843008Y538758D01*
X1842800Y538591D01*
X1842717Y538258D01*
X1842800Y537925D01*
X1843050Y537716D01*
X1843342Y537591D01*
X1844383D01*
G01X1843342D02*
X1842717Y536383D01*
G01X1840450D02*
Y538883D01*
X1840950Y538383D01*
G01Y536383D02*
X1839950D01*
G01X1838183Y538883D02*
Y536383D01*
X1836517D01*
G01X1833750D02*
Y538883D01*
X1835292Y537091D01*
X1833208D01*
G01X1831150Y536383D02*
Y538883D01*
X1831650Y538383D01*
G01Y536383D02*
X1830650D01*
G01X1846233Y546967D02*
Y549467D01*
X1845192D01*
X1844858Y549342D01*
X1844650Y549175D01*
X1844567Y548842D01*
X1844650Y548509D01*
X1844900Y548300D01*
X1845192Y548175D01*
X1846233D01*
G01X1845192D02*
X1844567Y546967D01*
G01X1842300D02*
Y549467D01*
X1842800Y548967D01*
G01Y546967D02*
X1841800D01*
G01X1840033Y549467D02*
Y546967D01*
X1838367D01*
G01X1837017Y547467D02*
X1836767Y547175D01*
X1836433Y547009D01*
X1836058Y546967D01*
X1835725Y547009D01*
X1835392Y547217D01*
X1835183Y547467D01*
X1835142Y547717D01*
X1835225Y548009D01*
X1835517Y548217D01*
X1835808Y548300D01*
X1836183D01*
G01X1835808D02*
X1835558Y548425D01*
X1835350Y548634D01*
X1835267Y548884D01*
X1835350Y549134D01*
X1835558Y549342D01*
X1835933Y549467D01*
X1836308Y549425D01*
X1836683Y549259D01*
G01X1833708Y547259D02*
X1833417Y547050D01*
X1833083Y546967D01*
X1832750Y547050D01*
X1832458Y547300D01*
X1832250Y547675D01*
X1832167Y548050D01*
Y548509D01*
X1832250Y548884D01*
X1832458Y549217D01*
X1832708Y549384D01*
X1833000Y549467D01*
X1833333Y549384D01*
X1833583Y549217D01*
X1833750Y548967D01*
X1833833Y548634D01*
X1833750Y548342D01*
X1833542Y548050D01*
X1833292Y547884D01*
X1833000Y547842D01*
X1832667Y547925D01*
X1832417Y548134D01*
X1832167Y548509D01*
G01X1820767Y552067D02*
X1823267D01*
Y553108D01*
X1823142Y553442D01*
X1822975Y553650D01*
X1822642Y553733D01*
X1822309Y553650D01*
X1822100Y553400D01*
X1821975Y553108D01*
Y552067D01*
G01Y553108D02*
X1820767Y553733D01*
G01Y556000D02*
X1823267D01*
X1822767Y555500D01*
G01X1820767D02*
Y556500D01*
G01X1823267Y558267D02*
X1820767D01*
Y559933D01*
G01X1822850Y561408D02*
X1823100Y561658D01*
X1823225Y561950D01*
X1823267Y562283D01*
X1823184Y562700D01*
X1822975Y562992D01*
X1822725Y563075D01*
X1822475Y563033D01*
X1822267Y562867D01*
X1821850Y562033D01*
X1821559Y561658D01*
X1821142Y561408D01*
X1820767Y561325D01*
Y563075D01*
G01X1821267Y564383D02*
X1820975Y564633D01*
X1820809Y564967D01*
X1820767Y565342D01*
X1820809Y565675D01*
X1821017Y566008D01*
X1821267Y566217D01*
X1821517Y566258D01*
X1821809Y566175D01*
X1822017Y565883D01*
X1822100Y565592D01*
Y565217D01*
G01Y565592D02*
X1822225Y565842D01*
X1822434Y566050D01*
X1822684Y566133D01*
X1822934Y566050D01*
X1823142Y565842D01*
X1823267Y565467D01*
X1823225Y565092D01*
X1823059Y564717D01*
G01X1801800Y542867D02*
X1804300D01*
Y543908D01*
X1804175Y544242D01*
X1804008Y544450D01*
X1803675Y544533D01*
X1803342Y544450D01*
X1803133Y544200D01*
X1803008Y543908D01*
Y542867D01*
G01Y543908D02*
X1801800Y544533D01*
G01Y546800D02*
X1804300D01*
X1803800Y546300D01*
G01X1801800D02*
Y547300D01*
G01X1804300Y549067D02*
X1801800D01*
Y550733D01*
G01X1803883Y552208D02*
X1804133Y552458D01*
X1804258Y552750D01*
X1804300Y553083D01*
X1804217Y553500D01*
X1804008Y553792D01*
X1803758Y553875D01*
X1803508Y553833D01*
X1803300Y553667D01*
X1802883Y552833D01*
X1802592Y552458D01*
X1802175Y552208D01*
X1801800Y552125D01*
Y553875D01*
G01Y556100D02*
X1801842Y556392D01*
X1801967Y556725D01*
X1802175Y556933D01*
X1802467Y557017D01*
X1802758Y556933D01*
X1803008Y556683D01*
X1803133Y556308D01*
Y555892D01*
X1803217Y555642D01*
X1803425Y555433D01*
X1803717Y555350D01*
X1804008Y555475D01*
X1804217Y555767D01*
X1804300Y556100D01*
X1804217Y556433D01*
X1804008Y556725D01*
X1803717Y556850D01*
X1803425Y556767D01*
X1803217Y556558D01*
X1803133Y556308D01*
Y555892D01*
X1803008Y555517D01*
X1802758Y555267D01*
X1802467Y555183D01*
X1802175Y555267D01*
X1801967Y555475D01*
X1801842Y555808D01*
X1801800Y556100D01*
G01X1798400Y542967D02*
X1800900D01*
Y544008D01*
X1800775Y544342D01*
X1800608Y544550D01*
X1800275Y544633D01*
X1799942Y544550D01*
X1799733Y544300D01*
X1799608Y544008D01*
Y542967D01*
G01Y544008D02*
X1798400Y544633D01*
G01Y546900D02*
X1800900D01*
X1800400Y546400D01*
G01X1798400D02*
Y547400D01*
G01X1800900Y549167D02*
X1798400D01*
Y550833D01*
G01X1800483Y552308D02*
X1800733Y552558D01*
X1800858Y552850D01*
X1800900Y553183D01*
X1800817Y553600D01*
X1800608Y553892D01*
X1800358Y553975D01*
X1800108Y553933D01*
X1799900Y553767D01*
X1799483Y552933D01*
X1799192Y552558D01*
X1798775Y552308D01*
X1798400Y552225D01*
Y553975D01*
G01X1798692Y555492D02*
X1798483Y555783D01*
X1798400Y556117D01*
X1798483Y556450D01*
X1798733Y556742D01*
X1799108Y556950D01*
X1799483Y557033D01*
X1799942D01*
X1800317Y556950D01*
X1800650Y556742D01*
X1800817Y556492D01*
X1800900Y556200D01*
X1800817Y555867D01*
X1800650Y555617D01*
X1800400Y555450D01*
X1800067Y555367D01*
X1799775Y555450D01*
X1799483Y555658D01*
X1799317Y555908D01*
X1799275Y556200D01*
X1799358Y556533D01*
X1799567Y556783D01*
X1799942Y557033D01*
G01X1824100Y577717D02*
X1826600D01*
Y578758D01*
X1826475Y579092D01*
X1826308Y579300D01*
X1825975Y579383D01*
X1825642Y579300D01*
X1825433Y579050D01*
X1825308Y578758D01*
Y577717D01*
G01Y578758D02*
X1824100Y579383D01*
G01Y581650D02*
X1826600D01*
X1826100Y581150D01*
G01X1824100D02*
Y582150D01*
G01X1826600Y583917D02*
X1824100D01*
Y585583D01*
G01Y587850D02*
X1826600D01*
X1826100Y587350D01*
G01X1824100D02*
Y588350D01*
G01X1824475Y590033D02*
X1824267Y590283D01*
X1824142Y590575D01*
X1824100Y590950D01*
X1824183Y591325D01*
X1824350Y591617D01*
X1824642Y591825D01*
X1824975Y591867D01*
X1825308Y591783D01*
X1825517Y591575D01*
X1825683Y591283D01*
X1825725Y590992D01*
X1825683Y590700D01*
X1825517Y590325D01*
X1826600Y590450D01*
Y591575D01*
G01X1844533Y530500D02*
Y533000D01*
X1843492D01*
X1843158Y532875D01*
X1842950Y532708D01*
X1842867Y532375D01*
X1842950Y532042D01*
X1843200Y531833D01*
X1843492Y531708D01*
X1844533D01*
G01X1843492D02*
X1842867Y530500D01*
G01X1841392Y531542D02*
X1841100Y531833D01*
X1840850Y532000D01*
X1840517Y532083D01*
X1840225Y532000D01*
X1840017Y531833D01*
X1839850Y531583D01*
X1839808Y531292D01*
X1839850Y531042D01*
X1840017Y530792D01*
X1840267Y530583D01*
X1840558Y530500D01*
X1840892Y530583D01*
X1841183Y530833D01*
X1841350Y531208D01*
X1841392Y531625D01*
X1841308Y532167D01*
X1841183Y532458D01*
X1840975Y532750D01*
X1840683Y532958D01*
X1840392Y533000D01*
X1840100Y532917D01*
X1839892Y532708D01*
G01X1838750Y533000D02*
X1838167Y530500D01*
X1837500Y533000D01*
X1836833Y530500D01*
X1836250Y533000D01*
G01X1835317Y531000D02*
X1835067Y530708D01*
X1834733Y530542D01*
X1834358Y530500D01*
X1834025Y530542D01*
X1833692Y530750D01*
X1833483Y531000D01*
X1833442Y531250D01*
X1833525Y531542D01*
X1833817Y531750D01*
X1834108Y531833D01*
X1834483D01*
G01X1834108D02*
X1833858Y531958D01*
X1833650Y532167D01*
X1833567Y532417D01*
X1833650Y532667D01*
X1833858Y532875D01*
X1834233Y533000D01*
X1834608Y532958D01*
X1834983Y532792D01*
G01X1832217Y530875D02*
X1831967Y530667D01*
X1831675Y530542D01*
X1831300Y530500D01*
X1830925Y530583D01*
X1830633Y530750D01*
X1830425Y531042D01*
X1830383Y531375D01*
X1830467Y531708D01*
X1830675Y531917D01*
X1830967Y532083D01*
X1831258Y532125D01*
X1831550Y532083D01*
X1831925Y531917D01*
X1831800Y533000D01*
X1830675D01*
G01X1798809Y570288D02*
Y572788D01*
X1797768D01*
X1797434Y572663D01*
X1797226Y572496D01*
X1797143Y572163D01*
X1797226Y571830D01*
X1797476Y571621D01*
X1797768Y571496D01*
X1798809D01*
G01X1797768D02*
X1797143Y570288D01*
G01X1795584Y570580D02*
X1795293Y570371D01*
X1794959Y570288D01*
X1794626Y570371D01*
X1794334Y570621D01*
X1794126Y570996D01*
X1794043Y571371D01*
Y571830D01*
X1794126Y572205D01*
X1794334Y572538D01*
X1794584Y572705D01*
X1794876Y572788D01*
X1795209Y572705D01*
X1795459Y572538D01*
X1795626Y572288D01*
X1795709Y571955D01*
X1795626Y571663D01*
X1795418Y571371D01*
X1795168Y571205D01*
X1794876Y571163D01*
X1794543Y571246D01*
X1794293Y571455D01*
X1794043Y571830D01*
G01X1792818Y570288D02*
X1791776Y572788D01*
X1790734Y570288D01*
G01X1791109Y571163D02*
X1792443D01*
G01X1788676Y570288D02*
Y572788D01*
X1789176Y572288D01*
G01Y570288D02*
X1788176D01*
G01X1785659D02*
X1785576Y570830D01*
X1785451Y571288D01*
X1785284Y571705D01*
X1785076Y572163D01*
X1784743Y572788D01*
X1786409D01*
G01X1809233Y578000D02*
Y580500D01*
X1808192D01*
X1807858Y580375D01*
X1807650Y580208D01*
X1807567Y579875D01*
X1807650Y579542D01*
X1807900Y579333D01*
X1808192Y579208D01*
X1809233D01*
G01X1808192D02*
X1807567Y578000D01*
G01X1806008Y578292D02*
X1805717Y578083D01*
X1805383Y578000D01*
X1805050Y578083D01*
X1804758Y578333D01*
X1804550Y578708D01*
X1804467Y579083D01*
Y579542D01*
X1804550Y579917D01*
X1804758Y580250D01*
X1805008Y580417D01*
X1805300Y580500D01*
X1805633Y580417D01*
X1805883Y580250D01*
X1806050Y580000D01*
X1806133Y579667D01*
X1806050Y579375D01*
X1805842Y579083D01*
X1805592Y578917D01*
X1805300Y578875D01*
X1804967Y578958D01*
X1804717Y579167D01*
X1804467Y579542D01*
G01X1803242Y578000D02*
X1802200Y580500D01*
X1801158Y578000D01*
G01X1801533Y578875D02*
X1802867D01*
G01X1799100Y578000D02*
Y580500D01*
X1799600Y580000D01*
G01Y578000D02*
X1798600D01*
G01X1795500D02*
Y580500D01*
X1797042Y578708D01*
X1794958D01*
G01X1803733Y584900D02*
Y587400D01*
X1802692D01*
X1802358Y587275D01*
X1802150Y587108D01*
X1802067Y586775D01*
X1802150Y586442D01*
X1802400Y586233D01*
X1802692Y586108D01*
X1803733D01*
G01X1802692D02*
X1802067Y584900D01*
G01X1800508Y585192D02*
X1800217Y584983D01*
X1799883Y584900D01*
X1799550Y584983D01*
X1799258Y585233D01*
X1799050Y585608D01*
X1798967Y585983D01*
Y586442D01*
X1799050Y586817D01*
X1799258Y587150D01*
X1799508Y587317D01*
X1799800Y587400D01*
X1800133Y587317D01*
X1800383Y587150D01*
X1800550Y586900D01*
X1800633Y586567D01*
X1800550Y586275D01*
X1800342Y585983D01*
X1800092Y585817D01*
X1799800Y585775D01*
X1799467Y585858D01*
X1799217Y586067D01*
X1798967Y586442D01*
G01X1797742Y584900D02*
X1796700Y587400D01*
X1795658Y584900D01*
G01X1796033Y585775D02*
X1797367D01*
G01X1793600Y584900D02*
Y587400D01*
X1794100Y586900D01*
G01Y584900D02*
X1793100D01*
G01X1790500D02*
Y587400D01*
X1791000Y586900D01*
G01Y584900D02*
X1790000D01*
G01X1819067Y555100D02*
Y553308D01*
X1818900Y552933D01*
X1818567Y552683D01*
X1818150Y552600D01*
X1817733Y552683D01*
X1817400Y552933D01*
X1817233Y553308D01*
Y555100D01*
G01X1815050Y552600D02*
Y555100D01*
X1815550Y554600D01*
G01Y552600D02*
X1814550D01*
G01X1812783Y555100D02*
Y552600D01*
X1811117D01*
G01X1808350D02*
Y555100D01*
X1809892Y553308D01*
X1807808D01*
G01X1842233Y542892D02*
X1842483Y543017D01*
X1842775Y543100D01*
X1843108D01*
X1843483Y542975D01*
X1843775Y542767D01*
X1843983Y542517D01*
X1844150Y542100D01*
X1844192Y541725D01*
X1844108Y541350D01*
X1843983Y541100D01*
X1843733Y540850D01*
X1843442Y540683D01*
X1843150Y540600D01*
X1842858D01*
X1842567Y540683D01*
X1842317Y540808D01*
X1842108Y540975D01*
G01X1840050Y540600D02*
Y543100D01*
X1840550Y542600D01*
G01Y540600D02*
X1839550D01*
G01X1837783Y543100D02*
Y540600D01*
X1836117D01*
G01X1833850D02*
Y543100D01*
X1834350Y542600D01*
G01Y540600D02*
X1833350D01*
G01X1830750D02*
X1830458Y540642D01*
X1830125Y540767D01*
X1829917Y540975D01*
X1829833Y541267D01*
X1829917Y541558D01*
X1830167Y541808D01*
X1830542Y541933D01*
X1830958D01*
X1831208Y542017D01*
X1831417Y542225D01*
X1831500Y542517D01*
X1831375Y542808D01*
X1831083Y543017D01*
X1830750Y543100D01*
X1830417Y543017D01*
X1830125Y542808D01*
X1830000Y542517D01*
X1830083Y542225D01*
X1830292Y542017D01*
X1830542Y541933D01*
X1830958D01*
X1831333Y541808D01*
X1831583Y541558D01*
X1831667Y541267D01*
X1831583Y540975D01*
X1831375Y540767D01*
X1831042Y540642D01*
X1830750Y540600D01*
G01X1840956Y561344D02*
X1841206Y561469D01*
X1841498Y561552D01*
X1841831D01*
X1842206Y561427D01*
X1842498Y561219D01*
X1842706Y560969D01*
X1842873Y560552D01*
X1842915Y560177D01*
X1842831Y559802D01*
X1842706Y559552D01*
X1842456Y559302D01*
X1842165Y559135D01*
X1841873Y559052D01*
X1841581D01*
X1841290Y559135D01*
X1841040Y559260D01*
X1840831Y559427D01*
G01X1838773Y559052D02*
Y561552D01*
X1839273Y561052D01*
G01Y559052D02*
X1838273D01*
G01X1836506Y561552D02*
Y559052D01*
X1834840D01*
G01X1833365Y561135D02*
X1833115Y561385D01*
X1832823Y561510D01*
X1832490Y561552D01*
X1832073Y561469D01*
X1831781Y561260D01*
X1831698Y561010D01*
X1831740Y560760D01*
X1831906Y560552D01*
X1832740Y560135D01*
X1833115Y559844D01*
X1833365Y559427D01*
X1833448Y559052D01*
X1831698D01*
G01X1829473Y561552D02*
X1829806Y561469D01*
X1830056Y561260D01*
X1830223Y561010D01*
X1830348Y560677D01*
X1830390Y560302D01*
X1830348Y559927D01*
X1830223Y559594D01*
X1830056Y559344D01*
X1829806Y559135D01*
X1829473Y559052D01*
X1829140Y559135D01*
X1828890Y559344D01*
X1828723Y559594D01*
X1828598Y559927D01*
X1828556Y560302D01*
X1828598Y560677D01*
X1828723Y561010D01*
X1828890Y561260D01*
X1829140Y561469D01*
X1829473Y561552D01*
G01X1827059Y556267D02*
X1827184Y556017D01*
X1827267Y555725D01*
Y555392D01*
X1827142Y555017D01*
X1826934Y554725D01*
X1826684Y554517D01*
X1826267Y554350D01*
X1825892Y554308D01*
X1825517Y554392D01*
X1825267Y554517D01*
X1825017Y554767D01*
X1824850Y555058D01*
X1824767Y555350D01*
Y555642D01*
X1824850Y555933D01*
X1824975Y556183D01*
X1825142Y556392D01*
G01X1824767Y558450D02*
X1827267D01*
X1826767Y557950D01*
G01X1824767D02*
Y558950D01*
G01X1827267Y560717D02*
X1824767D01*
Y562383D01*
G01Y564650D02*
X1824809Y564942D01*
X1824934Y565275D01*
X1825142Y565483D01*
X1825434Y565567D01*
X1825725Y565483D01*
X1825975Y565233D01*
X1826100Y564858D01*
Y564442D01*
X1826184Y564192D01*
X1826392Y563983D01*
X1826684Y563900D01*
X1826975Y564025D01*
X1827184Y564317D01*
X1827267Y564650D01*
X1827184Y564983D01*
X1826975Y565275D01*
X1826684Y565400D01*
X1826392Y565317D01*
X1826184Y565108D01*
X1826100Y564858D01*
Y564442D01*
X1825975Y564067D01*
X1825725Y563817D01*
X1825434Y563733D01*
X1825142Y563817D01*
X1824934Y564025D01*
X1824809Y564358D01*
X1824767Y564650D01*
G01X1797302Y539504D02*
X1797427Y539254D01*
X1797510Y538962D01*
Y538629D01*
X1797385Y538254D01*
X1797177Y537962D01*
X1796927Y537754D01*
X1796510Y537587D01*
X1796135Y537545D01*
X1795760Y537629D01*
X1795510Y537754D01*
X1795260Y538004D01*
X1795093Y538295D01*
X1795010Y538587D01*
Y538879D01*
X1795093Y539170D01*
X1795218Y539420D01*
X1795385Y539629D01*
G01X1795010Y541687D02*
X1797510D01*
X1797010Y541187D01*
G01X1795010D02*
Y542187D01*
G01X1797510Y543954D02*
X1795010D01*
Y545620D01*
G01Y547887D02*
X1797510D01*
X1797010Y547387D01*
G01X1795010D02*
Y548387D01*
G01X1795302Y550279D02*
X1795093Y550570D01*
X1795010Y550904D01*
X1795093Y551237D01*
X1795343Y551529D01*
X1795718Y551737D01*
X1796093Y551820D01*
X1796552D01*
X1796927Y551737D01*
X1797260Y551529D01*
X1797427Y551279D01*
X1797510Y550987D01*
X1797427Y550654D01*
X1797260Y550404D01*
X1797010Y550237D01*
X1796677Y550154D01*
X1796385Y550237D01*
X1796093Y550445D01*
X1795927Y550695D01*
X1795885Y550987D01*
X1795968Y551320D01*
X1796177Y551570D01*
X1796552Y551820D01*
G01X1807183Y576992D02*
X1807433Y577117D01*
X1807725Y577200D01*
X1808058D01*
X1808433Y577075D01*
X1808725Y576867D01*
X1808933Y576617D01*
X1809100Y576200D01*
X1809142Y575825D01*
X1809058Y575450D01*
X1808933Y575200D01*
X1808683Y574950D01*
X1808392Y574783D01*
X1808100Y574700D01*
X1807808D01*
X1807517Y574783D01*
X1807267Y574908D01*
X1807058Y575075D01*
G01X1805000Y574700D02*
Y577200D01*
X1805500Y576700D01*
G01Y574700D02*
X1804500D01*
G01X1802733Y577200D02*
Y574700D01*
X1801067D01*
G01X1798800D02*
Y577200D01*
X1799300Y576700D01*
G01Y574700D02*
X1798300D01*
G01X1795700D02*
Y577200D01*
X1796200Y576700D01*
G01Y574700D02*
X1795200D01*
G01X1829892Y578867D02*
X1830017Y578617D01*
X1830100Y578325D01*
Y577992D01*
X1829975Y577617D01*
X1829767Y577325D01*
X1829517Y577117D01*
X1829100Y576950D01*
X1828725Y576908D01*
X1828350Y576992D01*
X1828100Y577117D01*
X1827850Y577367D01*
X1827683Y577658D01*
X1827600Y577950D01*
Y578242D01*
X1827683Y578533D01*
X1827808Y578783D01*
X1827975Y578992D01*
G01X1827600Y581050D02*
X1830100D01*
X1829600Y580550D01*
G01X1827600D02*
Y581550D01*
G01X1830100Y583317D02*
X1827600D01*
Y584983D01*
G01X1827975Y586333D02*
X1827767Y586583D01*
X1827642Y586875D01*
X1827600Y587250D01*
X1827683Y587625D01*
X1827850Y587917D01*
X1828142Y588125D01*
X1828475Y588167D01*
X1828808Y588083D01*
X1829017Y587875D01*
X1829183Y587583D01*
X1829225Y587292D01*
X1829183Y587000D01*
X1829017Y586625D01*
X1830100Y586750D01*
Y587875D01*
G01X1801433Y583592D02*
X1801683Y583717D01*
X1801975Y583800D01*
X1802308D01*
X1802683Y583675D01*
X1802975Y583467D01*
X1803183Y583217D01*
X1803350Y582800D01*
X1803392Y582425D01*
X1803308Y582050D01*
X1803183Y581800D01*
X1802933Y581550D01*
X1802642Y581383D01*
X1802350Y581300D01*
X1802058D01*
X1801767Y581383D01*
X1801517Y581508D01*
X1801308Y581675D01*
G01X1799958Y581592D02*
X1799667Y581383D01*
X1799333Y581300D01*
X1799000Y581383D01*
X1798708Y581633D01*
X1798500Y582008D01*
X1798417Y582383D01*
Y582842D01*
X1798500Y583217D01*
X1798708Y583550D01*
X1798958Y583717D01*
X1799250Y583800D01*
X1799583Y583717D01*
X1799833Y583550D01*
X1800000Y583300D01*
X1800083Y582967D01*
X1800000Y582675D01*
X1799792Y582383D01*
X1799542Y582217D01*
X1799250Y582175D01*
X1798917Y582258D01*
X1798667Y582467D01*
X1798417Y582842D01*
G01X1797192Y581300D02*
X1796150Y583800D01*
X1795108Y581300D01*
G01X1795483Y582175D02*
X1796817D01*
G01X1793967Y581675D02*
X1793717Y581467D01*
X1793425Y581342D01*
X1793050Y581300D01*
X1792675Y581383D01*
X1792383Y581550D01*
X1792175Y581842D01*
X1792133Y582175D01*
X1792217Y582508D01*
X1792425Y582717D01*
X1792717Y582883D01*
X1793008Y582925D01*
X1793300Y582883D01*
X1793675Y582717D01*
X1793550Y583800D01*
X1792425D01*
G01X1795692Y556867D02*
X1795817Y556617D01*
X1795900Y556325D01*
Y555992D01*
X1795775Y555617D01*
X1795567Y555325D01*
X1795317Y555117D01*
X1794900Y554950D01*
X1794525Y554908D01*
X1794150Y554992D01*
X1793900Y555117D01*
X1793650Y555367D01*
X1793483Y555658D01*
X1793400Y555950D01*
Y556242D01*
X1793483Y556533D01*
X1793608Y556783D01*
X1793775Y556992D01*
G01X1793692Y558342D02*
X1793483Y558633D01*
X1793400Y558967D01*
X1793483Y559300D01*
X1793733Y559592D01*
X1794108Y559800D01*
X1794483Y559883D01*
X1794942D01*
X1795317Y559800D01*
X1795650Y559592D01*
X1795817Y559342D01*
X1795900Y559050D01*
X1795817Y558717D01*
X1795650Y558467D01*
X1795400Y558300D01*
X1795067Y558217D01*
X1794775Y558300D01*
X1794483Y558508D01*
X1794317Y558758D01*
X1794275Y559050D01*
X1794358Y559383D01*
X1794567Y559633D01*
X1794942Y559883D01*
G01X1793400Y561108D02*
X1795900Y562150D01*
X1793400Y563192D01*
G01X1794275Y562817D02*
Y561483D01*
G01X1794442Y564458D02*
X1794733Y564750D01*
X1794900Y565000D01*
X1794983Y565333D01*
X1794900Y565625D01*
X1794733Y565833D01*
X1794483Y566000D01*
X1794192Y566042D01*
X1793942Y566000D01*
X1793692Y565833D01*
X1793483Y565583D01*
X1793400Y565292D01*
X1793483Y564958D01*
X1793733Y564667D01*
X1794108Y564500D01*
X1794525Y564458D01*
X1795067Y564542D01*
X1795358Y564667D01*
X1795650Y564875D01*
X1795858Y565167D01*
X1795900Y565458D01*
X1795817Y565750D01*
X1795608Y565958D01*
G01X1828567Y545400D02*
Y543608D01*
X1828400Y543233D01*
X1828067Y542983D01*
X1827650Y542900D01*
X1827233Y542983D01*
X1826900Y543233D01*
X1826733Y543608D01*
Y545400D01*
G01X1824550Y542900D02*
Y545400D01*
X1825050Y544900D01*
G01Y542900D02*
X1824050D01*
G01X1822283Y545400D02*
Y542900D01*
X1820617D01*
G01X1819267Y543275D02*
X1819017Y543067D01*
X1818725Y542942D01*
X1818350Y542900D01*
X1817975Y542983D01*
X1817683Y543150D01*
X1817475Y543442D01*
X1817433Y543775D01*
X1817517Y544108D01*
X1817725Y544317D01*
X1818017Y544483D01*
X1818308Y544525D01*
X1818600Y544483D01*
X1818975Y544317D01*
X1818850Y545400D01*
X1817725D01*
G01X1783800Y583050D02*
X1779800D01*
Y590450D01*
G01X1832400Y591167D02*
X1834900D01*
Y592208D01*
X1834775Y592542D01*
X1834608Y592750D01*
X1834275Y592833D01*
X1833942Y592750D01*
X1833733Y592500D01*
X1833608Y592208D01*
Y591167D01*
G01Y592208D02*
X1832400Y592833D01*
G01Y595100D02*
X1834900D01*
X1834400Y594600D01*
G01X1832400D02*
Y595600D01*
G01X1834900Y597367D02*
X1832400D01*
Y599033D01*
G01Y601300D02*
X1834900D01*
X1834400Y600800D01*
G01X1832400D02*
Y601800D01*
G01X1832900Y603483D02*
X1832608Y603733D01*
X1832442Y604067D01*
X1832400Y604442D01*
X1832442Y604775D01*
X1832650Y605108D01*
X1832900Y605317D01*
X1833150Y605358D01*
X1833442Y605275D01*
X1833650Y604983D01*
X1833733Y604692D01*
Y604317D01*
G01Y604692D02*
X1833858Y604942D01*
X1834067Y605150D01*
X1834317Y605233D01*
X1834567Y605150D01*
X1834775Y604942D01*
X1834900Y604567D01*
X1834858Y604192D01*
X1834692Y603817D01*
G01X1788771Y613546D02*
X1791271D01*
Y614587D01*
X1791146Y614921D01*
X1790979Y615129D01*
X1790646Y615212D01*
X1790313Y615129D01*
X1790104Y614879D01*
X1789979Y614587D01*
Y613546D01*
G01Y614587D02*
X1788771Y615212D01*
G01X1789063Y616771D02*
X1788854Y617062D01*
X1788771Y617396D01*
X1788854Y617729D01*
X1789104Y618021D01*
X1789479Y618229D01*
X1789854Y618312D01*
X1790313D01*
X1790688Y618229D01*
X1791021Y618021D01*
X1791188Y617771D01*
X1791271Y617479D01*
X1791188Y617146D01*
X1791021Y616896D01*
X1790771Y616729D01*
X1790438Y616646D01*
X1790146Y616729D01*
X1789854Y616937D01*
X1789688Y617187D01*
X1789646Y617479D01*
X1789729Y617812D01*
X1789938Y618062D01*
X1790313Y618312D01*
G01X1788771Y619537D02*
X1791271Y620579D01*
X1788771Y621621D01*
G01X1789646Y621246D02*
Y619912D01*
G01X1789271Y622762D02*
X1788979Y623012D01*
X1788813Y623346D01*
X1788771Y623721D01*
X1788813Y624054D01*
X1789021Y624387D01*
X1789271Y624596D01*
X1789521Y624637D01*
X1789813Y624554D01*
X1790021Y624262D01*
X1790104Y623971D01*
Y623596D01*
G01Y623971D02*
X1790229Y624221D01*
X1790438Y624429D01*
X1790688Y624512D01*
X1790938Y624429D01*
X1791146Y624221D01*
X1791271Y623846D01*
X1791229Y623471D01*
X1791063Y623096D01*
G01X1792362Y613517D02*
X1794862D01*
Y614558D01*
X1794737Y614892D01*
X1794570Y615100D01*
X1794237Y615183D01*
X1793904Y615100D01*
X1793695Y614850D01*
X1793570Y614558D01*
Y613517D01*
G01Y614558D02*
X1792362Y615183D01*
G01X1792654Y616742D02*
X1792445Y617033D01*
X1792362Y617367D01*
X1792445Y617700D01*
X1792695Y617992D01*
X1793070Y618200D01*
X1793445Y618283D01*
X1793904D01*
X1794279Y618200D01*
X1794612Y617992D01*
X1794779Y617742D01*
X1794862Y617450D01*
X1794779Y617117D01*
X1794612Y616867D01*
X1794362Y616700D01*
X1794029Y616617D01*
X1793737Y616700D01*
X1793445Y616908D01*
X1793279Y617158D01*
X1793237Y617450D01*
X1793320Y617783D01*
X1793529Y618033D01*
X1793904Y618283D01*
G01X1792362Y619508D02*
X1794862Y620550D01*
X1792362Y621592D01*
G01X1793237Y621217D02*
Y619883D01*
G01X1794445Y622858D02*
X1794695Y623108D01*
X1794820Y623400D01*
X1794862Y623733D01*
X1794779Y624150D01*
X1794570Y624442D01*
X1794320Y624525D01*
X1794070Y624483D01*
X1793862Y624317D01*
X1793445Y623483D01*
X1793154Y623108D01*
X1792737Y622858D01*
X1792362Y622775D01*
Y624525D01*
G01X1811933Y611459D02*
X1812183Y611584D01*
X1812475Y611667D01*
X1812808D01*
X1813183Y611542D01*
X1813475Y611334D01*
X1813683Y611084D01*
X1813850Y610667D01*
X1813892Y610292D01*
X1813808Y609917D01*
X1813683Y609667D01*
X1813433Y609417D01*
X1813142Y609250D01*
X1812850Y609167D01*
X1812558D01*
X1812267Y609250D01*
X1812017Y609375D01*
X1811808Y609542D01*
G01X1809750Y609167D02*
Y611667D01*
X1810250Y611167D01*
G01Y609167D02*
X1809250D01*
G01X1807483Y611667D02*
Y609167D01*
X1805817D01*
G01X1803550D02*
Y611667D01*
X1804050Y611167D01*
G01Y609167D02*
X1803050D01*
G01X1828867Y609100D02*
Y607308D01*
X1828700Y606933D01*
X1828367Y606683D01*
X1827950Y606600D01*
X1827533Y606683D01*
X1827200Y606933D01*
X1827033Y607308D01*
Y609100D01*
G01X1824850Y606600D02*
Y609100D01*
X1825350Y608600D01*
G01Y606600D02*
X1824350D01*
G01X1822583Y609100D02*
Y606600D01*
X1820917D01*
G01X1818650D02*
Y609100D01*
X1819150Y608600D01*
G01Y606600D02*
X1818150D01*
G01X1789900Y590617D02*
X1792400D01*
Y591658D01*
X1792275Y591992D01*
X1792108Y592200D01*
X1791775Y592283D01*
X1791442Y592200D01*
X1791233Y591950D01*
X1791108Y591658D01*
Y590617D01*
G01Y591658D02*
X1789900Y592283D01*
G01X1791983Y593758D02*
X1792233Y594008D01*
X1792358Y594300D01*
X1792400Y594633D01*
X1792317Y595050D01*
X1792108Y595342D01*
X1791858Y595425D01*
X1791608Y595383D01*
X1791400Y595217D01*
X1790983Y594383D01*
X1790692Y594008D01*
X1790275Y593758D01*
X1789900Y593675D01*
Y595425D01*
G01X1790275Y596733D02*
X1790067Y596983D01*
X1789942Y597275D01*
X1789900Y597650D01*
X1789983Y598025D01*
X1790150Y598317D01*
X1790442Y598525D01*
X1790775Y598567D01*
X1791108Y598483D01*
X1791317Y598275D01*
X1791483Y597983D01*
X1791525Y597692D01*
X1791483Y597400D01*
X1791317Y597025D01*
X1792400Y597150D01*
Y598275D01*
G01Y599500D02*
X1789900Y600083D01*
X1792400Y600750D01*
X1789900Y601417D01*
X1792400Y602000D01*
G01X1789900Y603850D02*
X1792400D01*
X1791900Y603350D01*
G01X1789900D02*
Y604350D01*
G01Y606950D02*
X1789942Y607242D01*
X1790067Y607575D01*
X1790275Y607783D01*
X1790567Y607867D01*
X1790858Y607783D01*
X1791108Y607533D01*
X1791233Y607158D01*
Y606742D01*
X1791317Y606492D01*
X1791525Y606283D01*
X1791817Y606200D01*
X1792108Y606325D01*
X1792317Y606617D01*
X1792400Y606950D01*
X1792317Y607283D01*
X1792108Y607575D01*
X1791817Y607700D01*
X1791525Y607617D01*
X1791317Y607408D01*
X1791233Y607158D01*
Y606742D01*
X1791108Y606367D01*
X1790858Y606117D01*
X1790567Y606033D01*
X1790275Y606117D01*
X1790067Y606325D01*
X1789942Y606658D01*
X1789900Y606950D01*
G01X1790400Y609133D02*
X1790108Y609383D01*
X1789942Y609717D01*
X1789900Y610092D01*
X1789942Y610425D01*
X1790150Y610758D01*
X1790400Y610967D01*
X1790650Y611008D01*
X1790942Y610925D01*
X1791150Y610633D01*
X1791233Y610342D01*
Y609967D01*
G01Y610342D02*
X1791358Y610592D01*
X1791567Y610800D01*
X1791817Y610883D01*
X1792067Y610800D01*
X1792275Y610592D01*
X1792400Y610217D01*
X1792358Y609842D01*
X1792192Y609467D01*
G01X1853233Y5867D02*
Y8367D01*
X1852192D01*
X1851858Y8242D01*
X1851650Y8075D01*
X1851567Y7742D01*
X1851650Y7409D01*
X1851900Y7200D01*
X1852192Y7075D01*
X1853233D01*
G01X1852192D02*
X1851567Y5867D01*
G01X1849383D02*
X1849300Y6409D01*
X1849175Y6867D01*
X1849008Y7284D01*
X1848800Y7742D01*
X1848467Y8367D01*
X1850133D01*
G01X1845367Y5867D02*
X1847033D01*
Y8367D01*
X1845367D01*
G01X1846033Y7159D02*
X1847033D01*
G01X1843892Y7950D02*
X1843642Y8200D01*
X1843350Y8325D01*
X1843017Y8367D01*
X1842600Y8284D01*
X1842308Y8075D01*
X1842225Y7825D01*
X1842267Y7575D01*
X1842433Y7367D01*
X1843267Y6950D01*
X1843642Y6659D01*
X1843892Y6242D01*
X1843975Y5867D01*
X1842225D01*
G01X1840792Y7950D02*
X1840542Y8200D01*
X1840250Y8325D01*
X1839917Y8367D01*
X1839500Y8284D01*
X1839208Y8075D01*
X1839125Y7825D01*
X1839167Y7575D01*
X1839333Y7367D01*
X1840167Y6950D01*
X1840542Y6659D01*
X1840792Y6242D01*
X1840875Y5867D01*
X1839125D01*
G01X1891448Y33456D02*
Y35956D01*
X1890407D01*
X1890073Y35831D01*
X1889865Y35664D01*
X1889782Y35331D01*
X1889865Y34998D01*
X1890115Y34789D01*
X1890407Y34664D01*
X1891448D01*
G01X1890407D02*
X1889782Y33456D01*
G01X1888307Y35539D02*
X1888057Y35789D01*
X1887765Y35914D01*
X1887432Y35956D01*
X1887015Y35873D01*
X1886723Y35664D01*
X1886640Y35414D01*
X1886682Y35164D01*
X1886848Y34956D01*
X1887682Y34539D01*
X1888057Y34248D01*
X1888307Y33831D01*
X1888390Y33456D01*
X1886640D01*
G01X1885332Y35956D02*
Y34164D01*
X1885165Y33789D01*
X1884832Y33539D01*
X1884415Y33456D01*
X1883998Y33539D01*
X1883665Y33789D01*
X1883498Y34164D01*
Y35956D01*
G01X1882232Y33956D02*
X1881982Y33664D01*
X1881648Y33498D01*
X1881273Y33456D01*
X1880940Y33498D01*
X1880607Y33706D01*
X1880398Y33956D01*
X1880357Y34206D01*
X1880440Y34498D01*
X1880732Y34706D01*
X1881023Y34789D01*
X1881398D01*
G01X1881023D02*
X1880773Y34914D01*
X1880565Y35123D01*
X1880482Y35373D01*
X1880565Y35623D01*
X1880773Y35831D01*
X1881148Y35956D01*
X1881523Y35914D01*
X1881898Y35748D01*
G01X1878923Y33748D02*
X1878632Y33539D01*
X1878298Y33456D01*
X1877965Y33539D01*
X1877673Y33789D01*
X1877465Y34164D01*
X1877382Y34539D01*
Y34998D01*
X1877465Y35373D01*
X1877673Y35706D01*
X1877923Y35873D01*
X1878215Y35956D01*
X1878548Y35873D01*
X1878798Y35706D01*
X1878965Y35456D01*
X1879048Y35123D01*
X1878965Y34831D01*
X1878757Y34539D01*
X1878507Y34373D01*
X1878215Y34331D01*
X1877882Y34414D01*
X1877632Y34623D01*
X1877382Y34998D01*
G01X1891448Y29956D02*
Y32456D01*
X1890407D01*
X1890073Y32331D01*
X1889865Y32164D01*
X1889782Y31831D01*
X1889865Y31498D01*
X1890115Y31289D01*
X1890407Y31164D01*
X1891448D01*
G01X1890407D02*
X1889782Y29956D01*
G01X1888307Y32039D02*
X1888057Y32289D01*
X1887765Y32414D01*
X1887432Y32456D01*
X1887015Y32373D01*
X1886723Y32164D01*
X1886640Y31914D01*
X1886682Y31664D01*
X1886848Y31456D01*
X1887682Y31039D01*
X1888057Y30748D01*
X1888307Y30331D01*
X1888390Y29956D01*
X1886640D01*
G01X1885332Y32456D02*
Y30664D01*
X1885165Y30289D01*
X1884832Y30039D01*
X1884415Y29956D01*
X1883998Y30039D01*
X1883665Y30289D01*
X1883498Y30664D01*
Y32456D01*
G01X1882232Y30456D02*
X1881982Y30164D01*
X1881648Y29998D01*
X1881273Y29956D01*
X1880940Y29998D01*
X1880607Y30206D01*
X1880398Y30456D01*
X1880357Y30706D01*
X1880440Y30998D01*
X1880732Y31206D01*
X1881023Y31289D01*
X1881398D01*
G01X1881023D02*
X1880773Y31414D01*
X1880565Y31623D01*
X1880482Y31873D01*
X1880565Y32123D01*
X1880773Y32331D01*
X1881148Y32456D01*
X1881523Y32414D01*
X1881898Y32248D01*
G01X1878215Y29956D02*
X1877923Y29998D01*
X1877590Y30123D01*
X1877382Y30331D01*
X1877298Y30623D01*
X1877382Y30914D01*
X1877632Y31164D01*
X1878007Y31289D01*
X1878423D01*
X1878673Y31373D01*
X1878882Y31581D01*
X1878965Y31873D01*
X1878840Y32164D01*
X1878548Y32373D01*
X1878215Y32456D01*
X1877882Y32373D01*
X1877590Y32164D01*
X1877465Y31873D01*
X1877548Y31581D01*
X1877757Y31373D01*
X1878007Y31289D01*
X1878423D01*
X1878798Y31164D01*
X1879048Y30914D01*
X1879132Y30623D01*
X1879048Y30331D01*
X1878840Y30123D01*
X1878507Y29998D01*
X1878215Y29956D01*
G01X1892222Y18341D02*
Y20841D01*
X1891181D01*
X1890847Y20716D01*
X1890639Y20549D01*
X1890556Y20216D01*
X1890639Y19883D01*
X1890889Y19674D01*
X1891181Y19549D01*
X1892222D01*
G01X1891181D02*
X1890556Y18341D01*
G01X1888997Y18633D02*
X1888706Y18424D01*
X1888372Y18341D01*
X1888039Y18424D01*
X1887747Y18674D01*
X1887539Y19049D01*
X1887456Y19424D01*
Y19883D01*
X1887539Y20258D01*
X1887747Y20591D01*
X1887997Y20758D01*
X1888289Y20841D01*
X1888622Y20758D01*
X1888872Y20591D01*
X1889039Y20341D01*
X1889122Y20008D01*
X1889039Y19716D01*
X1888831Y19424D01*
X1888581Y19258D01*
X1888289Y19216D01*
X1887956Y19299D01*
X1887706Y19508D01*
X1887456Y19883D01*
G01X1884939Y19591D02*
X1884106D01*
Y18841D01*
X1884356Y18591D01*
X1884647Y18424D01*
X1885064Y18341D01*
X1885481Y18424D01*
X1885772Y18591D01*
X1886022Y18841D01*
X1886189Y19133D01*
X1886272Y19466D01*
Y19758D01*
X1886189Y20008D01*
X1886022Y20299D01*
X1885772Y20549D01*
X1885522Y20716D01*
X1885189Y20841D01*
X1884897D01*
X1884564Y20758D01*
X1884314Y20591D01*
G01X1882797Y18633D02*
X1882506Y18424D01*
X1882172Y18341D01*
X1881839Y18424D01*
X1881547Y18674D01*
X1881339Y19049D01*
X1881256Y19424D01*
Y19883D01*
X1881339Y20258D01*
X1881547Y20591D01*
X1881797Y20758D01*
X1882089Y20841D01*
X1882422Y20758D01*
X1882672Y20591D01*
X1882839Y20341D01*
X1882922Y20008D01*
X1882839Y19716D01*
X1882631Y19424D01*
X1882381Y19258D01*
X1882089Y19216D01*
X1881756Y19299D01*
X1881506Y19508D01*
X1881256Y19883D01*
G01X1885201Y-11917D02*
X1887701D01*
Y-10876D01*
X1887576Y-10542D01*
X1887409Y-10334D01*
X1887076Y-10251D01*
X1886743Y-10334D01*
X1886534Y-10584D01*
X1886409Y-10876D01*
Y-11917D01*
G01Y-10876D02*
X1885201Y-10251D01*
G01X1885493Y-8692D02*
X1885284Y-8401D01*
X1885201Y-8067D01*
X1885284Y-7734D01*
X1885534Y-7442D01*
X1885909Y-7234D01*
X1886284Y-7151D01*
X1886743D01*
X1887118Y-7234D01*
X1887451Y-7442D01*
X1887618Y-7692D01*
X1887701Y-7984D01*
X1887618Y-8317D01*
X1887451Y-8567D01*
X1887201Y-8734D01*
X1886868Y-8817D01*
X1886576Y-8734D01*
X1886284Y-8526D01*
X1886118Y-8276D01*
X1886076Y-7984D01*
X1886159Y-7651D01*
X1886368Y-7401D01*
X1886743Y-7151D01*
G01X1886451Y-4634D02*
Y-3801D01*
X1885701D01*
X1885451Y-4051D01*
X1885284Y-4342D01*
X1885201Y-4759D01*
X1885284Y-5176D01*
X1885451Y-5467D01*
X1885701Y-5717D01*
X1885993Y-5884D01*
X1886326Y-5967D01*
X1886618D01*
X1886868Y-5884D01*
X1887159Y-5717D01*
X1887409Y-5467D01*
X1887576Y-5217D01*
X1887701Y-4884D01*
Y-4592D01*
X1887618Y-4259D01*
X1887451Y-4009D01*
G01X1885201Y-1784D02*
X1887701D01*
X1887201Y-2284D01*
G01X1885201D02*
Y-1284D01*
G01X1892021Y14932D02*
Y17432D01*
X1890980D01*
X1890646Y17307D01*
X1890438Y17140D01*
X1890355Y16807D01*
X1890438Y16474D01*
X1890688Y16265D01*
X1890980Y16140D01*
X1892021D01*
G01X1890980D02*
X1890355Y14932D01*
G01X1888796Y15224D02*
X1888505Y15015D01*
X1888171Y14932D01*
X1887838Y15015D01*
X1887546Y15265D01*
X1887338Y15640D01*
X1887255Y16015D01*
Y16474D01*
X1887338Y16849D01*
X1887546Y17182D01*
X1887796Y17349D01*
X1888088Y17432D01*
X1888421Y17349D01*
X1888671Y17182D01*
X1888838Y16932D01*
X1888921Y16599D01*
X1888838Y16307D01*
X1888630Y16015D01*
X1888380Y15849D01*
X1888088Y15807D01*
X1887755Y15890D01*
X1887505Y16099D01*
X1887255Y16474D01*
G01X1884738Y16182D02*
X1883905D01*
Y15432D01*
X1884155Y15182D01*
X1884446Y15015D01*
X1884863Y14932D01*
X1885280Y15015D01*
X1885571Y15182D01*
X1885821Y15432D01*
X1885988Y15724D01*
X1886071Y16057D01*
Y16349D01*
X1885988Y16599D01*
X1885821Y16890D01*
X1885571Y17140D01*
X1885321Y17307D01*
X1884988Y17432D01*
X1884696D01*
X1884363Y17349D01*
X1884113Y17182D01*
G01X1881888Y14932D02*
Y17432D01*
X1882388Y16932D01*
G01Y14932D02*
X1881388D01*
G01X1878788D02*
Y17432D01*
X1879288Y16932D01*
G01Y14932D02*
X1878288D01*
G01X1866283Y32592D02*
X1866533Y32717D01*
X1866825Y32800D01*
X1867158D01*
X1867533Y32675D01*
X1867825Y32467D01*
X1868033Y32217D01*
X1868200Y31800D01*
X1868242Y31425D01*
X1868158Y31050D01*
X1868033Y30800D01*
X1867783Y30550D01*
X1867492Y30383D01*
X1867200Y30300D01*
X1866908D01*
X1866617Y30383D01*
X1866367Y30508D01*
X1866158Y30675D01*
G01X1864892Y32383D02*
X1864642Y32633D01*
X1864350Y32758D01*
X1864017Y32800D01*
X1863600Y32717D01*
X1863308Y32508D01*
X1863225Y32258D01*
X1863267Y32008D01*
X1863433Y31800D01*
X1864267Y31383D01*
X1864642Y31092D01*
X1864892Y30675D01*
X1864975Y30300D01*
X1863225D01*
G01X1861917Y32800D02*
Y31008D01*
X1861750Y30633D01*
X1861417Y30383D01*
X1861000Y30300D01*
X1860583Y30383D01*
X1860250Y30633D01*
X1860083Y31008D01*
Y32800D01*
G01X1858692Y32383D02*
X1858442Y32633D01*
X1858150Y32758D01*
X1857817Y32800D01*
X1857400Y32717D01*
X1857108Y32508D01*
X1857025Y32258D01*
X1857067Y32008D01*
X1857233Y31800D01*
X1858067Y31383D01*
X1858442Y31092D01*
X1858692Y30675D01*
X1858775Y30300D01*
X1857025D01*
G01X1855717Y30675D02*
X1855467Y30467D01*
X1855175Y30342D01*
X1854800Y30300D01*
X1854425Y30383D01*
X1854133Y30550D01*
X1853925Y30842D01*
X1853883Y31175D01*
X1853967Y31508D01*
X1854175Y31717D01*
X1854467Y31883D01*
X1854758Y31925D01*
X1855050Y31883D01*
X1855425Y31717D01*
X1855300Y32800D01*
X1854175D01*
G01X1850083Y33692D02*
X1850333Y33817D01*
X1850625Y33900D01*
X1850958D01*
X1851333Y33775D01*
X1851625Y33567D01*
X1851833Y33317D01*
X1852000Y32900D01*
X1852042Y32525D01*
X1851958Y32150D01*
X1851833Y31900D01*
X1851583Y31650D01*
X1851292Y31483D01*
X1851000Y31400D01*
X1850708D01*
X1850417Y31483D01*
X1850167Y31608D01*
X1849958Y31775D01*
G01X1848692Y33483D02*
X1848442Y33733D01*
X1848150Y33858D01*
X1847817Y33900D01*
X1847400Y33817D01*
X1847108Y33608D01*
X1847025Y33358D01*
X1847067Y33108D01*
X1847233Y32900D01*
X1848067Y32483D01*
X1848442Y32192D01*
X1848692Y31775D01*
X1848775Y31400D01*
X1847025D01*
G01X1845717Y33900D02*
Y32108D01*
X1845550Y31733D01*
X1845217Y31483D01*
X1844800Y31400D01*
X1844383Y31483D01*
X1844050Y31733D01*
X1843883Y32108D01*
Y33900D01*
G01X1842492Y33483D02*
X1842242Y33733D01*
X1841950Y33858D01*
X1841617Y33900D01*
X1841200Y33817D01*
X1840908Y33608D01*
X1840825Y33358D01*
X1840867Y33108D01*
X1841033Y32900D01*
X1841867Y32483D01*
X1842242Y32192D01*
X1842492Y31775D01*
X1842575Y31400D01*
X1840825D01*
G01X1838600D02*
Y33900D01*
X1839100Y33400D01*
G01Y31400D02*
X1838100D01*
G01X1861171Y15862D02*
X1861421Y15987D01*
X1861713Y16070D01*
X1862046D01*
X1862421Y15945D01*
X1862713Y15737D01*
X1862921Y15487D01*
X1863088Y15070D01*
X1863130Y14695D01*
X1863046Y14320D01*
X1862921Y14070D01*
X1862671Y13820D01*
X1862380Y13653D01*
X1862088Y13570D01*
X1861796D01*
X1861505Y13653D01*
X1861255Y13778D01*
X1861046Y13945D01*
G01X1859780Y15653D02*
X1859530Y15903D01*
X1859238Y16028D01*
X1858905Y16070D01*
X1858488Y15987D01*
X1858196Y15778D01*
X1858113Y15528D01*
X1858155Y15278D01*
X1858321Y15070D01*
X1859155Y14653D01*
X1859530Y14362D01*
X1859780Y13945D01*
X1859863Y13570D01*
X1858113D01*
G01X1856805Y16070D02*
Y14278D01*
X1856638Y13903D01*
X1856305Y13653D01*
X1855888Y13570D01*
X1855471Y13653D01*
X1855138Y13903D01*
X1854971Y14278D01*
Y16070D01*
G01X1853580Y15653D02*
X1853330Y15903D01*
X1853038Y16028D01*
X1852705Y16070D01*
X1852288Y15987D01*
X1851996Y15778D01*
X1851913Y15528D01*
X1851955Y15278D01*
X1852121Y15070D01*
X1852955Y14653D01*
X1853330Y14362D01*
X1853580Y13945D01*
X1853663Y13570D01*
X1851913D01*
G01X1849188D02*
Y16070D01*
X1850730Y14278D01*
X1848646D01*
G01X1903238Y-15687D02*
X1903488Y-15562D01*
X1903780Y-15479D01*
X1904113D01*
X1904488Y-15604D01*
X1904780Y-15812D01*
X1904988Y-16062D01*
X1905155Y-16479D01*
X1905197Y-16854D01*
X1905113Y-17229D01*
X1904988Y-17479D01*
X1904738Y-17729D01*
X1904447Y-17896D01*
X1904155Y-17979D01*
X1903863D01*
X1903572Y-17896D01*
X1903322Y-17771D01*
X1903113Y-17604D01*
G01X1901763Y-17687D02*
X1901472Y-17896D01*
X1901138Y-17979D01*
X1900805Y-17896D01*
X1900513Y-17646D01*
X1900305Y-17271D01*
X1900222Y-16896D01*
Y-16437D01*
X1900305Y-16062D01*
X1900513Y-15729D01*
X1900763Y-15562D01*
X1901055Y-15479D01*
X1901388Y-15562D01*
X1901638Y-15729D01*
X1901805Y-15979D01*
X1901888Y-16312D01*
X1901805Y-16604D01*
X1901597Y-16896D01*
X1901347Y-17062D01*
X1901055Y-17104D01*
X1900722Y-17021D01*
X1900472Y-16812D01*
X1900222Y-16437D01*
G01X1897705Y-16729D02*
X1896872D01*
Y-17479D01*
X1897122Y-17729D01*
X1897413Y-17896D01*
X1897830Y-17979D01*
X1898247Y-17896D01*
X1898538Y-17729D01*
X1898788Y-17479D01*
X1898955Y-17187D01*
X1899038Y-16854D01*
Y-16562D01*
X1898955Y-16312D01*
X1898788Y-16021D01*
X1898538Y-15771D01*
X1898288Y-15604D01*
X1897955Y-15479D01*
X1897663D01*
X1897330Y-15562D01*
X1897080Y-15729D01*
G01X1895647Y-15896D02*
X1895397Y-15646D01*
X1895105Y-15521D01*
X1894772Y-15479D01*
X1894355Y-15562D01*
X1894063Y-15771D01*
X1893980Y-16021D01*
X1894022Y-16271D01*
X1894188Y-16479D01*
X1895022Y-16896D01*
X1895397Y-17187D01*
X1895647Y-17604D01*
X1895730Y-17979D01*
X1893980D01*
G01X1873852Y16759D02*
X1874102Y16884D01*
X1874394Y16967D01*
X1874727D01*
X1875102Y16842D01*
X1875394Y16634D01*
X1875602Y16384D01*
X1875769Y15967D01*
X1875811Y15592D01*
X1875727Y15217D01*
X1875602Y14967D01*
X1875352Y14717D01*
X1875061Y14550D01*
X1874769Y14467D01*
X1874477D01*
X1874186Y14550D01*
X1873936Y14675D01*
X1873727Y14842D01*
G01X1872377Y14759D02*
X1872086Y14550D01*
X1871752Y14467D01*
X1871419Y14550D01*
X1871127Y14800D01*
X1870919Y15175D01*
X1870836Y15550D01*
Y16009D01*
X1870919Y16384D01*
X1871127Y16717D01*
X1871377Y16884D01*
X1871669Y16967D01*
X1872002Y16884D01*
X1872252Y16717D01*
X1872419Y16467D01*
X1872502Y16134D01*
X1872419Y15842D01*
X1872211Y15550D01*
X1871961Y15384D01*
X1871669Y15342D01*
X1871336Y15425D01*
X1871086Y15634D01*
X1870836Y16009D01*
G01X1868319Y15717D02*
X1867486D01*
Y14967D01*
X1867736Y14717D01*
X1868027Y14550D01*
X1868444Y14467D01*
X1868861Y14550D01*
X1869152Y14717D01*
X1869402Y14967D01*
X1869569Y15259D01*
X1869652Y15592D01*
Y15884D01*
X1869569Y16134D01*
X1869402Y16425D01*
X1869152Y16675D01*
X1868902Y16842D01*
X1868569Y16967D01*
X1868277D01*
X1867944Y16884D01*
X1867694Y16717D01*
G01X1866177Y14759D02*
X1865886Y14550D01*
X1865552Y14467D01*
X1865219Y14550D01*
X1864927Y14800D01*
X1864719Y15175D01*
X1864636Y15550D01*
Y16009D01*
X1864719Y16384D01*
X1864927Y16717D01*
X1865177Y16884D01*
X1865469Y16967D01*
X1865802Y16884D01*
X1866052Y16717D01*
X1866219Y16467D01*
X1866302Y16134D01*
X1866219Y15842D01*
X1866011Y15550D01*
X1865761Y15384D01*
X1865469Y15342D01*
X1865136Y15425D01*
X1864886Y15634D01*
X1864636Y16009D01*
G01X1890971Y-10581D02*
X1891096Y-10831D01*
X1891179Y-11123D01*
Y-11456D01*
X1891054Y-11831D01*
X1890846Y-12123D01*
X1890596Y-12331D01*
X1890179Y-12498D01*
X1889804Y-12540D01*
X1889429Y-12456D01*
X1889179Y-12331D01*
X1888929Y-12081D01*
X1888762Y-11790D01*
X1888679Y-11498D01*
Y-11206D01*
X1888762Y-10915D01*
X1888887Y-10665D01*
X1889054Y-10456D01*
G01X1888971Y-9106D02*
X1888762Y-8815D01*
X1888679Y-8481D01*
X1888762Y-8148D01*
X1889012Y-7856D01*
X1889387Y-7648D01*
X1889762Y-7565D01*
X1890221D01*
X1890596Y-7648D01*
X1890929Y-7856D01*
X1891096Y-8106D01*
X1891179Y-8398D01*
X1891096Y-8731D01*
X1890929Y-8981D01*
X1890679Y-9148D01*
X1890346Y-9231D01*
X1890054Y-9148D01*
X1889762Y-8940D01*
X1889596Y-8690D01*
X1889554Y-8398D01*
X1889637Y-8065D01*
X1889846Y-7815D01*
X1890221Y-7565D01*
G01X1888679Y-6090D02*
X1891179D01*
Y-4506D01*
G01X1889971Y-5090D02*
Y-6090D01*
G01X1890762Y-2990D02*
X1891012Y-2740D01*
X1891137Y-2448D01*
X1891179Y-2115D01*
X1891096Y-1698D01*
X1890887Y-1406D01*
X1890637Y-1323D01*
X1890387Y-1365D01*
X1890179Y-1531D01*
X1889762Y-2365D01*
X1889471Y-2740D01*
X1889054Y-2990D01*
X1888679Y-3073D01*
Y-1323D01*
G01X1890762Y110D02*
X1891012Y360D01*
X1891137Y652D01*
X1891179Y985D01*
X1891096Y1402D01*
X1890887Y1694D01*
X1890637Y1777D01*
X1890387Y1735D01*
X1890179Y1569D01*
X1889762Y735D01*
X1889471Y360D01*
X1889054Y110D01*
X1888679Y27D01*
Y1777D01*
G01X1873493Y11482D02*
X1873743Y11607D01*
X1874035Y11690D01*
X1874368D01*
X1874743Y11565D01*
X1875035Y11357D01*
X1875243Y11107D01*
X1875410Y10690D01*
X1875452Y10315D01*
X1875368Y9940D01*
X1875243Y9690D01*
X1874993Y9440D01*
X1874702Y9273D01*
X1874410Y9190D01*
X1874118D01*
X1873827Y9273D01*
X1873577Y9398D01*
X1873368Y9565D01*
G01X1872018Y9482D02*
X1871727Y9273D01*
X1871393Y9190D01*
X1871060Y9273D01*
X1870768Y9523D01*
X1870560Y9898D01*
X1870477Y10273D01*
Y10732D01*
X1870560Y11107D01*
X1870768Y11440D01*
X1871018Y11607D01*
X1871310Y11690D01*
X1871643Y11607D01*
X1871893Y11440D01*
X1872060Y11190D01*
X1872143Y10857D01*
X1872060Y10565D01*
X1871852Y10273D01*
X1871602Y10107D01*
X1871310Y10065D01*
X1870977Y10148D01*
X1870727Y10357D01*
X1870477Y10732D01*
G01X1867960Y10440D02*
X1867127D01*
Y9690D01*
X1867377Y9440D01*
X1867668Y9273D01*
X1868085Y9190D01*
X1868502Y9273D01*
X1868793Y9440D01*
X1869043Y9690D01*
X1869210Y9982D01*
X1869293Y10315D01*
Y10607D01*
X1869210Y10857D01*
X1869043Y11148D01*
X1868793Y11398D01*
X1868543Y11565D01*
X1868210Y11690D01*
X1867918D01*
X1867585Y11607D01*
X1867335Y11440D01*
G01X1865110Y9190D02*
Y11690D01*
X1865610Y11190D01*
G01Y9190D02*
X1864610D01*
G01X1862802Y11273D02*
X1862552Y11523D01*
X1862260Y11648D01*
X1861927Y11690D01*
X1861510Y11607D01*
X1861218Y11398D01*
X1861135Y11148D01*
X1861177Y10898D01*
X1861343Y10690D01*
X1862177Y10273D01*
X1862552Y9982D01*
X1862802Y9565D01*
X1862885Y9190D01*
X1861135D01*
G01X1864661Y56670D02*
X1864786Y56420D01*
X1864869Y56128D01*
Y55795D01*
X1864744Y55420D01*
X1864536Y55128D01*
X1864286Y54920D01*
X1863869Y54753D01*
X1863494Y54711D01*
X1863119Y54795D01*
X1862869Y54920D01*
X1862619Y55170D01*
X1862452Y55461D01*
X1862369Y55753D01*
Y56045D01*
X1862452Y56336D01*
X1862577Y56586D01*
X1862744Y56795D01*
G01X1864452Y58061D02*
X1864702Y58311D01*
X1864827Y58603D01*
X1864869Y58936D01*
X1864786Y59353D01*
X1864577Y59645D01*
X1864327Y59728D01*
X1864077Y59686D01*
X1863869Y59520D01*
X1863452Y58686D01*
X1863161Y58311D01*
X1862744Y58061D01*
X1862369Y57978D01*
Y59728D01*
G01X1864869Y61036D02*
X1863077D01*
X1862702Y61203D01*
X1862452Y61536D01*
X1862369Y61953D01*
X1862452Y62370D01*
X1862702Y62703D01*
X1863077Y62870D01*
X1864869D01*
G01X1864452Y64261D02*
X1864702Y64511D01*
X1864827Y64803D01*
X1864869Y65136D01*
X1864786Y65553D01*
X1864577Y65845D01*
X1864327Y65928D01*
X1864077Y65886D01*
X1863869Y65720D01*
X1863452Y64886D01*
X1863161Y64511D01*
X1862744Y64261D01*
X1862369Y64178D01*
Y65928D01*
G01X1903201Y57067D02*
Y59567D01*
X1902160D01*
X1901826Y59442D01*
X1901618Y59275D01*
X1901535Y58942D01*
X1901618Y58609D01*
X1901868Y58400D01*
X1902160Y58275D01*
X1903201D01*
G01X1902160D02*
X1901535Y57067D01*
G01X1899976Y57359D02*
X1899685Y57150D01*
X1899351Y57067D01*
X1899018Y57150D01*
X1898726Y57400D01*
X1898518Y57775D01*
X1898435Y58150D01*
Y58609D01*
X1898518Y58984D01*
X1898726Y59317D01*
X1898976Y59484D01*
X1899268Y59567D01*
X1899601Y59484D01*
X1899851Y59317D01*
X1900018Y59067D01*
X1900101Y58734D01*
X1900018Y58442D01*
X1899810Y58150D01*
X1899560Y57984D01*
X1899268Y57942D01*
X1898935Y58025D01*
X1898685Y58234D01*
X1898435Y58609D01*
G01X1895918Y58317D02*
X1895085D01*
Y57567D01*
X1895335Y57317D01*
X1895626Y57150D01*
X1896043Y57067D01*
X1896460Y57150D01*
X1896751Y57317D01*
X1897001Y57567D01*
X1897168Y57859D01*
X1897251Y58192D01*
Y58484D01*
X1897168Y58734D01*
X1897001Y59025D01*
X1896751Y59275D01*
X1896501Y59442D01*
X1896168Y59567D01*
X1895876D01*
X1895543Y59484D01*
X1895293Y59317D01*
G01X1893985Y57567D02*
X1893735Y57275D01*
X1893401Y57109D01*
X1893026Y57067D01*
X1892693Y57109D01*
X1892360Y57317D01*
X1892151Y57567D01*
X1892110Y57817D01*
X1892193Y58109D01*
X1892485Y58317D01*
X1892776Y58400D01*
X1893151D01*
G01X1892776D02*
X1892526Y58525D01*
X1892318Y58734D01*
X1892235Y58984D01*
X1892318Y59234D01*
X1892526Y59442D01*
X1892901Y59567D01*
X1893276Y59525D01*
X1893651Y59359D01*
G01X1850097Y36424D02*
X1852597D01*
Y37465D01*
X1852472Y37799D01*
X1852305Y38007D01*
X1851972Y38090D01*
X1851639Y38007D01*
X1851430Y37757D01*
X1851305Y37465D01*
Y36424D01*
G01Y37465D02*
X1850097Y38090D01*
G01X1852180Y39565D02*
X1852430Y39815D01*
X1852555Y40107D01*
X1852597Y40440D01*
X1852514Y40857D01*
X1852305Y41149D01*
X1852055Y41232D01*
X1851805Y41190D01*
X1851597Y41024D01*
X1851180Y40190D01*
X1850889Y39815D01*
X1850472Y39565D01*
X1850097Y39482D01*
Y41232D01*
G01X1852597Y42540D02*
X1850805D01*
X1850430Y42707D01*
X1850180Y43040D01*
X1850097Y43457D01*
X1850180Y43874D01*
X1850430Y44207D01*
X1850805Y44374D01*
X1852597D01*
G01X1850597Y45640D02*
X1850305Y45890D01*
X1850139Y46224D01*
X1850097Y46599D01*
X1850139Y46932D01*
X1850347Y47265D01*
X1850597Y47474D01*
X1850847Y47515D01*
X1851139Y47432D01*
X1851347Y47140D01*
X1851430Y46849D01*
Y46474D01*
G01Y46849D02*
X1851555Y47099D01*
X1851764Y47307D01*
X1852014Y47390D01*
X1852264Y47307D01*
X1852472Y47099D01*
X1852597Y46724D01*
X1852555Y46349D01*
X1852389Y45974D01*
G01X1851139Y48865D02*
X1851430Y49157D01*
X1851597Y49407D01*
X1851680Y49740D01*
X1851597Y50032D01*
X1851430Y50240D01*
X1851180Y50407D01*
X1850889Y50449D01*
X1850639Y50407D01*
X1850389Y50240D01*
X1850180Y49990D01*
X1850097Y49699D01*
X1850180Y49365D01*
X1850430Y49074D01*
X1850805Y48907D01*
X1851222Y48865D01*
X1851764Y48949D01*
X1852055Y49074D01*
X1852347Y49282D01*
X1852555Y49574D01*
X1852597Y49865D01*
X1852514Y50157D01*
X1852305Y50365D01*
G01X1853906Y36402D02*
X1856406D01*
Y37443D01*
X1856281Y37777D01*
X1856114Y37985D01*
X1855781Y38068D01*
X1855448Y37985D01*
X1855239Y37735D01*
X1855114Y37443D01*
Y36402D01*
G01Y37443D02*
X1853906Y38068D01*
G01X1855989Y39543D02*
X1856239Y39793D01*
X1856364Y40085D01*
X1856406Y40418D01*
X1856323Y40835D01*
X1856114Y41127D01*
X1855864Y41210D01*
X1855614Y41168D01*
X1855406Y41002D01*
X1854989Y40168D01*
X1854698Y39793D01*
X1854281Y39543D01*
X1853906Y39460D01*
Y41210D01*
G01X1856406Y42518D02*
X1854614D01*
X1854239Y42685D01*
X1853989Y43018D01*
X1853906Y43435D01*
X1853989Y43852D01*
X1854239Y44185D01*
X1854614Y44352D01*
X1856406D01*
G01X1854406Y45618D02*
X1854114Y45868D01*
X1853948Y46202D01*
X1853906Y46577D01*
X1853948Y46910D01*
X1854156Y47243D01*
X1854406Y47452D01*
X1854656Y47493D01*
X1854948Y47410D01*
X1855156Y47118D01*
X1855239Y46827D01*
Y46452D01*
G01Y46827D02*
X1855364Y47077D01*
X1855573Y47285D01*
X1855823Y47368D01*
X1856073Y47285D01*
X1856281Y47077D01*
X1856406Y46702D01*
X1856364Y46327D01*
X1856198Y45952D01*
G01X1854281Y48718D02*
X1854073Y48968D01*
X1853948Y49260D01*
X1853906Y49635D01*
X1853989Y50010D01*
X1854156Y50302D01*
X1854448Y50510D01*
X1854781Y50552D01*
X1855114Y50468D01*
X1855323Y50260D01*
X1855489Y49968D01*
X1855531Y49677D01*
X1855489Y49385D01*
X1855323Y49010D01*
X1856406Y49135D01*
Y50260D01*
G01X1846407Y49220D02*
X1848907D01*
Y50261D01*
X1848782Y50595D01*
X1848615Y50803D01*
X1848282Y50886D01*
X1847949Y50803D01*
X1847740Y50553D01*
X1847615Y50261D01*
Y49220D01*
G01Y50261D02*
X1846407Y50886D01*
G01X1848490Y52361D02*
X1848740Y52611D01*
X1848865Y52903D01*
X1848907Y53236D01*
X1848824Y53653D01*
X1848615Y53945D01*
X1848365Y54028D01*
X1848115Y53986D01*
X1847907Y53820D01*
X1847490Y52986D01*
X1847199Y52611D01*
X1846782Y52361D01*
X1846407Y52278D01*
Y54028D01*
G01X1848907Y55336D02*
X1847115D01*
X1846740Y55503D01*
X1846490Y55836D01*
X1846407Y56253D01*
X1846490Y56670D01*
X1846740Y57003D01*
X1847115Y57170D01*
X1848907D01*
G01X1846907Y58436D02*
X1846615Y58686D01*
X1846449Y59020D01*
X1846407Y59395D01*
X1846449Y59728D01*
X1846657Y60061D01*
X1846907Y60270D01*
X1847157Y60311D01*
X1847449Y60228D01*
X1847657Y59936D01*
X1847740Y59645D01*
Y59270D01*
G01Y59645D02*
X1847865Y59895D01*
X1848074Y60103D01*
X1848324Y60186D01*
X1848574Y60103D01*
X1848782Y59895D01*
X1848907Y59520D01*
X1848865Y59145D01*
X1848699Y58770D01*
G01X1846407Y62453D02*
X1848907D01*
X1848407Y61953D01*
G01X1846407D02*
Y62953D01*
G01X1842769Y49238D02*
X1845269D01*
Y50279D01*
X1845144Y50613D01*
X1844977Y50821D01*
X1844644Y50904D01*
X1844311Y50821D01*
X1844102Y50571D01*
X1843977Y50279D01*
Y49238D01*
G01Y50279D02*
X1842769Y50904D01*
G01X1844852Y52379D02*
X1845102Y52629D01*
X1845227Y52921D01*
X1845269Y53254D01*
X1845186Y53671D01*
X1844977Y53963D01*
X1844727Y54046D01*
X1844477Y54004D01*
X1844269Y53838D01*
X1843852Y53004D01*
X1843561Y52629D01*
X1843144Y52379D01*
X1842769Y52296D01*
Y54046D01*
G01X1845269Y55354D02*
X1843477D01*
X1843102Y55521D01*
X1842852Y55854D01*
X1842769Y56271D01*
X1842852Y56688D01*
X1843102Y57021D01*
X1843477Y57188D01*
X1845269D01*
G01X1843269Y58454D02*
X1842977Y58704D01*
X1842811Y59038D01*
X1842769Y59413D01*
X1842811Y59746D01*
X1843019Y60079D01*
X1843269Y60288D01*
X1843519Y60329D01*
X1843811Y60246D01*
X1844019Y59954D01*
X1844102Y59663D01*
Y59288D01*
G01Y59663D02*
X1844227Y59913D01*
X1844436Y60121D01*
X1844686Y60204D01*
X1844936Y60121D01*
X1845144Y59913D01*
X1845269Y59538D01*
X1845227Y59163D01*
X1845061Y58788D01*
G01X1844852Y61679D02*
X1845102Y61929D01*
X1845227Y62221D01*
X1845269Y62554D01*
X1845186Y62971D01*
X1844977Y63263D01*
X1844727Y63346D01*
X1844477Y63304D01*
X1844269Y63138D01*
X1843852Y62304D01*
X1843561Y61929D01*
X1843144Y61679D01*
X1842769Y61596D01*
Y63346D01*
G01X1859673Y77890D02*
Y80390D01*
X1858632D01*
X1858298Y80265D01*
X1858090Y80098D01*
X1858007Y79765D01*
X1858090Y79432D01*
X1858340Y79223D01*
X1858632Y79098D01*
X1859673D01*
G01X1858632D02*
X1858007Y77890D01*
G01X1855740D02*
X1855448Y77932D01*
X1855115Y78057D01*
X1854907Y78265D01*
X1854823Y78557D01*
X1854907Y78848D01*
X1855157Y79098D01*
X1855532Y79223D01*
X1855948D01*
X1856198Y79307D01*
X1856407Y79515D01*
X1856490Y79807D01*
X1856365Y80098D01*
X1856073Y80307D01*
X1855740Y80390D01*
X1855407Y80307D01*
X1855115Y80098D01*
X1854990Y79807D01*
X1855073Y79515D01*
X1855282Y79307D01*
X1855532Y79223D01*
X1855948D01*
X1856323Y79098D01*
X1856573Y78848D01*
X1856657Y78557D01*
X1856573Y78265D01*
X1856365Y78057D01*
X1856032Y77932D01*
X1855740Y77890D01*
G01X1853432D02*
Y80390D01*
X1851848D01*
G01X1852432Y79182D02*
X1853432D01*
G01X1850457Y78390D02*
X1850207Y78098D01*
X1849873Y77932D01*
X1849498Y77890D01*
X1849165Y77932D01*
X1848832Y78140D01*
X1848623Y78390D01*
X1848582Y78640D01*
X1848665Y78932D01*
X1848957Y79140D01*
X1849248Y79223D01*
X1849623D01*
G01X1849248D02*
X1848998Y79348D01*
X1848790Y79557D01*
X1848707Y79807D01*
X1848790Y80057D01*
X1848998Y80265D01*
X1849373Y80390D01*
X1849748Y80348D01*
X1850123Y80182D01*
G01X1894133Y68659D02*
X1894383Y68784D01*
X1894675Y68867D01*
X1895008D01*
X1895383Y68742D01*
X1895675Y68534D01*
X1895883Y68284D01*
X1896050Y67867D01*
X1896092Y67492D01*
X1896008Y67117D01*
X1895883Y66867D01*
X1895633Y66617D01*
X1895342Y66450D01*
X1895050Y66367D01*
X1894758D01*
X1894467Y66450D01*
X1894217Y66575D01*
X1894008Y66742D01*
G01X1892658Y66659D02*
X1892367Y66450D01*
X1892033Y66367D01*
X1891700Y66450D01*
X1891408Y66700D01*
X1891200Y67075D01*
X1891117Y67450D01*
Y67909D01*
X1891200Y68284D01*
X1891408Y68617D01*
X1891658Y68784D01*
X1891950Y68867D01*
X1892283Y68784D01*
X1892533Y68617D01*
X1892700Y68367D01*
X1892783Y68034D01*
X1892700Y67742D01*
X1892492Y67450D01*
X1892242Y67284D01*
X1891950Y67242D01*
X1891617Y67325D01*
X1891367Y67534D01*
X1891117Y67909D01*
G01X1888600Y67617D02*
X1887767D01*
Y66867D01*
X1888017Y66617D01*
X1888308Y66450D01*
X1888725Y66367D01*
X1889142Y66450D01*
X1889433Y66617D01*
X1889683Y66867D01*
X1889850Y67159D01*
X1889933Y67492D01*
Y67784D01*
X1889850Y68034D01*
X1889683Y68325D01*
X1889433Y68575D01*
X1889183Y68742D01*
X1888850Y68867D01*
X1888558D01*
X1888225Y68784D01*
X1887975Y68617D01*
G01X1886667Y66867D02*
X1886417Y66575D01*
X1886083Y66409D01*
X1885708Y66367D01*
X1885375Y66409D01*
X1885042Y66617D01*
X1884833Y66867D01*
X1884792Y67117D01*
X1884875Y67409D01*
X1885167Y67617D01*
X1885458Y67700D01*
X1885833D01*
G01X1885458D02*
X1885208Y67825D01*
X1885000Y68034D01*
X1884917Y68284D01*
X1885000Y68534D01*
X1885208Y68742D01*
X1885583Y68867D01*
X1885958Y68825D01*
X1886333Y68659D01*
G01X1870383Y43842D02*
X1870633Y43967D01*
X1870925Y44050D01*
X1871258D01*
X1871633Y43925D01*
X1871925Y43717D01*
X1872133Y43467D01*
X1872300Y43050D01*
X1872342Y42675D01*
X1872258Y42300D01*
X1872133Y42050D01*
X1871883Y41800D01*
X1871592Y41633D01*
X1871300Y41550D01*
X1871008D01*
X1870717Y41633D01*
X1870467Y41758D01*
X1870258Y41925D01*
G01X1868992Y43633D02*
X1868742Y43883D01*
X1868450Y44008D01*
X1868117Y44050D01*
X1867700Y43967D01*
X1867408Y43758D01*
X1867325Y43508D01*
X1867367Y43258D01*
X1867533Y43050D01*
X1868367Y42633D01*
X1868742Y42342D01*
X1868992Y41925D01*
X1869075Y41550D01*
X1867325D01*
G01X1866017Y44050D02*
Y42258D01*
X1865850Y41883D01*
X1865517Y41633D01*
X1865100Y41550D01*
X1864683Y41633D01*
X1864350Y41883D01*
X1864183Y42258D01*
Y44050D01*
G01X1862792Y43633D02*
X1862542Y43883D01*
X1862250Y44008D01*
X1861917Y44050D01*
X1861500Y43967D01*
X1861208Y43758D01*
X1861125Y43508D01*
X1861167Y43258D01*
X1861333Y43050D01*
X1862167Y42633D01*
X1862542Y42342D01*
X1862792Y41925D01*
X1862875Y41550D01*
X1861125D01*
G01X1858900Y44050D02*
X1859233Y43967D01*
X1859483Y43758D01*
X1859650Y43508D01*
X1859775Y43175D01*
X1859817Y42800D01*
X1859775Y42425D01*
X1859650Y42092D01*
X1859483Y41842D01*
X1859233Y41633D01*
X1858900Y41550D01*
X1858567Y41633D01*
X1858317Y41842D01*
X1858150Y42092D01*
X1858025Y42425D01*
X1857983Y42800D01*
X1858025Y43175D01*
X1858150Y43508D01*
X1858317Y43758D01*
X1858567Y43967D01*
X1858900Y44050D01*
G01X1852742Y64107D02*
X1852867Y63857D01*
X1852950Y63565D01*
Y63232D01*
X1852825Y62857D01*
X1852617Y62565D01*
X1852367Y62357D01*
X1851950Y62190D01*
X1851575Y62148D01*
X1851200Y62232D01*
X1850950Y62357D01*
X1850700Y62607D01*
X1850533Y62898D01*
X1850450Y63190D01*
Y63482D01*
X1850533Y63773D01*
X1850658Y64023D01*
X1850825Y64232D01*
G01X1852533Y65498D02*
X1852783Y65748D01*
X1852908Y66040D01*
X1852950Y66373D01*
X1852867Y66790D01*
X1852658Y67082D01*
X1852408Y67165D01*
X1852158Y67123D01*
X1851950Y66957D01*
X1851533Y66123D01*
X1851242Y65748D01*
X1850825Y65498D01*
X1850450Y65415D01*
Y67165D01*
G01X1852950Y68473D02*
X1851158D01*
X1850783Y68640D01*
X1850533Y68973D01*
X1850450Y69390D01*
X1850533Y69807D01*
X1850783Y70140D01*
X1851158Y70307D01*
X1852950D01*
G01X1850450Y72490D02*
X1852950D01*
X1852450Y71990D01*
G01X1850450D02*
Y72990D01*
G01X1850742Y74882D02*
X1850533Y75173D01*
X1850450Y75507D01*
X1850533Y75840D01*
X1850783Y76132D01*
X1851158Y76340D01*
X1851533Y76423D01*
X1851992D01*
X1852367Y76340D01*
X1852700Y76132D01*
X1852867Y75882D01*
X1852950Y75590D01*
X1852867Y75257D01*
X1852700Y75007D01*
X1852450Y74840D01*
X1852117Y74757D01*
X1851825Y74840D01*
X1851533Y75048D01*
X1851367Y75298D01*
X1851325Y75590D01*
X1851408Y75923D01*
X1851617Y76173D01*
X1851992Y76423D01*
G01X1875775Y63823D02*
X1875900Y63573D01*
X1875983Y63281D01*
Y62948D01*
X1875858Y62573D01*
X1875650Y62281D01*
X1875400Y62073D01*
X1874983Y61906D01*
X1874608Y61864D01*
X1874233Y61948D01*
X1873983Y62073D01*
X1873733Y62323D01*
X1873566Y62614D01*
X1873483Y62906D01*
Y63198D01*
X1873566Y63489D01*
X1873691Y63739D01*
X1873858Y63948D01*
G01X1873483Y66006D02*
X1873525Y66298D01*
X1873650Y66631D01*
X1873858Y66839D01*
X1874150Y66923D01*
X1874441Y66839D01*
X1874691Y66589D01*
X1874816Y66214D01*
Y65798D01*
X1874900Y65548D01*
X1875108Y65339D01*
X1875400Y65256D01*
X1875691Y65381D01*
X1875900Y65673D01*
X1875983Y66006D01*
X1875900Y66339D01*
X1875691Y66631D01*
X1875400Y66756D01*
X1875108Y66673D01*
X1874900Y66464D01*
X1874816Y66214D01*
Y65798D01*
X1874691Y65423D01*
X1874441Y65173D01*
X1874150Y65089D01*
X1873858Y65173D01*
X1873650Y65381D01*
X1873525Y65714D01*
X1873483Y66006D01*
G01Y68314D02*
X1875983D01*
Y69898D01*
G01X1874775Y69314D02*
Y68314D01*
G01X1873483Y72206D02*
X1875983D01*
X1875483Y71706D01*
G01X1873483D02*
Y72706D01*
G01Y75223D02*
X1874025Y75306D01*
X1874483Y75431D01*
X1874900Y75598D01*
X1875358Y75806D01*
X1875983Y76139D01*
Y74473D01*
G01X1863423Y71762D02*
X1863673Y71887D01*
X1863965Y71970D01*
X1864298D01*
X1864673Y71845D01*
X1864965Y71637D01*
X1865173Y71387D01*
X1865340Y70970D01*
X1865382Y70595D01*
X1865298Y70220D01*
X1865173Y69970D01*
X1864923Y69720D01*
X1864632Y69553D01*
X1864340Y69470D01*
X1864048D01*
X1863757Y69553D01*
X1863507Y69678D01*
X1863298Y69845D01*
G01X1861240Y69470D02*
X1860948Y69512D01*
X1860615Y69637D01*
X1860407Y69845D01*
X1860323Y70137D01*
X1860407Y70428D01*
X1860657Y70678D01*
X1861032Y70803D01*
X1861448D01*
X1861698Y70887D01*
X1861907Y71095D01*
X1861990Y71387D01*
X1861865Y71678D01*
X1861573Y71887D01*
X1861240Y71970D01*
X1860907Y71887D01*
X1860615Y71678D01*
X1860490Y71387D01*
X1860573Y71095D01*
X1860782Y70887D01*
X1861032Y70803D01*
X1861448D01*
X1861823Y70678D01*
X1862073Y70428D01*
X1862157Y70137D01*
X1862073Y69845D01*
X1861865Y69637D01*
X1861532Y69512D01*
X1861240Y69470D01*
G01X1858932D02*
Y71970D01*
X1857348D01*
G01X1857932Y70762D02*
X1858932D01*
G01X1855957Y69970D02*
X1855707Y69678D01*
X1855373Y69512D01*
X1854998Y69470D01*
X1854665Y69512D01*
X1854332Y69720D01*
X1854123Y69970D01*
X1854082Y70220D01*
X1854165Y70512D01*
X1854457Y70720D01*
X1854748Y70803D01*
X1855123D01*
G01X1854748D02*
X1854498Y70928D01*
X1854290Y71137D01*
X1854207Y71387D01*
X1854290Y71637D01*
X1854498Y71845D01*
X1854873Y71970D01*
X1855248Y71928D01*
X1855623Y71762D01*
G01X1870725Y78256D02*
X1893297D01*
G01X1870725D02*
Y80951D01*
G01Y96256D02*
Y93558D01*
G01X1906089Y93556D02*
Y97118D01*
X1893293D01*
Y93556D01*
G01X1906089Y80956D02*
Y77165D01*
X1893293D01*
Y80956D01*
G01X1882267Y46233D02*
Y44567D01*
X1884767D01*
Y46233D01*
G01X1883559Y45567D02*
Y44567D01*
G01X1884767Y47583D02*
X1882975D01*
X1882600Y47750D01*
X1882350Y48083D01*
X1882267Y48500D01*
X1882350Y48917D01*
X1882600Y49250D01*
X1882975Y49417D01*
X1884767D01*
G01X1884350Y50808D02*
X1884600Y51058D01*
X1884725Y51350D01*
X1884767Y51683D01*
X1884684Y52100D01*
X1884475Y52392D01*
X1884225Y52475D01*
X1883975Y52433D01*
X1883767Y52267D01*
X1883350Y51433D01*
X1883059Y51058D01*
X1882642Y50808D01*
X1882267Y50725D01*
Y52475D01*
G01X1884767Y54700D02*
X1882267D01*
G01X1884767Y53742D02*
Y55658D01*
G01X1882267Y57800D02*
X1884767D01*
X1884267Y57300D01*
G01X1882267D02*
Y58300D01*
G01X1895400Y154900D02*
Y160800D01*
G01X1887300Y149600D02*
X1894100D01*
Y150900D01*
X1895400D01*
G01X1903833Y101292D02*
X1904083Y101417D01*
X1904375Y101500D01*
X1904708D01*
X1905083Y101375D01*
X1905375Y101167D01*
X1905583Y100917D01*
X1905750Y100500D01*
X1905792Y100125D01*
X1905708Y99750D01*
X1905583Y99500D01*
X1905333Y99250D01*
X1905042Y99083D01*
X1904750Y99000D01*
X1904458D01*
X1904167Y99083D01*
X1903917Y99208D01*
X1903708Y99375D01*
G01X1902442Y101083D02*
X1902192Y101333D01*
X1901900Y101458D01*
X1901567Y101500D01*
X1901150Y101417D01*
X1900858Y101208D01*
X1900775Y100958D01*
X1900817Y100708D01*
X1900983Y100500D01*
X1901817Y100083D01*
X1902192Y99792D01*
X1902442Y99375D01*
X1902525Y99000D01*
X1900775D01*
G01X1898550Y101500D02*
Y99000D01*
G01X1899508Y101500D02*
X1897592D01*
G01X1896242Y101083D02*
X1895992Y101333D01*
X1895700Y101458D01*
X1895367Y101500D01*
X1894950Y101417D01*
X1894658Y101208D01*
X1894575Y100958D01*
X1894617Y100708D01*
X1894783Y100500D01*
X1895617Y100083D01*
X1895992Y99792D01*
X1896242Y99375D01*
X1896325Y99000D01*
X1894575D01*
G01X1893142Y101083D02*
X1892892Y101333D01*
X1892600Y101458D01*
X1892267Y101500D01*
X1891850Y101417D01*
X1891558Y101208D01*
X1891475Y100958D01*
X1891517Y100708D01*
X1891683Y100500D01*
X1892517Y100083D01*
X1892892Y99792D01*
X1893142Y99375D01*
X1893225Y99000D01*
X1891475D01*
G01X1851600Y100767D02*
X1854100D01*
Y101808D01*
X1853975Y102142D01*
X1853808Y102350D01*
X1853475Y102433D01*
X1853142Y102350D01*
X1852933Y102100D01*
X1852808Y101808D01*
Y100767D01*
G01Y101808D02*
X1851600Y102433D01*
G01X1853683Y103908D02*
X1853933Y104158D01*
X1854058Y104450D01*
X1854100Y104783D01*
X1854017Y105200D01*
X1853808Y105492D01*
X1853558Y105575D01*
X1853308Y105533D01*
X1853100Y105367D01*
X1852683Y104533D01*
X1852392Y104158D01*
X1851975Y103908D01*
X1851600Y103825D01*
Y105575D01*
G01X1854100Y107800D02*
X1851600D01*
G01X1854100Y106842D02*
Y108758D01*
G01X1853683Y110108D02*
X1853933Y110358D01*
X1854058Y110650D01*
X1854100Y110983D01*
X1854017Y111400D01*
X1853808Y111692D01*
X1853558Y111775D01*
X1853308Y111733D01*
X1853100Y111567D01*
X1852683Y110733D01*
X1852392Y110358D01*
X1851975Y110108D01*
X1851600Y110025D01*
Y111775D01*
G01X1851975Y113083D02*
X1851767Y113333D01*
X1851642Y113625D01*
X1851600Y114000D01*
X1851683Y114375D01*
X1851850Y114667D01*
X1852142Y114875D01*
X1852475Y114917D01*
X1852808Y114833D01*
X1853017Y114625D01*
X1853183Y114333D01*
X1853225Y114042D01*
X1853183Y113750D01*
X1853017Y113375D01*
X1854100Y113500D01*
Y114625D01*
G01X1856003Y146430D02*
Y148930D01*
X1854962D01*
X1854628Y148805D01*
X1854420Y148638D01*
X1854337Y148305D01*
X1854420Y147972D01*
X1854670Y147763D01*
X1854962Y147638D01*
X1856003D01*
G01X1854962D02*
X1854337Y146430D01*
G01X1852070D02*
Y148930D01*
X1852570Y148430D01*
G01Y146430D02*
X1851570D01*
G01X1848970Y148930D02*
Y146430D01*
G01X1849928Y148930D02*
X1848012D01*
G01X1846578Y146722D02*
X1846287Y146513D01*
X1845953Y146430D01*
X1845620Y146513D01*
X1845328Y146763D01*
X1845120Y147138D01*
X1845037Y147513D01*
Y147972D01*
X1845120Y148347D01*
X1845328Y148680D01*
X1845578Y148847D01*
X1845870Y148930D01*
X1846203Y148847D01*
X1846453Y148680D01*
X1846620Y148430D01*
X1846703Y148097D01*
X1846620Y147805D01*
X1846412Y147513D01*
X1846162Y147347D01*
X1845870Y147305D01*
X1845537Y147388D01*
X1845287Y147597D01*
X1845037Y147972D01*
G01X1869554Y153967D02*
Y156467D01*
X1868513D01*
X1868179Y156342D01*
X1867971Y156175D01*
X1867888Y155842D01*
X1867971Y155509D01*
X1868221Y155300D01*
X1868513Y155175D01*
X1869554D01*
G01X1868513D02*
X1867888Y153967D01*
G01X1866329Y154259D02*
X1866038Y154050D01*
X1865704Y153967D01*
X1865371Y154050D01*
X1865079Y154300D01*
X1864871Y154675D01*
X1864788Y155050D01*
Y155509D01*
X1864871Y155884D01*
X1865079Y156217D01*
X1865329Y156384D01*
X1865621Y156467D01*
X1865954Y156384D01*
X1866204Y156217D01*
X1866371Y155967D01*
X1866454Y155634D01*
X1866371Y155342D01*
X1866163Y155050D01*
X1865913Y154884D01*
X1865621Y154842D01*
X1865288Y154925D01*
X1865038Y155134D01*
X1864788Y155509D01*
G01X1863313Y153967D02*
Y156467D01*
X1861729D01*
G01X1862313Y155259D02*
X1863313D01*
G01X1859421Y153967D02*
Y156467D01*
X1859921Y155967D01*
G01Y153967D02*
X1858921D01*
G01X1857113Y156050D02*
X1856863Y156300D01*
X1856571Y156425D01*
X1856238Y156467D01*
X1855821Y156384D01*
X1855529Y156175D01*
X1855446Y155925D01*
X1855488Y155675D01*
X1855654Y155467D01*
X1856488Y155050D01*
X1856863Y154759D01*
X1857113Y154342D01*
X1857196Y153967D01*
X1855446D01*
G01X1864633Y136967D02*
Y139467D01*
X1863592D01*
X1863258Y139342D01*
X1863050Y139175D01*
X1862967Y138842D01*
X1863050Y138509D01*
X1863300Y138300D01*
X1863592Y138175D01*
X1864633D01*
G01X1863592D02*
X1862967Y136967D01*
G01X1860700D02*
Y139467D01*
X1861200Y138967D01*
G01Y136967D02*
X1860200D01*
G01X1857600Y139467D02*
Y136967D01*
G01X1858558Y139467D02*
X1856642D01*
G01X1855417Y137467D02*
X1855167Y137175D01*
X1854833Y137009D01*
X1854458Y136967D01*
X1854125Y137009D01*
X1853792Y137217D01*
X1853583Y137467D01*
X1853542Y137717D01*
X1853625Y138009D01*
X1853917Y138217D01*
X1854208Y138300D01*
X1854583D01*
G01X1854208D02*
X1853958Y138425D01*
X1853750Y138634D01*
X1853667Y138884D01*
X1853750Y139134D01*
X1853958Y139342D01*
X1854333Y139467D01*
X1854708Y139425D01*
X1855083Y139259D01*
G01X1850900Y136967D02*
Y139467D01*
X1852442Y137675D01*
X1850358D01*
G01X1867633Y142067D02*
Y144567D01*
X1866592D01*
X1866258Y144442D01*
X1866050Y144275D01*
X1865967Y143942D01*
X1866050Y143609D01*
X1866300Y143400D01*
X1866592Y143275D01*
X1867633D01*
G01X1866592D02*
X1865967Y142067D01*
G01X1863700D02*
Y144567D01*
X1864200Y144067D01*
G01Y142067D02*
X1863200D01*
G01X1860600Y144567D02*
Y142067D01*
G01X1861558Y144567D02*
X1859642D01*
G01X1858417Y142567D02*
X1858167Y142275D01*
X1857833Y142109D01*
X1857458Y142067D01*
X1857125Y142109D01*
X1856792Y142317D01*
X1856583Y142567D01*
X1856542Y142817D01*
X1856625Y143109D01*
X1856917Y143317D01*
X1857208Y143400D01*
X1857583D01*
G01X1857208D02*
X1856958Y143525D01*
X1856750Y143734D01*
X1856667Y143984D01*
X1856750Y144234D01*
X1856958Y144442D01*
X1857333Y144567D01*
X1857708Y144525D01*
X1858083Y144359D01*
G01X1855317Y142567D02*
X1855067Y142275D01*
X1854733Y142109D01*
X1854358Y142067D01*
X1854025Y142109D01*
X1853692Y142317D01*
X1853483Y142567D01*
X1853442Y142817D01*
X1853525Y143109D01*
X1853817Y143317D01*
X1854108Y143400D01*
X1854483D01*
G01X1854108D02*
X1853858Y143525D01*
X1853650Y143734D01*
X1853567Y143984D01*
X1853650Y144234D01*
X1853858Y144442D01*
X1854233Y144567D01*
X1854608Y144525D01*
X1854983Y144359D01*
G01X1865971Y132795D02*
Y135295D01*
X1864930D01*
X1864596Y135170D01*
X1864388Y135003D01*
X1864305Y134670D01*
X1864388Y134337D01*
X1864638Y134128D01*
X1864930Y134003D01*
X1865971D01*
G01X1864930D02*
X1864305Y132795D01*
G01X1862830Y134878D02*
X1862580Y135128D01*
X1862288Y135253D01*
X1861955Y135295D01*
X1861538Y135212D01*
X1861246Y135003D01*
X1861163Y134753D01*
X1861205Y134503D01*
X1861371Y134295D01*
X1862205Y133878D01*
X1862580Y133587D01*
X1862830Y133170D01*
X1862913Y132795D01*
X1861163D01*
G01X1858938Y135295D02*
Y132795D01*
G01X1859896Y135295D02*
X1857980D01*
G01X1856755Y133170D02*
X1856505Y132962D01*
X1856213Y132837D01*
X1855838Y132795D01*
X1855463Y132878D01*
X1855171Y133045D01*
X1854963Y133337D01*
X1854921Y133670D01*
X1855005Y134003D01*
X1855213Y134212D01*
X1855505Y134378D01*
X1855796Y134420D01*
X1856088Y134378D01*
X1856463Y134212D01*
X1856338Y135295D01*
X1855213D01*
G01X1853530Y134878D02*
X1853280Y135128D01*
X1852988Y135253D01*
X1852655Y135295D01*
X1852238Y135212D01*
X1851946Y135003D01*
X1851863Y134753D01*
X1851905Y134503D01*
X1852071Y134295D01*
X1852905Y133878D01*
X1853280Y133587D01*
X1853530Y133170D01*
X1853613Y132795D01*
X1851863D01*
G01X1896376Y146547D02*
X1898876D01*
Y147588D01*
X1898751Y147922D01*
X1898584Y148130D01*
X1898251Y148213D01*
X1897918Y148130D01*
X1897709Y147880D01*
X1897584Y147588D01*
Y146547D01*
G01Y147588D02*
X1896376Y148213D01*
G01Y150480D02*
X1898876D01*
X1898376Y149980D01*
G01X1896376D02*
Y150980D01*
G01X1898876Y153580D02*
X1896376D01*
G01X1898876Y152622D02*
Y154538D01*
G01X1896876Y155763D02*
X1896584Y156013D01*
X1896418Y156347D01*
X1896376Y156722D01*
X1896418Y157055D01*
X1896626Y157388D01*
X1896876Y157597D01*
X1897126Y157638D01*
X1897418Y157555D01*
X1897626Y157263D01*
X1897709Y156972D01*
Y156597D01*
G01Y156972D02*
X1897834Y157222D01*
X1898043Y157430D01*
X1898293Y157513D01*
X1898543Y157430D01*
X1898751Y157222D01*
X1898876Y156847D01*
X1898834Y156472D01*
X1898668Y156097D01*
G01X1898459Y158988D02*
X1898709Y159238D01*
X1898834Y159530D01*
X1898876Y159863D01*
X1898793Y160280D01*
X1898584Y160572D01*
X1898334Y160655D01*
X1898084Y160613D01*
X1897876Y160447D01*
X1897459Y159613D01*
X1897168Y159238D01*
X1896751Y158988D01*
X1896376Y158905D01*
Y160655D01*
G01X1843664Y98367D02*
X1846164D01*
Y99408D01*
X1846039Y99742D01*
X1845872Y99950D01*
X1845539Y100033D01*
X1845206Y99950D01*
X1844997Y99700D01*
X1844872Y99408D01*
Y98367D01*
G01Y99408D02*
X1843664Y100033D01*
G01X1845747Y101508D02*
X1845997Y101758D01*
X1846122Y102050D01*
X1846164Y102383D01*
X1846081Y102800D01*
X1845872Y103092D01*
X1845622Y103175D01*
X1845372Y103133D01*
X1845164Y102967D01*
X1844747Y102133D01*
X1844456Y101758D01*
X1844039Y101508D01*
X1843664Y101425D01*
Y103175D01*
G01X1846164Y105400D02*
X1843664D01*
G01X1846164Y104442D02*
Y106358D01*
G01X1845747Y107708D02*
X1845997Y107958D01*
X1846122Y108250D01*
X1846164Y108583D01*
X1846081Y109000D01*
X1845872Y109292D01*
X1845622Y109375D01*
X1845372Y109333D01*
X1845164Y109167D01*
X1844747Y108333D01*
X1844456Y107958D01*
X1844039Y107708D01*
X1843664Y107625D01*
Y109375D01*
G01X1844164Y110683D02*
X1843872Y110933D01*
X1843706Y111267D01*
X1843664Y111642D01*
X1843706Y111975D01*
X1843914Y112308D01*
X1844164Y112517D01*
X1844414Y112558D01*
X1844706Y112475D01*
X1844914Y112183D01*
X1844997Y111892D01*
Y111517D01*
G01Y111892D02*
X1845122Y112142D01*
X1845331Y112350D01*
X1845581Y112433D01*
X1845831Y112350D01*
X1846039Y112142D01*
X1846164Y111767D01*
X1846122Y111392D01*
X1845956Y111017D01*
G01X1862525Y101626D02*
X1865025D01*
Y102667D01*
X1864900Y103001D01*
X1864733Y103209D01*
X1864400Y103292D01*
X1864067Y103209D01*
X1863858Y102959D01*
X1863733Y102667D01*
Y101626D01*
G01Y102667D02*
X1862525Y103292D01*
G01X1864608Y104767D02*
X1864858Y105017D01*
X1864983Y105309D01*
X1865025Y105642D01*
X1864942Y106059D01*
X1864733Y106351D01*
X1864483Y106434D01*
X1864233Y106392D01*
X1864025Y106226D01*
X1863608Y105392D01*
X1863317Y105017D01*
X1862900Y104767D01*
X1862525Y104684D01*
Y106434D01*
G01X1865025Y108659D02*
X1862525D01*
G01X1865025Y107701D02*
Y109617D01*
G01X1864608Y110967D02*
X1864858Y111217D01*
X1864983Y111509D01*
X1865025Y111842D01*
X1864942Y112259D01*
X1864733Y112551D01*
X1864483Y112634D01*
X1864233Y112592D01*
X1864025Y112426D01*
X1863608Y111592D01*
X1863317Y111217D01*
X1862900Y110967D01*
X1862525Y110884D01*
Y112634D01*
G01Y114859D02*
X1865025D01*
X1864525Y114359D01*
G01X1862525D02*
Y115359D01*
G01X1839212Y152177D02*
X1839337Y151927D01*
X1839420Y151635D01*
Y151302D01*
X1839295Y150927D01*
X1839087Y150635D01*
X1838837Y150427D01*
X1838420Y150260D01*
X1838045Y150218D01*
X1837670Y150302D01*
X1837420Y150427D01*
X1837170Y150677D01*
X1837003Y150968D01*
X1836920Y151260D01*
Y151552D01*
X1837003Y151843D01*
X1837128Y152093D01*
X1837295Y152302D01*
G01X1837212Y153652D02*
X1837003Y153943D01*
X1836920Y154277D01*
X1837003Y154610D01*
X1837253Y154902D01*
X1837628Y155110D01*
X1838003Y155193D01*
X1838462D01*
X1838837Y155110D01*
X1839170Y154902D01*
X1839337Y154652D01*
X1839420Y154360D01*
X1839337Y154027D01*
X1839170Y153777D01*
X1838920Y153610D01*
X1838587Y153527D01*
X1838295Y153610D01*
X1838003Y153818D01*
X1837837Y154068D01*
X1837795Y154360D01*
X1837878Y154693D01*
X1838087Y154943D01*
X1838462Y155193D01*
G01X1839420Y156210D02*
X1836920Y156793D01*
X1839420Y157460D01*
X1836920Y158127D01*
X1839420Y158710D01*
G01X1836920Y160560D02*
X1839420D01*
X1838920Y160060D01*
G01X1836920D02*
Y161060D01*
G01Y163577D02*
X1837462Y163660D01*
X1837920Y163785D01*
X1838337Y163952D01*
X1838795Y164160D01*
X1839420Y164493D01*
Y162827D01*
G01X1864740Y131279D02*
X1864990Y131404D01*
X1865282Y131487D01*
X1865615D01*
X1865990Y131362D01*
X1866282Y131154D01*
X1866490Y130904D01*
X1866657Y130487D01*
X1866699Y130112D01*
X1866615Y129737D01*
X1866490Y129487D01*
X1866240Y129237D01*
X1865949Y129070D01*
X1865657Y128987D01*
X1865365D01*
X1865074Y129070D01*
X1864824Y129195D01*
X1864615Y129362D01*
G01X1863349Y131070D02*
X1863099Y131320D01*
X1862807Y131445D01*
X1862474Y131487D01*
X1862057Y131404D01*
X1861765Y131195D01*
X1861682Y130945D01*
X1861724Y130695D01*
X1861890Y130487D01*
X1862724Y130070D01*
X1863099Y129779D01*
X1863349Y129362D01*
X1863432Y128987D01*
X1861682D01*
G01X1859457Y131487D02*
Y128987D01*
G01X1860415Y131487D02*
X1858499D01*
G01X1857274Y129487D02*
X1857024Y129195D01*
X1856690Y129029D01*
X1856315Y128987D01*
X1855982Y129029D01*
X1855649Y129237D01*
X1855440Y129487D01*
X1855399Y129737D01*
X1855482Y130029D01*
X1855774Y130237D01*
X1856065Y130320D01*
X1856440D01*
G01X1856065D02*
X1855815Y130445D01*
X1855607Y130654D01*
X1855524Y130904D01*
X1855607Y131154D01*
X1855815Y131362D01*
X1856190Y131487D01*
X1856565Y131445D01*
X1856940Y131279D01*
G01X1853340Y128987D02*
X1853257Y129529D01*
X1853132Y129987D01*
X1852965Y130404D01*
X1852757Y130862D01*
X1852424Y131487D01*
X1854090D01*
G01X1904883Y135459D02*
X1905133Y135584D01*
X1905425Y135667D01*
X1905758D01*
X1906133Y135542D01*
X1906425Y135334D01*
X1906633Y135084D01*
X1906800Y134667D01*
X1906842Y134292D01*
X1906758Y133917D01*
X1906633Y133667D01*
X1906383Y133417D01*
X1906092Y133250D01*
X1905800Y133167D01*
X1905508D01*
X1905217Y133250D01*
X1904967Y133375D01*
X1904758Y133542D01*
G01X1903492Y135250D02*
X1903242Y135500D01*
X1902950Y135625D01*
X1902617Y135667D01*
X1902200Y135584D01*
X1901908Y135375D01*
X1901825Y135125D01*
X1901867Y134875D01*
X1902033Y134667D01*
X1902867Y134250D01*
X1903242Y133959D01*
X1903492Y133542D01*
X1903575Y133167D01*
X1901825D01*
G01X1899600Y135667D02*
Y133167D01*
G01X1900558Y135667D02*
X1898642D01*
G01X1897292Y135250D02*
X1897042Y135500D01*
X1896750Y135625D01*
X1896417Y135667D01*
X1896000Y135584D01*
X1895708Y135375D01*
X1895625Y135125D01*
X1895667Y134875D01*
X1895833Y134667D01*
X1896667Y134250D01*
X1897042Y133959D01*
X1897292Y133542D01*
X1897375Y133167D01*
X1895625D01*
G01X1893400D02*
X1893108Y133209D01*
X1892775Y133334D01*
X1892567Y133542D01*
X1892483Y133834D01*
X1892567Y134125D01*
X1892817Y134375D01*
X1893192Y134500D01*
X1893608D01*
X1893858Y134584D01*
X1894067Y134792D01*
X1894150Y135084D01*
X1894025Y135375D01*
X1893733Y135584D01*
X1893400Y135667D01*
X1893067Y135584D01*
X1892775Y135375D01*
X1892650Y135084D01*
X1892733Y134792D01*
X1892942Y134584D01*
X1893192Y134500D01*
X1893608D01*
X1893983Y134375D01*
X1894233Y134125D01*
X1894317Y133834D01*
X1894233Y133542D01*
X1894025Y133334D01*
X1893692Y133209D01*
X1893400Y133167D01*
G01X1865312Y127078D02*
X1865562Y127203D01*
X1865854Y127286D01*
X1866187D01*
X1866562Y127161D01*
X1866854Y126953D01*
X1867062Y126703D01*
X1867229Y126286D01*
X1867271Y125911D01*
X1867187Y125536D01*
X1867062Y125286D01*
X1866812Y125036D01*
X1866521Y124869D01*
X1866229Y124786D01*
X1865937D01*
X1865646Y124869D01*
X1865396Y124994D01*
X1865187Y125161D01*
G01X1863921Y126869D02*
X1863671Y127119D01*
X1863379Y127244D01*
X1863046Y127286D01*
X1862629Y127203D01*
X1862337Y126994D01*
X1862254Y126744D01*
X1862296Y126494D01*
X1862462Y126286D01*
X1863296Y125869D01*
X1863671Y125578D01*
X1863921Y125161D01*
X1864004Y124786D01*
X1862254D01*
G01X1860029Y127286D02*
Y124786D01*
G01X1860987Y127286D02*
X1859071D01*
G01X1857846Y125286D02*
X1857596Y124994D01*
X1857262Y124828D01*
X1856887Y124786D01*
X1856554Y124828D01*
X1856221Y125036D01*
X1856012Y125286D01*
X1855971Y125536D01*
X1856054Y125828D01*
X1856346Y126036D01*
X1856637Y126119D01*
X1857012D01*
G01X1856637D02*
X1856387Y126244D01*
X1856179Y126453D01*
X1856096Y126703D01*
X1856179Y126953D01*
X1856387Y127161D01*
X1856762Y127286D01*
X1857137Y127244D01*
X1857512Y127078D01*
G01X1853329Y124786D02*
Y127286D01*
X1854871Y125494D01*
X1852787D01*
G01X1863773Y122172D02*
X1864023Y122297D01*
X1864315Y122380D01*
X1864648D01*
X1865023Y122255D01*
X1865315Y122047D01*
X1865523Y121797D01*
X1865690Y121380D01*
X1865732Y121005D01*
X1865648Y120630D01*
X1865523Y120380D01*
X1865273Y120130D01*
X1864982Y119963D01*
X1864690Y119880D01*
X1864398D01*
X1864107Y119963D01*
X1863857Y120088D01*
X1863648Y120255D01*
G01X1862382Y121963D02*
X1862132Y122213D01*
X1861840Y122338D01*
X1861507Y122380D01*
X1861090Y122297D01*
X1860798Y122088D01*
X1860715Y121838D01*
X1860757Y121588D01*
X1860923Y121380D01*
X1861757Y120963D01*
X1862132Y120672D01*
X1862382Y120255D01*
X1862465Y119880D01*
X1860715D01*
G01X1858490Y122380D02*
Y119880D01*
G01X1859448Y122380D02*
X1857532D01*
G01X1856307Y120380D02*
X1856057Y120088D01*
X1855723Y119922D01*
X1855348Y119880D01*
X1855015Y119922D01*
X1854682Y120130D01*
X1854473Y120380D01*
X1854432Y120630D01*
X1854515Y120922D01*
X1854807Y121130D01*
X1855098Y121213D01*
X1855473D01*
G01X1855098D02*
X1854848Y121338D01*
X1854640Y121547D01*
X1854557Y121797D01*
X1854640Y122047D01*
X1854848Y122255D01*
X1855223Y122380D01*
X1855598Y122338D01*
X1855973Y122172D01*
G01X1852290Y119880D02*
Y122380D01*
X1852790Y121880D01*
G01Y119880D02*
X1851790D01*
G01X1863773Y118672D02*
X1864023Y118797D01*
X1864315Y118880D01*
X1864648D01*
X1865023Y118755D01*
X1865315Y118547D01*
X1865523Y118297D01*
X1865690Y117880D01*
X1865732Y117505D01*
X1865648Y117130D01*
X1865523Y116880D01*
X1865273Y116630D01*
X1864982Y116463D01*
X1864690Y116380D01*
X1864398D01*
X1864107Y116463D01*
X1863857Y116588D01*
X1863648Y116755D01*
G01X1862382Y118463D02*
X1862132Y118713D01*
X1861840Y118838D01*
X1861507Y118880D01*
X1861090Y118797D01*
X1860798Y118588D01*
X1860715Y118338D01*
X1860757Y118088D01*
X1860923Y117880D01*
X1861757Y117463D01*
X1862132Y117172D01*
X1862382Y116755D01*
X1862465Y116380D01*
X1860715D01*
G01X1858490Y118880D02*
Y116380D01*
G01X1859448Y118880D02*
X1857532D01*
G01X1856182Y118463D02*
X1855932Y118713D01*
X1855640Y118838D01*
X1855307Y118880D01*
X1854890Y118797D01*
X1854598Y118588D01*
X1854515Y118338D01*
X1854557Y118088D01*
X1854723Y117880D01*
X1855557Y117463D01*
X1855932Y117172D01*
X1856182Y116755D01*
X1856265Y116380D01*
X1854515D01*
G01X1852373D02*
X1852290Y116922D01*
X1852165Y117380D01*
X1851998Y117797D01*
X1851790Y118255D01*
X1851457Y118880D01*
X1853123D01*
G01X1849956Y100117D02*
X1850081Y99867D01*
X1850164Y99575D01*
Y99242D01*
X1850039Y98867D01*
X1849831Y98575D01*
X1849581Y98367D01*
X1849164Y98200D01*
X1848789Y98158D01*
X1848414Y98242D01*
X1848164Y98367D01*
X1847914Y98617D01*
X1847747Y98908D01*
X1847664Y99200D01*
Y99492D01*
X1847747Y99783D01*
X1847872Y100033D01*
X1848039Y100242D01*
G01X1849747Y101508D02*
X1849997Y101758D01*
X1850122Y102050D01*
X1850164Y102383D01*
X1850081Y102800D01*
X1849872Y103092D01*
X1849622Y103175D01*
X1849372Y103133D01*
X1849164Y102967D01*
X1848747Y102133D01*
X1848456Y101758D01*
X1848039Y101508D01*
X1847664Y101425D01*
Y103175D01*
G01X1850164Y105400D02*
X1847664D01*
G01X1850164Y104442D02*
Y106358D01*
G01X1847664Y108500D02*
X1850164D01*
X1849664Y108000D01*
G01X1847664D02*
Y109000D01*
G01Y111517D02*
X1848206Y111600D01*
X1848664Y111725D01*
X1849081Y111892D01*
X1849539Y112100D01*
X1850164Y112433D01*
Y110767D01*
G01X1887293Y125301D02*
X1887543Y125426D01*
X1887835Y125509D01*
X1888168D01*
X1888543Y125384D01*
X1888835Y125176D01*
X1889043Y124926D01*
X1889210Y124509D01*
X1889252Y124134D01*
X1889168Y123759D01*
X1889043Y123509D01*
X1888793Y123259D01*
X1888502Y123092D01*
X1888210Y123009D01*
X1887918D01*
X1887627Y123092D01*
X1887377Y123217D01*
X1887168Y123384D01*
G01X1885902Y125092D02*
X1885652Y125342D01*
X1885360Y125467D01*
X1885027Y125509D01*
X1884610Y125426D01*
X1884318Y125217D01*
X1884235Y124967D01*
X1884277Y124717D01*
X1884443Y124509D01*
X1885277Y124092D01*
X1885652Y123801D01*
X1885902Y123384D01*
X1885985Y123009D01*
X1884235D01*
G01X1882010Y125509D02*
Y123009D01*
G01X1882968Y125509D02*
X1881052D01*
G01X1879827Y123509D02*
X1879577Y123217D01*
X1879243Y123051D01*
X1878868Y123009D01*
X1878535Y123051D01*
X1878202Y123259D01*
X1877993Y123509D01*
X1877952Y123759D01*
X1878035Y124051D01*
X1878327Y124259D01*
X1878618Y124342D01*
X1878993D01*
G01X1878618D02*
X1878368Y124467D01*
X1878160Y124676D01*
X1878077Y124926D01*
X1878160Y125176D01*
X1878368Y125384D01*
X1878743Y125509D01*
X1879118Y125467D01*
X1879493Y125301D01*
G01X1875810Y125509D02*
X1876143Y125426D01*
X1876393Y125217D01*
X1876560Y124967D01*
X1876685Y124634D01*
X1876727Y124259D01*
X1876685Y123884D01*
X1876560Y123551D01*
X1876393Y123301D01*
X1876143Y123092D01*
X1875810Y123009D01*
X1875477Y123092D01*
X1875227Y123301D01*
X1875060Y123551D01*
X1874935Y123884D01*
X1874893Y124259D01*
X1874935Y124634D01*
X1875060Y124967D01*
X1875227Y125217D01*
X1875477Y125426D01*
X1875810Y125509D01*
G01X1885933Y119581D02*
X1886183Y119706D01*
X1886475Y119789D01*
X1886808D01*
X1887183Y119664D01*
X1887475Y119456D01*
X1887683Y119206D01*
X1887850Y118789D01*
X1887892Y118414D01*
X1887808Y118039D01*
X1887683Y117789D01*
X1887433Y117539D01*
X1887142Y117372D01*
X1886850Y117289D01*
X1886558D01*
X1886267Y117372D01*
X1886017Y117497D01*
X1885808Y117664D01*
G01X1884542Y119372D02*
X1884292Y119622D01*
X1884000Y119747D01*
X1883667Y119789D01*
X1883250Y119706D01*
X1882958Y119497D01*
X1882875Y119247D01*
X1882917Y118997D01*
X1883083Y118789D01*
X1883917Y118372D01*
X1884292Y118081D01*
X1884542Y117664D01*
X1884625Y117289D01*
X1882875D01*
G01X1880650Y119789D02*
Y117289D01*
G01X1881608Y119789D02*
X1879692D01*
G01X1878342Y119372D02*
X1878092Y119622D01*
X1877800Y119747D01*
X1877467Y119789D01*
X1877050Y119706D01*
X1876758Y119497D01*
X1876675Y119247D01*
X1876717Y118997D01*
X1876883Y118789D01*
X1877717Y118372D01*
X1878092Y118081D01*
X1878342Y117664D01*
X1878425Y117289D01*
X1876675D01*
G01X1875367Y117664D02*
X1875117Y117456D01*
X1874825Y117331D01*
X1874450Y117289D01*
X1874075Y117372D01*
X1873783Y117539D01*
X1873575Y117831D01*
X1873533Y118164D01*
X1873617Y118497D01*
X1873825Y118706D01*
X1874117Y118872D01*
X1874408Y118914D01*
X1874700Y118872D01*
X1875075Y118706D01*
X1874950Y119789D01*
X1873825D01*
G01X1861092Y97217D02*
X1861217Y96967D01*
X1861300Y96675D01*
Y96342D01*
X1861175Y95967D01*
X1860967Y95675D01*
X1860717Y95467D01*
X1860300Y95300D01*
X1859925Y95258D01*
X1859550Y95342D01*
X1859300Y95467D01*
X1859050Y95717D01*
X1858883Y96008D01*
X1858800Y96300D01*
Y96592D01*
X1858883Y96883D01*
X1859008Y97133D01*
X1859175Y97342D01*
G01X1860883Y98608D02*
X1861133Y98858D01*
X1861258Y99150D01*
X1861300Y99483D01*
X1861217Y99900D01*
X1861008Y100192D01*
X1860758Y100275D01*
X1860508Y100233D01*
X1860300Y100067D01*
X1859883Y99233D01*
X1859592Y98858D01*
X1859175Y98608D01*
X1858800Y98525D01*
Y100275D01*
G01X1861300Y102500D02*
X1858800D01*
G01X1861300Y101542D02*
Y103458D01*
G01X1858800Y105600D02*
X1861300D01*
X1860800Y105100D01*
G01X1858800D02*
Y106100D01*
G01X1859092Y107992D02*
X1858883Y108283D01*
X1858800Y108617D01*
X1858883Y108950D01*
X1859133Y109242D01*
X1859508Y109450D01*
X1859883Y109533D01*
X1860342D01*
X1860717Y109450D01*
X1861050Y109242D01*
X1861217Y108992D01*
X1861300Y108700D01*
X1861217Y108367D01*
X1861050Y108117D01*
X1860800Y107950D01*
X1860467Y107867D01*
X1860175Y107950D01*
X1859883Y108158D01*
X1859717Y108408D01*
X1859675Y108700D01*
X1859758Y109033D01*
X1859967Y109283D01*
X1860342Y109533D01*
G01X1857537Y100375D02*
X1857662Y100125D01*
X1857745Y99833D01*
Y99500D01*
X1857620Y99125D01*
X1857412Y98833D01*
X1857162Y98625D01*
X1856745Y98458D01*
X1856370Y98416D01*
X1855995Y98500D01*
X1855745Y98625D01*
X1855495Y98875D01*
X1855328Y99166D01*
X1855245Y99458D01*
Y99750D01*
X1855328Y100041D01*
X1855453Y100291D01*
X1855620Y100500D01*
G01X1857328Y101766D02*
X1857578Y102016D01*
X1857703Y102308D01*
X1857745Y102641D01*
X1857662Y103058D01*
X1857453Y103350D01*
X1857203Y103433D01*
X1856953Y103391D01*
X1856745Y103225D01*
X1856328Y102391D01*
X1856037Y102016D01*
X1855620Y101766D01*
X1855245Y101683D01*
Y103433D01*
G01X1857745Y105658D02*
X1855245D01*
G01X1857745Y104700D02*
Y106616D01*
G01X1855245Y108758D02*
X1857745D01*
X1857245Y108258D01*
G01X1855245D02*
Y109258D01*
G01Y111858D02*
X1855287Y112150D01*
X1855412Y112483D01*
X1855620Y112691D01*
X1855912Y112775D01*
X1856203Y112691D01*
X1856453Y112441D01*
X1856578Y112066D01*
Y111650D01*
X1856662Y111400D01*
X1856870Y111191D01*
X1857162Y111108D01*
X1857453Y111233D01*
X1857662Y111525D01*
X1857745Y111858D01*
X1857662Y112191D01*
X1857453Y112483D01*
X1857162Y112608D01*
X1856870Y112525D01*
X1856662Y112316D01*
X1856578Y112066D01*
Y111650D01*
X1856453Y111275D01*
X1856203Y111025D01*
X1855912Y110941D01*
X1855620Y111025D01*
X1855412Y111233D01*
X1855287Y111566D01*
X1855245Y111858D01*
G01X1875383Y100092D02*
X1875633Y100217D01*
X1875925Y100300D01*
X1876258D01*
X1876633Y100175D01*
X1876925Y99967D01*
X1877133Y99717D01*
X1877300Y99300D01*
X1877342Y98925D01*
X1877258Y98550D01*
X1877133Y98300D01*
X1876883Y98050D01*
X1876592Y97883D01*
X1876300Y97800D01*
X1876008D01*
X1875717Y97883D01*
X1875467Y98008D01*
X1875258Y98175D01*
G01X1873200Y97800D02*
Y100300D01*
X1873700Y99800D01*
G01Y97800D02*
X1872700D01*
G01X1870933D02*
Y100300D01*
X1869892D01*
X1869558Y100175D01*
X1869350Y100008D01*
X1869267Y99675D01*
X1869350Y99342D01*
X1869600Y99133D01*
X1869892Y99008D01*
X1870933D01*
G01X1869892D02*
X1869267Y97800D01*
G01X1867792Y99883D02*
X1867542Y100133D01*
X1867250Y100258D01*
X1866917Y100300D01*
X1866500Y100217D01*
X1866208Y100008D01*
X1866125Y99758D01*
X1866167Y99508D01*
X1866333Y99300D01*
X1867167Y98883D01*
X1867542Y98592D01*
X1867792Y98175D01*
X1867875Y97800D01*
X1866125D01*
G01X1864817Y98300D02*
X1864567Y98008D01*
X1864233Y97842D01*
X1863858Y97800D01*
X1863525Y97842D01*
X1863192Y98050D01*
X1862983Y98300D01*
X1862942Y98550D01*
X1863025Y98842D01*
X1863317Y99050D01*
X1863608Y99133D01*
X1863983D01*
G01X1863608D02*
X1863358Y99258D01*
X1863150Y99467D01*
X1863067Y99717D01*
X1863150Y99967D01*
X1863358Y100175D01*
X1863733Y100300D01*
X1864108Y100258D01*
X1864483Y100092D01*
G01X1870725Y96256D02*
X1893300D01*
G01X1886600Y177000D02*
Y174500D01*
G01X1886500Y181200D02*
Y188300D01*
X1892400D01*
Y197500D01*
X1903900D01*
Y194300D01*
X1913900D01*
Y192101D01*
X1913901Y192100D01*
X1919400D01*
Y196600D01*
X1922831D01*
G01X1886600Y165000D02*
Y162500D01*
G01X1882183Y217015D02*
Y219515D01*
X1881142D01*
X1880808Y219390D01*
X1880600Y219223D01*
X1880517Y218890D01*
X1880600Y218557D01*
X1880850Y218348D01*
X1881142Y218223D01*
X1882183D01*
G01X1881142D02*
X1880517Y217015D01*
G01X1878250D02*
X1877958Y217057D01*
X1877625Y217182D01*
X1877417Y217390D01*
X1877333Y217682D01*
X1877417Y217973D01*
X1877667Y218223D01*
X1878042Y218348D01*
X1878458D01*
X1878708Y218432D01*
X1878917Y218640D01*
X1879000Y218932D01*
X1878875Y219223D01*
X1878583Y219432D01*
X1878250Y219515D01*
X1877917Y219432D01*
X1877625Y219223D01*
X1877500Y218932D01*
X1877583Y218640D01*
X1877792Y218432D01*
X1878042Y218348D01*
X1878458D01*
X1878833Y218223D01*
X1879083Y217973D01*
X1879167Y217682D01*
X1879083Y217390D01*
X1878875Y217182D01*
X1878542Y217057D01*
X1878250Y217015D01*
G01X1874317D02*
X1875983D01*
Y219515D01*
X1874317D01*
G01X1874983Y218307D02*
X1875983D01*
G01X1872842Y219098D02*
X1872592Y219348D01*
X1872300Y219473D01*
X1871967Y219515D01*
X1871550Y219432D01*
X1871258Y219223D01*
X1871175Y218973D01*
X1871217Y218723D01*
X1871383Y218515D01*
X1872217Y218098D01*
X1872592Y217807D01*
X1872842Y217390D01*
X1872925Y217015D01*
X1871175D01*
G01X1868950D02*
X1868658Y217057D01*
X1868325Y217182D01*
X1868117Y217390D01*
X1868033Y217682D01*
X1868117Y217973D01*
X1868367Y218223D01*
X1868742Y218348D01*
X1869158D01*
X1869408Y218432D01*
X1869617Y218640D01*
X1869700Y218932D01*
X1869575Y219223D01*
X1869283Y219432D01*
X1868950Y219515D01*
X1868617Y219432D01*
X1868325Y219223D01*
X1868200Y218932D01*
X1868283Y218640D01*
X1868492Y218432D01*
X1868742Y218348D01*
X1869158D01*
X1869533Y218223D01*
X1869783Y217973D01*
X1869867Y217682D01*
X1869783Y217390D01*
X1869575Y217182D01*
X1869242Y217057D01*
X1868950Y217015D01*
G01X1866233Y217600D02*
Y220100D01*
X1865192D01*
X1864858Y219975D01*
X1864650Y219808D01*
X1864567Y219475D01*
X1864650Y219142D01*
X1864900Y218933D01*
X1865192Y218808D01*
X1866233D01*
G01X1865192D02*
X1864567Y217600D01*
G01X1862300D02*
X1862008Y217642D01*
X1861675Y217767D01*
X1861467Y217975D01*
X1861383Y218267D01*
X1861467Y218558D01*
X1861717Y218808D01*
X1862092Y218933D01*
X1862508D01*
X1862758Y219017D01*
X1862967Y219225D01*
X1863050Y219517D01*
X1862925Y219808D01*
X1862633Y220017D01*
X1862300Y220100D01*
X1861967Y220017D01*
X1861675Y219808D01*
X1861550Y219517D01*
X1861633Y219225D01*
X1861842Y219017D01*
X1862092Y218933D01*
X1862508D01*
X1862883Y218808D01*
X1863133Y218558D01*
X1863217Y218267D01*
X1863133Y217975D01*
X1862925Y217767D01*
X1862592Y217642D01*
X1862300Y217600D01*
G01X1858367D02*
X1860033D01*
Y220100D01*
X1858367D01*
G01X1859033Y218892D02*
X1860033D01*
G01X1856892Y219683D02*
X1856642Y219933D01*
X1856350Y220058D01*
X1856017Y220100D01*
X1855600Y220017D01*
X1855308Y219808D01*
X1855225Y219558D01*
X1855267Y219308D01*
X1855433Y219100D01*
X1856267Y218683D01*
X1856642Y218392D01*
X1856892Y217975D01*
X1856975Y217600D01*
X1855225D01*
G01X1853000D02*
Y220100D01*
X1853500Y219600D01*
G01Y217600D02*
X1852500D01*
G01X1881883Y213015D02*
Y215515D01*
X1880842D01*
X1880508Y215390D01*
X1880300Y215223D01*
X1880217Y214890D01*
X1880300Y214557D01*
X1880550Y214348D01*
X1880842Y214223D01*
X1881883D01*
G01X1880842D02*
X1880217Y213015D01*
G01X1877950D02*
X1877658Y213057D01*
X1877325Y213182D01*
X1877117Y213390D01*
X1877033Y213682D01*
X1877117Y213973D01*
X1877367Y214223D01*
X1877742Y214348D01*
X1878158D01*
X1878408Y214432D01*
X1878617Y214640D01*
X1878700Y214932D01*
X1878575Y215223D01*
X1878283Y215432D01*
X1877950Y215515D01*
X1877617Y215432D01*
X1877325Y215223D01*
X1877200Y214932D01*
X1877283Y214640D01*
X1877492Y214432D01*
X1877742Y214348D01*
X1878158D01*
X1878533Y214223D01*
X1878783Y213973D01*
X1878867Y213682D01*
X1878783Y213390D01*
X1878575Y213182D01*
X1878242Y213057D01*
X1877950Y213015D01*
G01X1874017D02*
X1875683D01*
Y215515D01*
X1874017D01*
G01X1874683Y214307D02*
X1875683D01*
G01X1872542Y215098D02*
X1872292Y215348D01*
X1872000Y215473D01*
X1871667Y215515D01*
X1871250Y215432D01*
X1870958Y215223D01*
X1870875Y214973D01*
X1870917Y214723D01*
X1871083Y214515D01*
X1871917Y214098D01*
X1872292Y213807D01*
X1872542Y213390D01*
X1872625Y213015D01*
X1870875D01*
G01X1868733D02*
X1868650Y213557D01*
X1868525Y214015D01*
X1868358Y214432D01*
X1868150Y214890D01*
X1867817Y215515D01*
X1869483D01*
G01X1885033Y204367D02*
Y206867D01*
X1883992D01*
X1883658Y206742D01*
X1883450Y206575D01*
X1883367Y206242D01*
X1883450Y205909D01*
X1883700Y205700D01*
X1883992Y205575D01*
X1885033D01*
G01X1883992D02*
X1883367Y204367D01*
G01X1881100D02*
X1880808Y204409D01*
X1880475Y204534D01*
X1880267Y204742D01*
X1880183Y205034D01*
X1880267Y205325D01*
X1880517Y205575D01*
X1880892Y205700D01*
X1881308D01*
X1881558Y205784D01*
X1881767Y205992D01*
X1881850Y206284D01*
X1881725Y206575D01*
X1881433Y206784D01*
X1881100Y206867D01*
X1880767Y206784D01*
X1880475Y206575D01*
X1880350Y206284D01*
X1880433Y205992D01*
X1880642Y205784D01*
X1880892Y205700D01*
X1881308D01*
X1881683Y205575D01*
X1881933Y205325D01*
X1882017Y205034D01*
X1881933Y204742D01*
X1881725Y204534D01*
X1881392Y204409D01*
X1881100Y204367D01*
G01X1877167D02*
X1878833D01*
Y206867D01*
X1877167D01*
G01X1877833Y205659D02*
X1878833D01*
G01X1874900Y204367D02*
Y206867D01*
X1875400Y206367D01*
G01Y204367D02*
X1874400D01*
G01X1871883D02*
X1871800Y204909D01*
X1871675Y205367D01*
X1871508Y205784D01*
X1871300Y206242D01*
X1870967Y206867D01*
X1872633D01*
G01X1867066Y207325D02*
Y209825D01*
X1866025D01*
X1865691Y209700D01*
X1865483Y209533D01*
X1865400Y209200D01*
X1865483Y208867D01*
X1865733Y208658D01*
X1866025Y208533D01*
X1867066D01*
G01X1866025D02*
X1865400Y207325D01*
G01X1863133D02*
X1862841Y207367D01*
X1862508Y207492D01*
X1862300Y207700D01*
X1862216Y207992D01*
X1862300Y208283D01*
X1862550Y208533D01*
X1862925Y208658D01*
X1863341D01*
X1863591Y208742D01*
X1863800Y208950D01*
X1863883Y209242D01*
X1863758Y209533D01*
X1863466Y209742D01*
X1863133Y209825D01*
X1862800Y209742D01*
X1862508Y209533D01*
X1862383Y209242D01*
X1862466Y208950D01*
X1862675Y208742D01*
X1862925Y208658D01*
X1863341D01*
X1863716Y208533D01*
X1863966Y208283D01*
X1864050Y207992D01*
X1863966Y207700D01*
X1863758Y207492D01*
X1863425Y207367D01*
X1863133Y207325D01*
G01X1859200D02*
X1860866D01*
Y209825D01*
X1859200D01*
G01X1859866Y208617D02*
X1860866D01*
G01X1857725Y209408D02*
X1857475Y209658D01*
X1857183Y209783D01*
X1856850Y209825D01*
X1856433Y209742D01*
X1856141Y209533D01*
X1856058Y209283D01*
X1856100Y209033D01*
X1856266Y208825D01*
X1857100Y208408D01*
X1857475Y208117D01*
X1857725Y207700D01*
X1857808Y207325D01*
X1856058D01*
G01X1854750Y207825D02*
X1854500Y207533D01*
X1854166Y207367D01*
X1853791Y207325D01*
X1853458Y207367D01*
X1853125Y207575D01*
X1852916Y207825D01*
X1852875Y208075D01*
X1852958Y208367D01*
X1853250Y208575D01*
X1853541Y208658D01*
X1853916D01*
G01X1853541D02*
X1853291Y208783D01*
X1853083Y208992D01*
X1853000Y209242D01*
X1853083Y209492D01*
X1853291Y209700D01*
X1853666Y209825D01*
X1854041Y209783D01*
X1854416Y209617D01*
G01X1839144Y189437D02*
X1841644D01*
Y190478D01*
X1841519Y190812D01*
X1841352Y191020D01*
X1841019Y191103D01*
X1840686Y191020D01*
X1840477Y190770D01*
X1840352Y190478D01*
Y189437D01*
G01Y190478D02*
X1839144Y191103D01*
G01X1839436Y192662D02*
X1839227Y192953D01*
X1839144Y193287D01*
X1839227Y193620D01*
X1839477Y193912D01*
X1839852Y194120D01*
X1840227Y194203D01*
X1840686D01*
X1841061Y194120D01*
X1841394Y193912D01*
X1841561Y193662D01*
X1841644Y193370D01*
X1841561Y193037D01*
X1841394Y192787D01*
X1841144Y192620D01*
X1840811Y192537D01*
X1840519Y192620D01*
X1840227Y192828D01*
X1840061Y193078D01*
X1840019Y193370D01*
X1840102Y193703D01*
X1840311Y193953D01*
X1840686Y194203D01*
G01X1839144Y197303D02*
Y195637D01*
X1841644D01*
Y197303D01*
G01X1840436Y196637D02*
Y195637D01*
G01X1839144Y199570D02*
X1841644D01*
X1841144Y199070D01*
G01X1839144D02*
Y200070D01*
G01Y202670D02*
X1841644D01*
X1841144Y202170D01*
G01X1839144D02*
Y203170D01*
G01X1842903Y189319D02*
X1845403D01*
Y190360D01*
X1845278Y190694D01*
X1845111Y190902D01*
X1844778Y190985D01*
X1844445Y190902D01*
X1844236Y190652D01*
X1844111Y190360D01*
Y189319D01*
G01Y190360D02*
X1842903Y190985D01*
G01X1843195Y192544D02*
X1842986Y192835D01*
X1842903Y193169D01*
X1842986Y193502D01*
X1843236Y193794D01*
X1843611Y194002D01*
X1843986Y194085D01*
X1844445D01*
X1844820Y194002D01*
X1845153Y193794D01*
X1845320Y193544D01*
X1845403Y193252D01*
X1845320Y192919D01*
X1845153Y192669D01*
X1844903Y192502D01*
X1844570Y192419D01*
X1844278Y192502D01*
X1843986Y192710D01*
X1843820Y192960D01*
X1843778Y193252D01*
X1843861Y193585D01*
X1844070Y193835D01*
X1844445Y194085D01*
G01X1842903Y197185D02*
Y195519D01*
X1845403D01*
Y197185D01*
G01X1844195Y196519D02*
Y195519D01*
G01X1842903Y199452D02*
X1845403D01*
X1844903Y198952D01*
G01X1842903D02*
Y199952D01*
G01X1844986Y201760D02*
X1845236Y202010D01*
X1845361Y202302D01*
X1845403Y202635D01*
X1845320Y203052D01*
X1845111Y203344D01*
X1844861Y203427D01*
X1844611Y203385D01*
X1844403Y203219D01*
X1843986Y202385D01*
X1843695Y202010D01*
X1843278Y201760D01*
X1842903Y201677D01*
Y203427D01*
G01X1850962Y160657D02*
X1851087Y160407D01*
X1851170Y160115D01*
Y159782D01*
X1851045Y159407D01*
X1850837Y159115D01*
X1850587Y158907D01*
X1850170Y158740D01*
X1849795Y158698D01*
X1849420Y158782D01*
X1849170Y158907D01*
X1848920Y159157D01*
X1848753Y159448D01*
X1848670Y159740D01*
Y160032D01*
X1848753Y160323D01*
X1848878Y160573D01*
X1849045Y160782D01*
G01X1848670Y162840D02*
X1851170D01*
X1850670Y162340D01*
G01X1848670D02*
Y163340D01*
G01X1851170Y165940D02*
X1848670D01*
G01X1851170Y164982D02*
Y166898D01*
G01X1848670Y168957D02*
X1849212Y169040D01*
X1849670Y169165D01*
X1850087Y169332D01*
X1850545Y169540D01*
X1851170Y169873D01*
Y168207D01*
G01X1881467Y211850D02*
Y210058D01*
X1881300Y209683D01*
X1880967Y209433D01*
X1880550Y209350D01*
X1880133Y209433D01*
X1879800Y209683D01*
X1879633Y210058D01*
Y211850D01*
G01X1877450Y209350D02*
X1877158Y209392D01*
X1876825Y209517D01*
X1876617Y209725D01*
X1876533Y210017D01*
X1876617Y210308D01*
X1876867Y210558D01*
X1877242Y210683D01*
X1877658D01*
X1877908Y210767D01*
X1878117Y210975D01*
X1878200Y211267D01*
X1878075Y211558D01*
X1877783Y211767D01*
X1877450Y211850D01*
X1877117Y211767D01*
X1876825Y211558D01*
X1876700Y211267D01*
X1876783Y210975D01*
X1876992Y210767D01*
X1877242Y210683D01*
X1877658D01*
X1878033Y210558D01*
X1878283Y210308D01*
X1878367Y210017D01*
X1878283Y209725D01*
X1878075Y209517D01*
X1877742Y209392D01*
X1877450Y209350D01*
G01X1873517D02*
X1875183D01*
Y211850D01*
X1873517D01*
G01X1874183Y210642D02*
X1875183D01*
G01X1870750Y209350D02*
Y211850D01*
X1872292Y210058D01*
X1870208D01*
G01X1864359Y204344D02*
X1864609Y204469D01*
X1864901Y204552D01*
X1865234D01*
X1865609Y204427D01*
X1865901Y204219D01*
X1866109Y203969D01*
X1866276Y203552D01*
X1866318Y203177D01*
X1866234Y202802D01*
X1866109Y202552D01*
X1865859Y202302D01*
X1865568Y202135D01*
X1865276Y202052D01*
X1864984D01*
X1864693Y202135D01*
X1864443Y202260D01*
X1864234Y202427D01*
G01X1862176Y202052D02*
X1861884Y202094D01*
X1861551Y202219D01*
X1861343Y202427D01*
X1861259Y202719D01*
X1861343Y203010D01*
X1861593Y203260D01*
X1861968Y203385D01*
X1862384D01*
X1862634Y203469D01*
X1862843Y203677D01*
X1862926Y203969D01*
X1862801Y204260D01*
X1862509Y204469D01*
X1862176Y204552D01*
X1861843Y204469D01*
X1861551Y204260D01*
X1861426Y203969D01*
X1861509Y203677D01*
X1861718Y203469D01*
X1861968Y203385D01*
X1862384D01*
X1862759Y203260D01*
X1863009Y203010D01*
X1863093Y202719D01*
X1863009Y202427D01*
X1862801Y202219D01*
X1862468Y202094D01*
X1862176Y202052D01*
G01X1858243D02*
X1859909D01*
Y204552D01*
X1858243D01*
G01X1858909Y203344D02*
X1859909D01*
G01X1856893Y202427D02*
X1856643Y202219D01*
X1856351Y202094D01*
X1855976Y202052D01*
X1855601Y202135D01*
X1855309Y202302D01*
X1855101Y202594D01*
X1855059Y202927D01*
X1855143Y203260D01*
X1855351Y203469D01*
X1855643Y203635D01*
X1855934Y203677D01*
X1856226Y203635D01*
X1856601Y203469D01*
X1856476Y204552D01*
X1855351D01*
G01X1866150Y214050D02*
Y216550D01*
X1865109D01*
X1864775Y216425D01*
X1864567Y216258D01*
X1864484Y215925D01*
X1864567Y215592D01*
X1864817Y215383D01*
X1865109Y215258D01*
X1866150D01*
G01X1865109D02*
X1864484Y214050D01*
G01X1862217D02*
X1861925Y214092D01*
X1861592Y214217D01*
X1861384Y214425D01*
X1861300Y214717D01*
X1861384Y215008D01*
X1861634Y215258D01*
X1862009Y215383D01*
X1862425D01*
X1862675Y215467D01*
X1862884Y215675D01*
X1862967Y215967D01*
X1862842Y216258D01*
X1862550Y216467D01*
X1862217Y216550D01*
X1861884Y216467D01*
X1861592Y216258D01*
X1861467Y215967D01*
X1861550Y215675D01*
X1861759Y215467D01*
X1862009Y215383D01*
X1862425D01*
X1862800Y215258D01*
X1863050Y215008D01*
X1863134Y214717D01*
X1863050Y214425D01*
X1862842Y214217D01*
X1862509Y214092D01*
X1862217Y214050D01*
G01X1858284D02*
X1859950D01*
Y216550D01*
X1858284D01*
G01X1858950Y215342D02*
X1859950D01*
G01X1856934Y214550D02*
X1856684Y214258D01*
X1856350Y214092D01*
X1855975Y214050D01*
X1855642Y214092D01*
X1855309Y214300D01*
X1855100Y214550D01*
X1855059Y214800D01*
X1855142Y215092D01*
X1855434Y215300D01*
X1855725Y215383D01*
X1856100D01*
G01X1855725D02*
X1855475Y215508D01*
X1855267Y215717D01*
X1855184Y215967D01*
X1855267Y216217D01*
X1855475Y216425D01*
X1855850Y216550D01*
X1856225Y216508D01*
X1856600Y216342D01*
G01X1852917Y216550D02*
X1853250Y216467D01*
X1853500Y216258D01*
X1853667Y216008D01*
X1853792Y215675D01*
X1853834Y215300D01*
X1853792Y214925D01*
X1853667Y214592D01*
X1853500Y214342D01*
X1853250Y214133D01*
X1852917Y214050D01*
X1852584Y214133D01*
X1852334Y214342D01*
X1852167Y214592D01*
X1852042Y214925D01*
X1852000Y215300D01*
X1852042Y215675D01*
X1852167Y216008D01*
X1852334Y216258D01*
X1852584Y216467D01*
X1852917Y216550D01*
G01X1867416Y162418D02*
X1867666Y162543D01*
X1867958Y162626D01*
X1868291D01*
X1868666Y162501D01*
X1868958Y162293D01*
X1869166Y162043D01*
X1869333Y161626D01*
X1869375Y161251D01*
X1869291Y160876D01*
X1869166Y160626D01*
X1868916Y160376D01*
X1868625Y160209D01*
X1868333Y160126D01*
X1868041D01*
X1867750Y160209D01*
X1867500Y160334D01*
X1867291Y160501D01*
G01X1866025Y162209D02*
X1865775Y162459D01*
X1865483Y162584D01*
X1865150Y162626D01*
X1864733Y162543D01*
X1864441Y162334D01*
X1864358Y162084D01*
X1864400Y161834D01*
X1864566Y161626D01*
X1865400Y161209D01*
X1865775Y160918D01*
X1866025Y160501D01*
X1866108Y160126D01*
X1864358D01*
G01X1862925Y162209D02*
X1862675Y162459D01*
X1862383Y162584D01*
X1862050Y162626D01*
X1861633Y162543D01*
X1861341Y162334D01*
X1861258Y162084D01*
X1861300Y161834D01*
X1861466Y161626D01*
X1862300Y161209D01*
X1862675Y160918D01*
X1862925Y160501D01*
X1863008Y160126D01*
X1861258D01*
G01X1860283Y162626D02*
X1859700Y160126D01*
X1859033Y162626D01*
X1858366Y160126D01*
X1857783Y162626D01*
G01X1856850Y160626D02*
X1856600Y160334D01*
X1856266Y160168D01*
X1855891Y160126D01*
X1855558Y160168D01*
X1855225Y160376D01*
X1855016Y160626D01*
X1854975Y160876D01*
X1855058Y161168D01*
X1855350Y161376D01*
X1855641Y161459D01*
X1856016D01*
G01X1855641D02*
X1855391Y161584D01*
X1855183Y161793D01*
X1855100Y162043D01*
X1855183Y162293D01*
X1855391Y162501D01*
X1855766Y162626D01*
X1856141Y162584D01*
X1856516Y162418D01*
G01X1853750Y160501D02*
X1853500Y160293D01*
X1853208Y160168D01*
X1852833Y160126D01*
X1852458Y160209D01*
X1852166Y160376D01*
X1851958Y160668D01*
X1851916Y161001D01*
X1852000Y161334D01*
X1852208Y161543D01*
X1852500Y161709D01*
X1852791Y161751D01*
X1853083Y161709D01*
X1853458Y161543D01*
X1853333Y162626D01*
X1852208D01*
G01X1865574Y170467D02*
X1865824Y170592D01*
X1866116Y170675D01*
X1866449D01*
X1866824Y170550D01*
X1867116Y170342D01*
X1867324Y170092D01*
X1867491Y169675D01*
X1867533Y169300D01*
X1867449Y168925D01*
X1867324Y168675D01*
X1867074Y168425D01*
X1866783Y168258D01*
X1866491Y168175D01*
X1866199D01*
X1865908Y168258D01*
X1865658Y168383D01*
X1865449Y168550D01*
G01X1864099Y168467D02*
X1863808Y168258D01*
X1863474Y168175D01*
X1863141Y168258D01*
X1862849Y168508D01*
X1862641Y168883D01*
X1862558Y169258D01*
Y169717D01*
X1862641Y170092D01*
X1862849Y170425D01*
X1863099Y170592D01*
X1863391Y170675D01*
X1863724Y170592D01*
X1863974Y170425D01*
X1864141Y170175D01*
X1864224Y169842D01*
X1864141Y169550D01*
X1863933Y169258D01*
X1863683Y169092D01*
X1863391Y169050D01*
X1863058Y169133D01*
X1862808Y169342D01*
X1862558Y169717D01*
G01X1859458Y168175D02*
X1861124D01*
Y170675D01*
X1859458D01*
G01X1860124Y169467D02*
X1861124D01*
G01X1857983Y169217D02*
X1857691Y169508D01*
X1857441Y169675D01*
X1857108Y169758D01*
X1856816Y169675D01*
X1856608Y169508D01*
X1856441Y169258D01*
X1856399Y168967D01*
X1856441Y168717D01*
X1856608Y168467D01*
X1856858Y168258D01*
X1857149Y168175D01*
X1857483Y168258D01*
X1857774Y168508D01*
X1857941Y168883D01*
X1857983Y169300D01*
X1857899Y169842D01*
X1857774Y170133D01*
X1857566Y170425D01*
X1857274Y170633D01*
X1856983Y170675D01*
X1856691Y170592D01*
X1856483Y170383D01*
G01X1886333Y197892D02*
X1886583Y198017D01*
X1886875Y198100D01*
X1887208D01*
X1887583Y197975D01*
X1887875Y197767D01*
X1888083Y197517D01*
X1888250Y197100D01*
X1888292Y196725D01*
X1888208Y196350D01*
X1888083Y196100D01*
X1887833Y195850D01*
X1887542Y195683D01*
X1887250Y195600D01*
X1886958D01*
X1886667Y195683D01*
X1886417Y195808D01*
X1886208Y195975D01*
G01X1884942Y197683D02*
X1884692Y197933D01*
X1884400Y198058D01*
X1884067Y198100D01*
X1883650Y198017D01*
X1883358Y197808D01*
X1883275Y197558D01*
X1883317Y197308D01*
X1883483Y197100D01*
X1884317Y196683D01*
X1884692Y196392D01*
X1884942Y195975D01*
X1885025Y195600D01*
X1883275D01*
G01X1881842Y197683D02*
X1881592Y197933D01*
X1881300Y198058D01*
X1880967Y198100D01*
X1880550Y198017D01*
X1880258Y197808D01*
X1880175Y197558D01*
X1880217Y197308D01*
X1880383Y197100D01*
X1881217Y196683D01*
X1881592Y196392D01*
X1881842Y195975D01*
X1881925Y195600D01*
X1880175D01*
G01X1879200Y198100D02*
X1878617Y195600D01*
X1877950Y198100D01*
X1877283Y195600D01*
X1876700Y198100D01*
G01X1875767Y196100D02*
X1875517Y195808D01*
X1875183Y195642D01*
X1874808Y195600D01*
X1874475Y195642D01*
X1874142Y195850D01*
X1873933Y196100D01*
X1873892Y196350D01*
X1873975Y196642D01*
X1874267Y196850D01*
X1874558Y196933D01*
X1874933D01*
G01X1874558D02*
X1874308Y197058D01*
X1874100Y197267D01*
X1874017Y197517D01*
X1874100Y197767D01*
X1874308Y197975D01*
X1874683Y198100D01*
X1875058Y198058D01*
X1875433Y197892D01*
G01X1871250Y195600D02*
Y198100D01*
X1872792Y196308D01*
X1870708D01*
G01X1881633Y202792D02*
X1881883Y202917D01*
X1882175Y203000D01*
X1882508D01*
X1882883Y202875D01*
X1883175Y202667D01*
X1883383Y202417D01*
X1883550Y202000D01*
X1883592Y201625D01*
X1883508Y201250D01*
X1883383Y201000D01*
X1883133Y200750D01*
X1882842Y200583D01*
X1882550Y200500D01*
X1882258D01*
X1881967Y200583D01*
X1881717Y200708D01*
X1881508Y200875D01*
G01X1880158Y200792D02*
X1879867Y200583D01*
X1879533Y200500D01*
X1879200Y200583D01*
X1878908Y200833D01*
X1878700Y201208D01*
X1878617Y201583D01*
Y202042D01*
X1878700Y202417D01*
X1878908Y202750D01*
X1879158Y202917D01*
X1879450Y203000D01*
X1879783Y202917D01*
X1880033Y202750D01*
X1880200Y202500D01*
X1880283Y202167D01*
X1880200Y201875D01*
X1879992Y201583D01*
X1879742Y201417D01*
X1879450Y201375D01*
X1879117Y201458D01*
X1878867Y201667D01*
X1878617Y202042D01*
G01X1877142Y200500D02*
Y203000D01*
X1875558D01*
G01X1876142Y201792D02*
X1877142D01*
G01X1874042Y202583D02*
X1873792Y202833D01*
X1873500Y202958D01*
X1873167Y203000D01*
X1872750Y202917D01*
X1872458Y202708D01*
X1872375Y202458D01*
X1872417Y202208D01*
X1872583Y202000D01*
X1873417Y201583D01*
X1873792Y201292D01*
X1874042Y200875D01*
X1874125Y200500D01*
X1872375D01*
G01X1882533Y220717D02*
Y223217D01*
X1881492D01*
X1881158Y223092D01*
X1880950Y222925D01*
X1880867Y222592D01*
X1880950Y222259D01*
X1881200Y222050D01*
X1881492Y221925D01*
X1882533D01*
G01X1881492D02*
X1880867Y220717D01*
G01X1878600D02*
X1878308Y220759D01*
X1877975Y220884D01*
X1877767Y221092D01*
X1877683Y221384D01*
X1877767Y221675D01*
X1878017Y221925D01*
X1878392Y222050D01*
X1878808D01*
X1879058Y222134D01*
X1879267Y222342D01*
X1879350Y222634D01*
X1879225Y222925D01*
X1878933Y223134D01*
X1878600Y223217D01*
X1878267Y223134D01*
X1877975Y222925D01*
X1877850Y222634D01*
X1877933Y222342D01*
X1878142Y222134D01*
X1878392Y222050D01*
X1878808D01*
X1879183Y221925D01*
X1879433Y221675D01*
X1879517Y221384D01*
X1879433Y221092D01*
X1879225Y220884D01*
X1878892Y220759D01*
X1878600Y220717D01*
G01X1874667D02*
X1876333D01*
Y223217D01*
X1874667D01*
G01X1875333Y222009D02*
X1876333D01*
G01X1873192Y222800D02*
X1872942Y223050D01*
X1872650Y223175D01*
X1872317Y223217D01*
X1871900Y223134D01*
X1871608Y222925D01*
X1871525Y222675D01*
X1871567Y222425D01*
X1871733Y222217D01*
X1872567Y221800D01*
X1872942Y221509D01*
X1873192Y221092D01*
X1873275Y220717D01*
X1871525D01*
G01X1870092Y221759D02*
X1869800Y222050D01*
X1869550Y222217D01*
X1869217Y222300D01*
X1868925Y222217D01*
X1868717Y222050D01*
X1868550Y221800D01*
X1868508Y221509D01*
X1868550Y221259D01*
X1868717Y221009D01*
X1868967Y220800D01*
X1869258Y220717D01*
X1869592Y220800D01*
X1869883Y221050D01*
X1870050Y221425D01*
X1870092Y221842D01*
X1870008Y222384D01*
X1869883Y222675D01*
X1869675Y222967D01*
X1869383Y223175D01*
X1869092Y223217D01*
X1868800Y223134D01*
X1868592Y222925D01*
G01X1866233Y221600D02*
Y224100D01*
X1865192D01*
X1864858Y223975D01*
X1864650Y223808D01*
X1864567Y223475D01*
X1864650Y223142D01*
X1864900Y222933D01*
X1865192Y222808D01*
X1866233D01*
G01X1865192D02*
X1864567Y221600D01*
G01X1862300D02*
X1862008Y221642D01*
X1861675Y221767D01*
X1861467Y221975D01*
X1861383Y222267D01*
X1861467Y222558D01*
X1861717Y222808D01*
X1862092Y222933D01*
X1862508D01*
X1862758Y223017D01*
X1862967Y223225D01*
X1863050Y223517D01*
X1862925Y223808D01*
X1862633Y224017D01*
X1862300Y224100D01*
X1861967Y224017D01*
X1861675Y223808D01*
X1861550Y223517D01*
X1861633Y223225D01*
X1861842Y223017D01*
X1862092Y222933D01*
X1862508D01*
X1862883Y222808D01*
X1863133Y222558D01*
X1863217Y222267D01*
X1863133Y221975D01*
X1862925Y221767D01*
X1862592Y221642D01*
X1862300Y221600D01*
G01X1858367D02*
X1860033D01*
Y224100D01*
X1858367D01*
G01X1859033Y222892D02*
X1860033D01*
G01X1856892Y223683D02*
X1856642Y223933D01*
X1856350Y224058D01*
X1856017Y224100D01*
X1855600Y224017D01*
X1855308Y223808D01*
X1855225Y223558D01*
X1855267Y223308D01*
X1855433Y223100D01*
X1856267Y222683D01*
X1856642Y222392D01*
X1856892Y221975D01*
X1856975Y221600D01*
X1855225D01*
G01X1853708Y221892D02*
X1853417Y221683D01*
X1853083Y221600D01*
X1852750Y221683D01*
X1852458Y221933D01*
X1852250Y222308D01*
X1852167Y222683D01*
Y223142D01*
X1852250Y223517D01*
X1852458Y223850D01*
X1852708Y224017D01*
X1853000Y224100D01*
X1853333Y224017D01*
X1853583Y223850D01*
X1853750Y223600D01*
X1853833Y223267D01*
X1853750Y222975D01*
X1853542Y222683D01*
X1853292Y222517D01*
X1853000Y222475D01*
X1852667Y222558D01*
X1852417Y222767D01*
X1852167Y223142D01*
G01X1904781Y242509D02*
Y245009D01*
X1903740D01*
X1903406Y244884D01*
X1903198Y244717D01*
X1903115Y244384D01*
X1903198Y244051D01*
X1903448Y243842D01*
X1903740Y243717D01*
X1904781D01*
G01X1903740D02*
X1903115Y242509D01*
G01X1901765Y243009D02*
X1901515Y242717D01*
X1901181Y242551D01*
X1900806Y242509D01*
X1900473Y242551D01*
X1900140Y242759D01*
X1899931Y243009D01*
X1899890Y243259D01*
X1899973Y243551D01*
X1900265Y243759D01*
X1900556Y243842D01*
X1900931D01*
G01X1900556D02*
X1900306Y243967D01*
X1900098Y244176D01*
X1900015Y244426D01*
X1900098Y244676D01*
X1900306Y244884D01*
X1900681Y245009D01*
X1901056Y244967D01*
X1901431Y244801D01*
G01X1897748Y245009D02*
X1898081Y244926D01*
X1898331Y244717D01*
X1898498Y244467D01*
X1898623Y244134D01*
X1898665Y243759D01*
X1898623Y243384D01*
X1898498Y243051D01*
X1898331Y242801D01*
X1898081Y242592D01*
X1897748Y242509D01*
X1897415Y242592D01*
X1897165Y242801D01*
X1896998Y243051D01*
X1896873Y243384D01*
X1896831Y243759D01*
X1896873Y244134D01*
X1896998Y244467D01*
X1897165Y244717D01*
X1897415Y244926D01*
X1897748Y245009D01*
G01X1895898D02*
X1895315Y242509D01*
X1894648Y245009D01*
X1893981Y242509D01*
X1893398Y245009D01*
G01X1892465Y243009D02*
X1892215Y242717D01*
X1891881Y242551D01*
X1891506Y242509D01*
X1891173Y242551D01*
X1890840Y242759D01*
X1890631Y243009D01*
X1890590Y243259D01*
X1890673Y243551D01*
X1890965Y243759D01*
X1891256Y243842D01*
X1891631D01*
G01X1891256D02*
X1891006Y243967D01*
X1890798Y244176D01*
X1890715Y244426D01*
X1890798Y244676D01*
X1891006Y244884D01*
X1891381Y245009D01*
X1891756Y244967D01*
X1892131Y244801D01*
G01X1904781Y238909D02*
Y241409D01*
X1903740D01*
X1903406Y241284D01*
X1903198Y241117D01*
X1903115Y240784D01*
X1903198Y240451D01*
X1903448Y240242D01*
X1903740Y240117D01*
X1904781D01*
G01X1903740D02*
X1903115Y238909D01*
G01X1901765Y239409D02*
X1901515Y239117D01*
X1901181Y238951D01*
X1900806Y238909D01*
X1900473Y238951D01*
X1900140Y239159D01*
X1899931Y239409D01*
X1899890Y239659D01*
X1899973Y239951D01*
X1900265Y240159D01*
X1900556Y240242D01*
X1900931D01*
G01X1900556D02*
X1900306Y240367D01*
X1900098Y240576D01*
X1900015Y240826D01*
X1900098Y241076D01*
X1900306Y241284D01*
X1900681Y241409D01*
X1901056Y241367D01*
X1901431Y241201D01*
G01X1897748Y241409D02*
X1898081Y241326D01*
X1898331Y241117D01*
X1898498Y240867D01*
X1898623Y240534D01*
X1898665Y240159D01*
X1898623Y239784D01*
X1898498Y239451D01*
X1898331Y239201D01*
X1898081Y238992D01*
X1897748Y238909D01*
X1897415Y238992D01*
X1897165Y239201D01*
X1896998Y239451D01*
X1896873Y239784D01*
X1896831Y240159D01*
X1896873Y240534D01*
X1896998Y240867D01*
X1897165Y241117D01*
X1897415Y241326D01*
X1897748Y241409D01*
G01X1895898D02*
X1895315Y238909D01*
X1894648Y241409D01*
X1893981Y238909D01*
X1893398Y241409D01*
G01X1891048Y238909D02*
Y241409D01*
X1892590Y239617D01*
X1890506D01*
G01X1852833Y255600D02*
Y258100D01*
X1851792D01*
X1851458Y257975D01*
X1851250Y257808D01*
X1851167Y257475D01*
X1851250Y257142D01*
X1851500Y256933D01*
X1851792Y256808D01*
X1852833D01*
G01X1851792D02*
X1851167Y255600D01*
G01X1848900D02*
Y258100D01*
X1849400Y257600D01*
G01Y255600D02*
X1848400D01*
G01X1846633D02*
Y258100D01*
X1845592D01*
X1845258Y257975D01*
X1845050Y257808D01*
X1844967Y257475D01*
X1845050Y257142D01*
X1845300Y256933D01*
X1845592Y256808D01*
X1846633D01*
G01X1845592D02*
X1844967Y255600D01*
G01X1842700D02*
Y258100D01*
X1843200Y257600D01*
G01Y255600D02*
X1842200D01*
G01X1839683D02*
X1839600Y256142D01*
X1839475Y256600D01*
X1839308Y257017D01*
X1839100Y257475D01*
X1838767Y258100D01*
X1840433D01*
G01X1852833Y259100D02*
Y261600D01*
X1851792D01*
X1851458Y261475D01*
X1851250Y261308D01*
X1851167Y260975D01*
X1851250Y260642D01*
X1851500Y260433D01*
X1851792Y260308D01*
X1852833D01*
G01X1851792D02*
X1851167Y259100D01*
G01X1848900D02*
Y261600D01*
X1849400Y261100D01*
G01Y259100D02*
X1848400D01*
G01X1846633D02*
Y261600D01*
X1845592D01*
X1845258Y261475D01*
X1845050Y261308D01*
X1844967Y260975D01*
X1845050Y260642D01*
X1845300Y260433D01*
X1845592Y260308D01*
X1846633D01*
G01X1845592D02*
X1844967Y259100D01*
G01X1842700D02*
Y261600D01*
X1843200Y261100D01*
G01Y259100D02*
X1842200D01*
G01X1840392Y260142D02*
X1840100Y260433D01*
X1839850Y260600D01*
X1839517Y260683D01*
X1839225Y260600D01*
X1839017Y260433D01*
X1838850Y260183D01*
X1838808Y259892D01*
X1838850Y259642D01*
X1839017Y259392D01*
X1839267Y259183D01*
X1839558Y259100D01*
X1839892Y259183D01*
X1840183Y259433D01*
X1840350Y259808D01*
X1840392Y260225D01*
X1840308Y260767D01*
X1840183Y261058D01*
X1839975Y261350D01*
X1839683Y261558D01*
X1839392Y261600D01*
X1839100Y261517D01*
X1838892Y261308D01*
G01X1887319Y244728D02*
X1887569Y244853D01*
X1887861Y244936D01*
X1888194D01*
X1888569Y244811D01*
X1888861Y244603D01*
X1889069Y244353D01*
X1889236Y243936D01*
X1889278Y243561D01*
X1889194Y243186D01*
X1889069Y242936D01*
X1888819Y242686D01*
X1888528Y242519D01*
X1888236Y242436D01*
X1887944D01*
X1887653Y242519D01*
X1887403Y242644D01*
X1887194Y242811D01*
G01X1886053Y242936D02*
X1885803Y242644D01*
X1885469Y242478D01*
X1885094Y242436D01*
X1884761Y242478D01*
X1884428Y242686D01*
X1884219Y242936D01*
X1884178Y243186D01*
X1884261Y243478D01*
X1884553Y243686D01*
X1884844Y243769D01*
X1885219D01*
G01X1884844D02*
X1884594Y243894D01*
X1884386Y244103D01*
X1884303Y244353D01*
X1884386Y244603D01*
X1884594Y244811D01*
X1884969Y244936D01*
X1885344Y244894D01*
X1885719Y244728D01*
G01X1882036Y244936D02*
X1882369Y244853D01*
X1882619Y244644D01*
X1882786Y244394D01*
X1882911Y244061D01*
X1882953Y243686D01*
X1882911Y243311D01*
X1882786Y242978D01*
X1882619Y242728D01*
X1882369Y242519D01*
X1882036Y242436D01*
X1881703Y242519D01*
X1881453Y242728D01*
X1881286Y242978D01*
X1881161Y243311D01*
X1881119Y243686D01*
X1881161Y244061D01*
X1881286Y244394D01*
X1881453Y244644D01*
X1881703Y244853D01*
X1882036Y244936D01*
G01X1880186D02*
X1879603Y242436D01*
X1878936Y244936D01*
X1878269Y242436D01*
X1877686Y244936D01*
G01X1875836Y242436D02*
Y244936D01*
X1876336Y244436D01*
G01Y242436D02*
X1875336D01*
G01X1887308Y241528D02*
X1887558Y241653D01*
X1887850Y241736D01*
X1888183D01*
X1888558Y241611D01*
X1888850Y241403D01*
X1889058Y241153D01*
X1889225Y240736D01*
X1889267Y240361D01*
X1889183Y239986D01*
X1889058Y239736D01*
X1888808Y239486D01*
X1888517Y239319D01*
X1888225Y239236D01*
X1887933D01*
X1887642Y239319D01*
X1887392Y239444D01*
X1887183Y239611D01*
G01X1886042Y239736D02*
X1885792Y239444D01*
X1885458Y239278D01*
X1885083Y239236D01*
X1884750Y239278D01*
X1884417Y239486D01*
X1884208Y239736D01*
X1884167Y239986D01*
X1884250Y240278D01*
X1884542Y240486D01*
X1884833Y240569D01*
X1885208D01*
G01X1884833D02*
X1884583Y240694D01*
X1884375Y240903D01*
X1884292Y241153D01*
X1884375Y241403D01*
X1884583Y241611D01*
X1884958Y241736D01*
X1885333Y241694D01*
X1885708Y241528D01*
G01X1882025Y241736D02*
X1882358Y241653D01*
X1882608Y241444D01*
X1882775Y241194D01*
X1882900Y240861D01*
X1882942Y240486D01*
X1882900Y240111D01*
X1882775Y239778D01*
X1882608Y239528D01*
X1882358Y239319D01*
X1882025Y239236D01*
X1881692Y239319D01*
X1881442Y239528D01*
X1881275Y239778D01*
X1881150Y240111D01*
X1881108Y240486D01*
X1881150Y240861D01*
X1881275Y241194D01*
X1881442Y241444D01*
X1881692Y241653D01*
X1882025Y241736D01*
G01X1880175D02*
X1879592Y239236D01*
X1878925Y241736D01*
X1878258Y239236D01*
X1877675Y241736D01*
G01X1876617Y241319D02*
X1876367Y241569D01*
X1876075Y241694D01*
X1875742Y241736D01*
X1875325Y241653D01*
X1875033Y241444D01*
X1874950Y241194D01*
X1874992Y240944D01*
X1875158Y240736D01*
X1875992Y240319D01*
X1876367Y240028D01*
X1876617Y239611D01*
X1876700Y239236D01*
X1874950D01*
G01X1886500Y223100D02*
Y227100D01*
X1893900D01*
G01X1903771Y436421D02*
X1904021Y436546D01*
X1904313Y436629D01*
X1904646D01*
X1905021Y436504D01*
X1905313Y436296D01*
X1905521Y436046D01*
X1905688Y435629D01*
X1905730Y435254D01*
X1905646Y434879D01*
X1905521Y434629D01*
X1905271Y434379D01*
X1904980Y434212D01*
X1904688Y434129D01*
X1904396D01*
X1904105Y434212D01*
X1903855Y434337D01*
X1903646Y434504D01*
G01X1901588Y434129D02*
Y436629D01*
X1902088Y436129D01*
G01Y434129D02*
X1901088D01*
G01X1899571D02*
Y436629D01*
X1898488Y434546D01*
X1897405Y436629D01*
Y434129D01*
G01X1896180Y436212D02*
X1895930Y436462D01*
X1895638Y436587D01*
X1895305Y436629D01*
X1894888Y436546D01*
X1894596Y436337D01*
X1894513Y436087D01*
X1894555Y435837D01*
X1894721Y435629D01*
X1895555Y435212D01*
X1895930Y434921D01*
X1896180Y434504D01*
X1896263Y434129D01*
X1894513D01*
G01X1892371D02*
X1892288Y434671D01*
X1892163Y435129D01*
X1891996Y435546D01*
X1891788Y436004D01*
X1891455Y436629D01*
X1893121D01*
G01X1843967Y451567D02*
X1846467D01*
Y452608D01*
X1846342Y452942D01*
X1846175Y453150D01*
X1845842Y453233D01*
X1845509Y453150D01*
X1845300Y452900D01*
X1845175Y452608D01*
Y451567D01*
G01Y452608D02*
X1843967Y453233D01*
G01Y455500D02*
X1846467D01*
X1845967Y455000D01*
G01X1843967D02*
Y456000D01*
G01Y457517D02*
X1846467D01*
X1844384Y458600D01*
X1846467Y459683D01*
X1843967D01*
G01Y461700D02*
X1846467D01*
X1845967Y461200D01*
G01X1843967D02*
Y462200D01*
G01X1845009Y464008D02*
X1845300Y464300D01*
X1845467Y464550D01*
X1845550Y464883D01*
X1845467Y465175D01*
X1845300Y465383D01*
X1845050Y465550D01*
X1844759Y465592D01*
X1844509Y465550D01*
X1844259Y465383D01*
X1844050Y465133D01*
X1843967Y464842D01*
X1844050Y464508D01*
X1844300Y464217D01*
X1844675Y464050D01*
X1845092Y464008D01*
X1845634Y464092D01*
X1845925Y464217D01*
X1846217Y464425D01*
X1846425Y464717D01*
X1846467Y465008D01*
X1846384Y465300D01*
X1846175Y465508D01*
G01X1847967Y451667D02*
X1850467D01*
Y452708D01*
X1850342Y453042D01*
X1850175Y453250D01*
X1849842Y453333D01*
X1849509Y453250D01*
X1849300Y453000D01*
X1849175Y452708D01*
Y451667D01*
G01Y452708D02*
X1847967Y453333D01*
G01Y455600D02*
X1850467D01*
X1849967Y455100D01*
G01X1847967D02*
Y456100D01*
G01Y457617D02*
X1850467D01*
X1848384Y458700D01*
X1850467Y459783D01*
X1847967D01*
G01Y461800D02*
X1850467D01*
X1849967Y461300D01*
G01X1847967D02*
Y462300D01*
G01Y464817D02*
X1848509Y464900D01*
X1848967Y465025D01*
X1849384Y465192D01*
X1849842Y465400D01*
X1850467Y465733D01*
Y464067D01*
G01X1860998Y437342D02*
Y439842D01*
X1859957D01*
X1859623Y439717D01*
X1859415Y439550D01*
X1859332Y439217D01*
X1859415Y438884D01*
X1859665Y438675D01*
X1859957Y438550D01*
X1860998D01*
G01X1859957D02*
X1859332Y437342D01*
G01X1857065D02*
Y439842D01*
X1857565Y439342D01*
G01Y437342D02*
X1856565D01*
G01X1855048D02*
Y439842D01*
X1853965Y437759D01*
X1852882Y439842D01*
Y437342D01*
G01X1850865D02*
Y439842D01*
X1851365Y439342D01*
G01Y437342D02*
X1850365D01*
G01X1848682Y437717D02*
X1848432Y437509D01*
X1848140Y437384D01*
X1847765Y437342D01*
X1847390Y437425D01*
X1847098Y437592D01*
X1846890Y437884D01*
X1846848Y438217D01*
X1846932Y438550D01*
X1847140Y438759D01*
X1847432Y438925D01*
X1847723Y438967D01*
X1848015Y438925D01*
X1848390Y438759D01*
X1848265Y439842D01*
X1847140D01*
G01X1863267Y464167D02*
X1865767D01*
Y465208D01*
X1865642Y465542D01*
X1865475Y465750D01*
X1865142Y465833D01*
X1864809Y465750D01*
X1864600Y465500D01*
X1864475Y465208D01*
Y464167D01*
G01Y465208D02*
X1863267Y465833D01*
G01Y468100D02*
X1865767D01*
X1865267Y467600D01*
G01X1863267D02*
Y468600D01*
G01Y470117D02*
X1865767D01*
X1863684Y471200D01*
X1865767Y472283D01*
X1863267D01*
G01Y474300D02*
X1865767D01*
X1865267Y473800D01*
G01X1863267D02*
Y474800D01*
G01Y477900D02*
X1865767D01*
X1863975Y476358D01*
Y478442D01*
G01X1860985Y433906D02*
Y436406D01*
X1859944D01*
X1859610Y436281D01*
X1859402Y436114D01*
X1859319Y435781D01*
X1859402Y435448D01*
X1859652Y435239D01*
X1859944Y435114D01*
X1860985D01*
G01X1859944D02*
X1859319Y433906D01*
G01X1857052D02*
Y436406D01*
X1857552Y435906D01*
G01Y433906D02*
X1856552D01*
G01X1855035D02*
Y436406D01*
X1853952Y434323D01*
X1852869Y436406D01*
Y433906D01*
G01X1850852D02*
Y436406D01*
X1851352Y435906D01*
G01Y433906D02*
X1850352D01*
G01X1847752D02*
X1847460Y433948D01*
X1847127Y434073D01*
X1846919Y434281D01*
X1846835Y434573D01*
X1846919Y434864D01*
X1847169Y435114D01*
X1847544Y435239D01*
X1847960D01*
X1848210Y435323D01*
X1848419Y435531D01*
X1848502Y435823D01*
X1848377Y436114D01*
X1848085Y436323D01*
X1847752Y436406D01*
X1847419Y436323D01*
X1847127Y436114D01*
X1847002Y435823D01*
X1847085Y435531D01*
X1847294Y435323D01*
X1847544Y435239D01*
X1847960D01*
X1848335Y435114D01*
X1848585Y434864D01*
X1848669Y434573D01*
X1848585Y434281D01*
X1848377Y434073D01*
X1848044Y433948D01*
X1847752Y433906D01*
G01X1897618Y440033D02*
X1897868Y440158D01*
X1898160Y440241D01*
X1898493D01*
X1898868Y440116D01*
X1899160Y439908D01*
X1899368Y439658D01*
X1899535Y439241D01*
X1899577Y438866D01*
X1899493Y438491D01*
X1899368Y438241D01*
X1899118Y437991D01*
X1898827Y437824D01*
X1898535Y437741D01*
X1898243D01*
X1897952Y437824D01*
X1897702Y437949D01*
X1897493Y438116D01*
G01X1895435Y437741D02*
Y440241D01*
X1895935Y439741D01*
G01Y437741D02*
X1894935D01*
G01X1893418D02*
Y440241D01*
X1892335Y438158D01*
X1891252Y440241D01*
Y437741D01*
G01X1890027Y439824D02*
X1889777Y440074D01*
X1889485Y440199D01*
X1889152Y440241D01*
X1888735Y440158D01*
X1888443Y439949D01*
X1888360Y439699D01*
X1888402Y439449D01*
X1888568Y439241D01*
X1889402Y438824D01*
X1889777Y438533D01*
X1890027Y438116D01*
X1890110Y437741D01*
X1888360D01*
G01X1887052Y438116D02*
X1886802Y437908D01*
X1886510Y437783D01*
X1886135Y437741D01*
X1885760Y437824D01*
X1885468Y437991D01*
X1885260Y438283D01*
X1885218Y438616D01*
X1885302Y438949D01*
X1885510Y439158D01*
X1885802Y439324D01*
X1886093Y439366D01*
X1886385Y439324D01*
X1886760Y439158D01*
X1886635Y440241D01*
X1885510D01*
G01X1876783Y440559D02*
X1877033Y440684D01*
X1877325Y440767D01*
X1877658D01*
X1878033Y440642D01*
X1878325Y440434D01*
X1878533Y440184D01*
X1878700Y439767D01*
X1878742Y439392D01*
X1878658Y439017D01*
X1878533Y438767D01*
X1878283Y438517D01*
X1877992Y438350D01*
X1877700Y438267D01*
X1877408D01*
X1877117Y438350D01*
X1876867Y438475D01*
X1876658Y438642D01*
G01X1874600Y438267D02*
Y440767D01*
X1875100Y440267D01*
G01Y438267D02*
X1874100D01*
G01X1872583D02*
Y440767D01*
X1871500Y438684D01*
X1870417Y440767D01*
Y438267D01*
G01X1869192Y440350D02*
X1868942Y440600D01*
X1868650Y440725D01*
X1868317Y440767D01*
X1867900Y440684D01*
X1867608Y440475D01*
X1867525Y440225D01*
X1867567Y439975D01*
X1867733Y439767D01*
X1868567Y439350D01*
X1868942Y439059D01*
X1869192Y438642D01*
X1869275Y438267D01*
X1867525D01*
G01X1864800D02*
Y440767D01*
X1866342Y438975D01*
X1864258D01*
G01X1891483Y444459D02*
X1891733Y444584D01*
X1892025Y444667D01*
X1892358D01*
X1892733Y444542D01*
X1893025Y444334D01*
X1893233Y444084D01*
X1893400Y443667D01*
X1893442Y443292D01*
X1893358Y442917D01*
X1893233Y442667D01*
X1892983Y442417D01*
X1892692Y442250D01*
X1892400Y442167D01*
X1892108D01*
X1891817Y442250D01*
X1891567Y442375D01*
X1891358Y442542D01*
G01X1889300Y442167D02*
Y444667D01*
X1889800Y444167D01*
G01Y442167D02*
X1888800D01*
G01X1887283D02*
Y444667D01*
X1886200Y442584D01*
X1885117Y444667D01*
Y442167D01*
G01X1883892Y444250D02*
X1883642Y444500D01*
X1883350Y444625D01*
X1883017Y444667D01*
X1882600Y444584D01*
X1882308Y444375D01*
X1882225Y444125D01*
X1882267Y443875D01*
X1882433Y443667D01*
X1883267Y443250D01*
X1883642Y442959D01*
X1883892Y442542D01*
X1883975Y442167D01*
X1882225D01*
G01X1880000Y444667D02*
X1880333Y444584D01*
X1880583Y444375D01*
X1880750Y444125D01*
X1880875Y443792D01*
X1880917Y443417D01*
X1880875Y443042D01*
X1880750Y442709D01*
X1880583Y442459D01*
X1880333Y442250D01*
X1880000Y442167D01*
X1879667Y442250D01*
X1879417Y442459D01*
X1879250Y442709D01*
X1879125Y443042D01*
X1879083Y443417D01*
X1879125Y443792D01*
X1879250Y444125D01*
X1879417Y444375D01*
X1879667Y444584D01*
X1880000Y444667D01*
G01X1875383Y444659D02*
X1875633Y444784D01*
X1875925Y444867D01*
X1876258D01*
X1876633Y444742D01*
X1876925Y444534D01*
X1877133Y444284D01*
X1877300Y443867D01*
X1877342Y443492D01*
X1877258Y443117D01*
X1877133Y442867D01*
X1876883Y442617D01*
X1876592Y442450D01*
X1876300Y442367D01*
X1876008D01*
X1875717Y442450D01*
X1875467Y442575D01*
X1875258Y442742D01*
G01X1873200Y442367D02*
Y444867D01*
X1873700Y444367D01*
G01Y442367D02*
X1872700D01*
G01X1871183D02*
Y444867D01*
X1870100Y442784D01*
X1869017Y444867D01*
Y442367D01*
G01X1867792Y444450D02*
X1867542Y444700D01*
X1867250Y444825D01*
X1866917Y444867D01*
X1866500Y444784D01*
X1866208Y444575D01*
X1866125Y444325D01*
X1866167Y444075D01*
X1866333Y443867D01*
X1867167Y443450D01*
X1867542Y443159D01*
X1867792Y442742D01*
X1867875Y442367D01*
X1866125D01*
G01X1863900D02*
Y444867D01*
X1864400Y444367D01*
G01Y442367D02*
X1863400D01*
G01X1889352Y460497D02*
X1889477Y460247D01*
X1889560Y459955D01*
Y459622D01*
X1889435Y459247D01*
X1889227Y458955D01*
X1888977Y458747D01*
X1888560Y458580D01*
X1888185Y458538D01*
X1887810Y458622D01*
X1887560Y458747D01*
X1887310Y458997D01*
X1887143Y459288D01*
X1887060Y459580D01*
Y459872D01*
X1887143Y460163D01*
X1887268Y460413D01*
X1887435Y460622D01*
G01X1887060Y462680D02*
X1889560D01*
X1889060Y462180D01*
G01X1887060D02*
Y463180D01*
G01Y464697D02*
X1889560D01*
X1887477Y465780D01*
X1889560Y466863D01*
X1887060D01*
G01X1887435Y467963D02*
X1887227Y468213D01*
X1887102Y468505D01*
X1887060Y468880D01*
X1887143Y469255D01*
X1887310Y469547D01*
X1887602Y469755D01*
X1887935Y469797D01*
X1888268Y469713D01*
X1888477Y469505D01*
X1888643Y469213D01*
X1888685Y468922D01*
X1888643Y468630D01*
X1888477Y468255D01*
X1889560Y468380D01*
Y469505D01*
G01X1896200Y454700D02*
X1918772D01*
G01X1896200D02*
Y457395D01*
G01X1877250Y461750D02*
X1879750D01*
G01X1872500Y459500D02*
Y456250D01*
X1876000D01*
G01X1884500Y459500D02*
Y456250D01*
X1881000D01*
G01X1852476Y494362D02*
Y507736D01*
G01Y510613D02*
Y513850D01*
X1856000D01*
Y534800D01*
X1849600D01*
Y539400D01*
G01X1876811Y513637D02*
Y502000D01*
X1878500D01*
Y496500D01*
X1879856D01*
Y481896D01*
X1852588D01*
Y485921D01*
G01X1841200Y470667D02*
X1843700D01*
Y471708D01*
X1843575Y472042D01*
X1843408Y472250D01*
X1843075Y472333D01*
X1842742Y472250D01*
X1842533Y472000D01*
X1842408Y471708D01*
Y470667D01*
G01Y471708D02*
X1841200Y472333D01*
G01Y474600D02*
X1843700D01*
X1843200Y474100D01*
G01X1841200D02*
Y475100D01*
G01Y476617D02*
X1843700D01*
X1841617Y477700D01*
X1843700Y478783D01*
X1841200D01*
G01X1843283Y480008D02*
X1843533Y480258D01*
X1843658Y480550D01*
X1843700Y480883D01*
X1843617Y481300D01*
X1843408Y481592D01*
X1843158Y481675D01*
X1842908Y481633D01*
X1842700Y481467D01*
X1842283Y480633D01*
X1841992Y480258D01*
X1841575Y480008D01*
X1841200Y479925D01*
Y481675D01*
G01X1841575Y482983D02*
X1841367Y483233D01*
X1841242Y483525D01*
X1841200Y483900D01*
X1841283Y484275D01*
X1841450Y484567D01*
X1841742Y484775D01*
X1842075Y484817D01*
X1842408Y484733D01*
X1842617Y484525D01*
X1842783Y484233D01*
X1842825Y483942D01*
X1842783Y483650D01*
X1842617Y483275D01*
X1843700Y483400D01*
Y484525D01*
G01X1908052Y510762D02*
Y513262D01*
X1907011D01*
X1906677Y513137D01*
X1906469Y512970D01*
X1906386Y512637D01*
X1906469Y512304D01*
X1906719Y512095D01*
X1907011Y511970D01*
X1908052D01*
G01X1907011D02*
X1906386Y510762D01*
G01X1904119D02*
Y513262D01*
X1904619Y512762D01*
G01Y510762D02*
X1903619D01*
G01X1901936Y513262D02*
Y511470D01*
X1901769Y511095D01*
X1901436Y510845D01*
X1901019Y510762D01*
X1900602Y510845D01*
X1900269Y511095D01*
X1900102Y511470D01*
Y513262D01*
G01X1897919Y510762D02*
Y513262D01*
X1898419Y512762D01*
G01Y510762D02*
X1897419D01*
G01X1895527Y511054D02*
X1895236Y510845D01*
X1894902Y510762D01*
X1894569Y510845D01*
X1894277Y511095D01*
X1894069Y511470D01*
X1893986Y511845D01*
Y512304D01*
X1894069Y512679D01*
X1894277Y513012D01*
X1894527Y513179D01*
X1894819Y513262D01*
X1895152Y513179D01*
X1895402Y513012D01*
X1895569Y512762D01*
X1895652Y512429D01*
X1895569Y512137D01*
X1895361Y511845D01*
X1895111Y511679D01*
X1894819Y511637D01*
X1894486Y511720D01*
X1894236Y511929D01*
X1893986Y512304D01*
G01X1907033Y507200D02*
Y509700D01*
X1905992D01*
X1905658Y509575D01*
X1905450Y509408D01*
X1905367Y509075D01*
X1905450Y508742D01*
X1905700Y508533D01*
X1905992Y508408D01*
X1907033D01*
G01X1905992D02*
X1905367Y507200D01*
G01X1903100D02*
Y509700D01*
X1903600Y509200D01*
G01Y507200D02*
X1902600D01*
G01X1900917Y509700D02*
Y507908D01*
X1900750Y507533D01*
X1900417Y507283D01*
X1900000Y507200D01*
X1899583Y507283D01*
X1899250Y507533D01*
X1899083Y507908D01*
Y509700D01*
G01X1897692Y509283D02*
X1897442Y509533D01*
X1897150Y509658D01*
X1896817Y509700D01*
X1896400Y509617D01*
X1896108Y509408D01*
X1896025Y509158D01*
X1896067Y508908D01*
X1896233Y508700D01*
X1897067Y508283D01*
X1897442Y507992D01*
X1897692Y507575D01*
X1897775Y507200D01*
X1896025D01*
G01X1893800Y509700D02*
X1894133Y509617D01*
X1894383Y509408D01*
X1894550Y509158D01*
X1894675Y508825D01*
X1894717Y508450D01*
X1894675Y508075D01*
X1894550Y507742D01*
X1894383Y507492D01*
X1894133Y507283D01*
X1893800Y507200D01*
X1893467Y507283D01*
X1893217Y507492D01*
X1893050Y507742D01*
X1892925Y508075D01*
X1892883Y508450D01*
X1892925Y508825D01*
X1893050Y509158D01*
X1893217Y509408D01*
X1893467Y509617D01*
X1893800Y509700D01*
G01X1883413Y514597D02*
X1885913D01*
Y515638D01*
X1885788Y515972D01*
X1885621Y516180D01*
X1885288Y516263D01*
X1884955Y516180D01*
X1884746Y515930D01*
X1884621Y515638D01*
Y514597D01*
G01Y515638D02*
X1883413Y516263D01*
G01Y518530D02*
X1885913D01*
X1885413Y518030D01*
G01X1883413D02*
Y519030D01*
G01X1885913Y520380D02*
X1883413Y520963D01*
X1885913Y521630D01*
X1883413Y522297D01*
X1885913Y522880D01*
G01X1883913Y523813D02*
X1883621Y524063D01*
X1883455Y524397D01*
X1883413Y524772D01*
X1883455Y525105D01*
X1883663Y525438D01*
X1883913Y525647D01*
X1884163Y525688D01*
X1884455Y525605D01*
X1884663Y525313D01*
X1884746Y525022D01*
Y524647D01*
G01Y525022D02*
X1884871Y525272D01*
X1885080Y525480D01*
X1885330Y525563D01*
X1885580Y525480D01*
X1885788Y525272D01*
X1885913Y524897D01*
X1885871Y524522D01*
X1885705Y524147D01*
G01X1883705Y527122D02*
X1883496Y527413D01*
X1883413Y527747D01*
X1883496Y528080D01*
X1883746Y528372D01*
X1884121Y528580D01*
X1884496Y528663D01*
X1884955D01*
X1885330Y528580D01*
X1885663Y528372D01*
X1885830Y528122D01*
X1885913Y527830D01*
X1885830Y527497D01*
X1885663Y527247D01*
X1885413Y527080D01*
X1885080Y526997D01*
X1884788Y527080D01*
X1884496Y527288D01*
X1884330Y527538D01*
X1884288Y527830D01*
X1884371Y528163D01*
X1884580Y528413D01*
X1884955Y528663D01*
G01X1880046Y499430D02*
X1882546D01*
Y500471D01*
X1882421Y500805D01*
X1882254Y501013D01*
X1881921Y501096D01*
X1881588Y501013D01*
X1881379Y500763D01*
X1881254Y500471D01*
Y499430D01*
G01Y500471D02*
X1880046Y501096D01*
G01Y503363D02*
X1882546D01*
X1882046Y502863D01*
G01X1880046D02*
Y503863D01*
G01X1882546Y505213D02*
X1880046Y505796D01*
X1882546Y506463D01*
X1880046Y507130D01*
X1882546Y507713D01*
G01X1880546Y508646D02*
X1880254Y508896D01*
X1880088Y509230D01*
X1880046Y509605D01*
X1880088Y509938D01*
X1880296Y510271D01*
X1880546Y510480D01*
X1880796Y510521D01*
X1881088Y510438D01*
X1881296Y510146D01*
X1881379Y509855D01*
Y509480D01*
G01Y509855D02*
X1881504Y510105D01*
X1881713Y510313D01*
X1881963Y510396D01*
X1882213Y510313D01*
X1882421Y510105D01*
X1882546Y509730D01*
X1882504Y509355D01*
X1882338Y508980D01*
G01X1880046Y512663D02*
X1880088Y512955D01*
X1880213Y513288D01*
X1880421Y513496D01*
X1880713Y513580D01*
X1881004Y513496D01*
X1881254Y513246D01*
X1881379Y512871D01*
Y512455D01*
X1881463Y512205D01*
X1881671Y511996D01*
X1881963Y511913D01*
X1882254Y512038D01*
X1882463Y512330D01*
X1882546Y512663D01*
X1882463Y512996D01*
X1882254Y513288D01*
X1881963Y513413D01*
X1881671Y513330D01*
X1881463Y513121D01*
X1881379Y512871D01*
Y512455D01*
X1881254Y512080D01*
X1881004Y511830D01*
X1880713Y511746D01*
X1880421Y511830D01*
X1880213Y512038D01*
X1880088Y512371D01*
X1880046Y512663D01*
G01X1898772Y476357D02*
X1898897Y476107D01*
X1898980Y475815D01*
Y475482D01*
X1898855Y475107D01*
X1898647Y474815D01*
X1898397Y474607D01*
X1897980Y474440D01*
X1897605Y474398D01*
X1897230Y474482D01*
X1896980Y474607D01*
X1896730Y474857D01*
X1896563Y475148D01*
X1896480Y475440D01*
Y475732D01*
X1896563Y476023D01*
X1896688Y476273D01*
X1896855Y476482D01*
G01X1896772Y477832D02*
X1896563Y478123D01*
X1896480Y478457D01*
X1896563Y478790D01*
X1896813Y479082D01*
X1897188Y479290D01*
X1897563Y479373D01*
X1898022D01*
X1898397Y479290D01*
X1898730Y479082D01*
X1898897Y478832D01*
X1898980Y478540D01*
X1898897Y478207D01*
X1898730Y477957D01*
X1898480Y477790D01*
X1898147Y477707D01*
X1897855Y477790D01*
X1897563Y477998D01*
X1897397Y478248D01*
X1897355Y478540D01*
X1897438Y478873D01*
X1897647Y479123D01*
X1898022Y479373D01*
G01X1897813Y481973D02*
X1897938Y482140D01*
X1898147Y482265D01*
X1898438Y482348D01*
X1898688Y482265D01*
X1898855Y482098D01*
X1898980Y481807D01*
Y480682D01*
X1896480D01*
Y482057D01*
X1896647Y482348D01*
X1896897Y482515D01*
X1897188Y482598D01*
X1897480Y482515D01*
X1897730Y482265D01*
X1897813Y481973D01*
Y480682D01*
G01X1896480Y484740D02*
X1898980D01*
X1898480Y484240D01*
G01X1896480D02*
Y485240D01*
G01X1898980Y487840D02*
X1898897Y487507D01*
X1898688Y487257D01*
X1898438Y487090D01*
X1898105Y486965D01*
X1897730Y486923D01*
X1897355Y486965D01*
X1897022Y487090D01*
X1896772Y487257D01*
X1896563Y487507D01*
X1896480Y487840D01*
X1896563Y488173D01*
X1896772Y488423D01*
X1897022Y488590D01*
X1897355Y488715D01*
X1897730Y488757D01*
X1898105Y488715D01*
X1898438Y488590D01*
X1898688Y488423D01*
X1898897Y488173D01*
X1898980Y487840D01*
G01X1896200Y472700D02*
X1918775D01*
G01X1896200D02*
Y470002D01*
G01X1864470Y514862D02*
Y522234D01*
G01X1876670Y514863D02*
Y522251D01*
G01X1847492Y473617D02*
X1847617Y473367D01*
X1847700Y473075D01*
Y472742D01*
X1847575Y472367D01*
X1847367Y472075D01*
X1847117Y471867D01*
X1846700Y471700D01*
X1846325Y471658D01*
X1845950Y471742D01*
X1845700Y471867D01*
X1845450Y472117D01*
X1845283Y472408D01*
X1845200Y472700D01*
Y472992D01*
X1845283Y473283D01*
X1845408Y473533D01*
X1845575Y473742D01*
G01X1845200Y474967D02*
X1847700D01*
Y476008D01*
X1847575Y476342D01*
X1847408Y476550D01*
X1847075Y476633D01*
X1846742Y476550D01*
X1846533Y476300D01*
X1846408Y476008D01*
Y474967D01*
G01Y476008D02*
X1845200Y476633D01*
G01X1846242Y478108D02*
X1846533Y478400D01*
X1846700Y478650D01*
X1846783Y478983D01*
X1846700Y479275D01*
X1846533Y479483D01*
X1846283Y479650D01*
X1845992Y479692D01*
X1845742Y479650D01*
X1845492Y479483D01*
X1845283Y479233D01*
X1845200Y478942D01*
X1845283Y478608D01*
X1845533Y478317D01*
X1845908Y478150D01*
X1846325Y478108D01*
X1846867Y478192D01*
X1847158Y478317D01*
X1847450Y478525D01*
X1847658Y478817D01*
X1847700Y479108D01*
X1847617Y479400D01*
X1847408Y479608D01*
G01X1847700Y480750D02*
X1845200Y481333D01*
X1847700Y482000D01*
X1845200Y482667D01*
X1847700Y483250D01*
G01X1847283Y484308D02*
X1847533Y484558D01*
X1847658Y484850D01*
X1847700Y485183D01*
X1847617Y485600D01*
X1847408Y485892D01*
X1847158Y485975D01*
X1846908Y485933D01*
X1846700Y485767D01*
X1846283Y484933D01*
X1845992Y484558D01*
X1845575Y484308D01*
X1845200Y484225D01*
Y485975D01*
G01X1844034Y526632D02*
Y523043D01*
X1842141D01*
X1844034Y519764D01*
X1845927Y523043D01*
X1844034D01*
G01X1845927Y519764D02*
X1842141D01*
G01X1844034Y515341D02*
Y519764D01*
G01X1851242Y481567D02*
X1851367Y481317D01*
X1851450Y481025D01*
Y480692D01*
X1851325Y480317D01*
X1851117Y480025D01*
X1850867Y479817D01*
X1850450Y479650D01*
X1850075Y479608D01*
X1849700Y479692D01*
X1849450Y479817D01*
X1849200Y480067D01*
X1849033Y480358D01*
X1848950Y480650D01*
Y480942D01*
X1849033Y481233D01*
X1849158Y481483D01*
X1849325Y481692D01*
G01X1848950Y482917D02*
X1851450D01*
Y483958D01*
X1851325Y484292D01*
X1851158Y484500D01*
X1850825Y484583D01*
X1850492Y484500D01*
X1850283Y484250D01*
X1850158Y483958D01*
Y482917D01*
G01Y483958D02*
X1848950Y484583D01*
G01X1849992Y486058D02*
X1850283Y486350D01*
X1850450Y486600D01*
X1850533Y486933D01*
X1850450Y487225D01*
X1850283Y487433D01*
X1850033Y487600D01*
X1849742Y487642D01*
X1849492Y487600D01*
X1849242Y487433D01*
X1849033Y487183D01*
X1848950Y486892D01*
X1849033Y486558D01*
X1849283Y486267D01*
X1849658Y486100D01*
X1850075Y486058D01*
X1850617Y486142D01*
X1850908Y486267D01*
X1851200Y486475D01*
X1851408Y486767D01*
X1851450Y487058D01*
X1851367Y487350D01*
X1851158Y487558D01*
G01X1851450Y488700D02*
X1848950Y489283D01*
X1851450Y489950D01*
X1848950Y490617D01*
X1851450Y491200D01*
G01X1848950Y493050D02*
X1851450D01*
X1850950Y492550D01*
G01X1848950D02*
Y493550D01*
G01X1851138Y526366D02*
Y522777D01*
X1849245D01*
X1851138Y519498D01*
X1853031Y522777D01*
X1851138D01*
G01X1853031Y519498D02*
X1849245D01*
G01X1851138Y515075D02*
Y519498D01*
G01X1890463Y498550D02*
X1890233Y498188D01*
X1889927Y497982D01*
X1889582Y497930D01*
X1889275Y497982D01*
X1888968Y498240D01*
X1888777Y498550D01*
X1888738Y498860D01*
X1888815Y499222D01*
X1889083Y499480D01*
X1889352Y499583D01*
X1889697D01*
G01X1889352D02*
X1889122Y499738D01*
X1888930Y499997D01*
X1888853Y500307D01*
X1888930Y500617D01*
X1889122Y500875D01*
X1889467Y501030D01*
X1889812Y500978D01*
X1890157Y500772D01*
G01X1883049Y466889D02*
X1883382Y466931D01*
X1883674Y467097D01*
X1883924Y467347D01*
X1884091Y467639D01*
X1884174Y467972D01*
Y468306D01*
X1884091Y468639D01*
X1883924Y468931D01*
X1883674Y469181D01*
X1883382Y469347D01*
X1883049Y469389D01*
X1882716Y469347D01*
X1882424Y469181D01*
X1882174Y468931D01*
X1882007Y468639D01*
X1881924Y468306D01*
Y467972D01*
X1882007Y467639D01*
X1882174Y467347D01*
X1882424Y467097D01*
X1882716Y466931D01*
X1883049Y466889D01*
G01X1882716Y467556D02*
X1882216Y466889D01*
G01X1879949D02*
Y469389D01*
X1880449Y468889D01*
G01Y466889D02*
X1879449D01*
G01X1878099Y469389D02*
X1877516Y466889D01*
X1876849Y469389D01*
X1876182Y466889D01*
X1875599Y469389D01*
G01X1873749Y466889D02*
Y469389D01*
X1874249Y468889D01*
G01Y466889D02*
X1873249D01*
G01X1890733Y477990D02*
Y480490D01*
X1889692D01*
X1889358Y480365D01*
X1889150Y480198D01*
X1889067Y479865D01*
X1889150Y479532D01*
X1889400Y479323D01*
X1889692Y479198D01*
X1890733D01*
G01X1889692D02*
X1889067Y477990D01*
G01X1886800D02*
Y480490D01*
X1887300Y479990D01*
G01Y477990D02*
X1886300D01*
G01X1884950Y480490D02*
X1884367Y477990D01*
X1883700Y480490D01*
X1883033Y477990D01*
X1882450Y480490D01*
G01X1880600Y477990D02*
Y480490D01*
X1881100Y479990D01*
G01Y477990D02*
X1880100D01*
G01X1888466Y475995D02*
Y471995D01*
X1881066D01*
G01X1877160Y529190D02*
Y536500D01*
X1891900D01*
Y559198D01*
X1900527D01*
Y558517D01*
X1904585D01*
Y559998D01*
X1917500D01*
Y560000D01*
G01X1880100Y593100D02*
X1869572D01*
Y578427D01*
X1868189D01*
G01X1850500Y553200D02*
Y557100D01*
X1854500D01*
Y570498D01*
X1859400D01*
Y575302D01*
G01X1841379Y570998D02*
X1843879D01*
Y572039D01*
X1843754Y572373D01*
X1843587Y572581D01*
X1843254Y572664D01*
X1842921Y572581D01*
X1842712Y572331D01*
X1842587Y572039D01*
Y570998D01*
G01Y572039D02*
X1841379Y572664D01*
G01Y574931D02*
X1843879D01*
X1843379Y574431D01*
G01X1841379D02*
Y575431D01*
G01X1843879Y577198D02*
X1841379D01*
Y578864D01*
G01Y581131D02*
X1843879D01*
X1843379Y580631D01*
G01X1841379D02*
Y581631D01*
G01Y584148D02*
X1841921Y584231D01*
X1842379Y584356D01*
X1842796Y584523D01*
X1843254Y584731D01*
X1843879Y585064D01*
Y583398D01*
G01X1861594Y586149D02*
Y583049D01*
X1860176Y585271D01*
X1862092D01*
G01X1895506Y530363D02*
X1895237Y530104D01*
X1894931Y530001D01*
X1894624Y530104D01*
X1894356Y530414D01*
X1894164Y530879D01*
X1894087Y531344D01*
Y531913D01*
X1894164Y532378D01*
X1894356Y532791D01*
X1894586Y532998D01*
X1894854Y533101D01*
X1895161Y532998D01*
X1895391Y532791D01*
X1895544Y532481D01*
X1895621Y532068D01*
X1895544Y531706D01*
X1895352Y531344D01*
X1895122Y531138D01*
X1894854Y531086D01*
X1894547Y531189D01*
X1894317Y531448D01*
X1894087Y531913D01*
G01X1892350Y580087D02*
Y577587D01*
G01X1890100Y584837D02*
X1886850D01*
Y581337D01*
G01X1890100Y572837D02*
X1886850D01*
Y576337D01*
G01X1903250Y537900D02*
X1903583Y537942D01*
X1903875Y538108D01*
X1904125Y538358D01*
X1904292Y538650D01*
X1904375Y538983D01*
Y539317D01*
X1904292Y539650D01*
X1904125Y539942D01*
X1903875Y540192D01*
X1903583Y540358D01*
X1903250Y540400D01*
X1902917Y540358D01*
X1902625Y540192D01*
X1902375Y539942D01*
X1902208Y539650D01*
X1902125Y539317D01*
Y538983D01*
X1902208Y538650D01*
X1902375Y538358D01*
X1902625Y538108D01*
X1902917Y537942D01*
X1903250Y537900D01*
G01X1902917Y538567D02*
X1902417Y537900D01*
G01X1900150D02*
Y540400D01*
X1900650Y539900D01*
G01Y537900D02*
X1899650D01*
G01X1897883Y540400D02*
Y537900D01*
X1896217D01*
G01X1894867Y538400D02*
X1894617Y538108D01*
X1894283Y537942D01*
X1893908Y537900D01*
X1893575Y537942D01*
X1893242Y538150D01*
X1893033Y538400D01*
X1892992Y538650D01*
X1893075Y538942D01*
X1893367Y539150D01*
X1893658Y539233D01*
X1894033D01*
G01X1893658D02*
X1893408Y539358D01*
X1893200Y539567D01*
X1893117Y539817D01*
X1893200Y540067D01*
X1893408Y540275D01*
X1893783Y540400D01*
X1894158Y540358D01*
X1894533Y540192D01*
G01X1872754Y570638D02*
X1875904Y567488D01*
X1879054Y570638D01*
G01X1891404D02*
X1870404D01*
Y538988D01*
X1881404D01*
Y570638D01*
G01X1933000Y560000D02*
X1938600D01*
Y620600D01*
X1886500D01*
Y596200D01*
X1880100D01*
G01X1890377Y618880D02*
X1890607Y619242D01*
X1890913Y619448D01*
X1891258Y619500D01*
X1891565Y619448D01*
X1891872Y619190D01*
X1892063Y618880D01*
X1892102Y618570D01*
X1892025Y618208D01*
X1891757Y617950D01*
X1891488Y617847D01*
X1891143D01*
G01X1891488D02*
X1891718Y617692D01*
X1891910Y617433D01*
X1891987Y617123D01*
X1891910Y616813D01*
X1891718Y616555D01*
X1891373Y616400D01*
X1891028Y616452D01*
X1890683Y616658D01*
G01X1926329Y-21185D02*
Y-18685D01*
X1925288D01*
X1924954Y-18810D01*
X1924746Y-18977D01*
X1924663Y-19310D01*
X1924746Y-19643D01*
X1924996Y-19852D01*
X1925288Y-19977D01*
X1926329D01*
G01X1925288D02*
X1924663Y-21185D01*
G01X1923104Y-20893D02*
X1922813Y-21102D01*
X1922479Y-21185D01*
X1922146Y-21102D01*
X1921854Y-20852D01*
X1921646Y-20477D01*
X1921563Y-20102D01*
Y-19643D01*
X1921646Y-19268D01*
X1921854Y-18935D01*
X1922104Y-18768D01*
X1922396Y-18685D01*
X1922729Y-18768D01*
X1922979Y-18935D01*
X1923146Y-19185D01*
X1923229Y-19518D01*
X1923146Y-19810D01*
X1922938Y-20102D01*
X1922688Y-20268D01*
X1922396Y-20310D01*
X1922063Y-20227D01*
X1921813Y-20018D01*
X1921563Y-19643D01*
G01X1919046Y-19935D02*
X1918213D01*
Y-20685D01*
X1918463Y-20935D01*
X1918754Y-21102D01*
X1919171Y-21185D01*
X1919588Y-21102D01*
X1919879Y-20935D01*
X1920129Y-20685D01*
X1920296Y-20393D01*
X1920379Y-20060D01*
Y-19768D01*
X1920296Y-19518D01*
X1920129Y-19227D01*
X1919879Y-18977D01*
X1919629Y-18810D01*
X1919296Y-18685D01*
X1919004D01*
X1918671Y-18768D01*
X1918421Y-18935D01*
G01X1915696Y-21185D02*
Y-18685D01*
X1917238Y-20477D01*
X1915154D01*
G01X1916418Y60624D02*
Y63124D01*
X1915377D01*
X1915043Y62999D01*
X1914835Y62832D01*
X1914752Y62499D01*
X1914835Y62166D01*
X1915085Y61957D01*
X1915377Y61832D01*
X1916418D01*
G01X1915377D02*
X1914752Y60624D01*
G01X1913193Y60916D02*
X1912902Y60707D01*
X1912568Y60624D01*
X1912235Y60707D01*
X1911943Y60957D01*
X1911735Y61332D01*
X1911652Y61707D01*
Y62166D01*
X1911735Y62541D01*
X1911943Y62874D01*
X1912193Y63041D01*
X1912485Y63124D01*
X1912818Y63041D01*
X1913068Y62874D01*
X1913235Y62624D01*
X1913318Y62291D01*
X1913235Y61999D01*
X1913027Y61707D01*
X1912777Y61541D01*
X1912485Y61499D01*
X1912152Y61582D01*
X1911902Y61791D01*
X1911652Y62166D01*
G01X1909135Y61874D02*
X1908302D01*
Y61124D01*
X1908552Y60874D01*
X1908843Y60707D01*
X1909260Y60624D01*
X1909677Y60707D01*
X1909968Y60874D01*
X1910218Y61124D01*
X1910385Y61416D01*
X1910468Y61749D01*
Y62041D01*
X1910385Y62291D01*
X1910218Y62582D01*
X1909968Y62832D01*
X1909718Y62999D01*
X1909385Y63124D01*
X1909093D01*
X1908760Y63041D01*
X1908510Y62874D01*
G01X1907077Y62707D02*
X1906827Y62957D01*
X1906535Y63082D01*
X1906202Y63124D01*
X1905785Y63041D01*
X1905493Y62832D01*
X1905410Y62582D01*
X1905452Y62332D01*
X1905618Y62124D01*
X1906452Y61707D01*
X1906827Y61416D01*
X1907077Y60999D01*
X1907160Y60624D01*
X1905410D01*
G01X1943326Y66031D02*
Y68531D01*
X1942285D01*
X1941951Y68406D01*
X1941743Y68239D01*
X1941660Y67906D01*
X1941743Y67573D01*
X1941993Y67364D01*
X1942285Y67239D01*
X1943326D01*
G01X1942285D02*
X1941660Y66031D01*
G01X1939393D02*
Y68531D01*
X1939893Y68031D01*
G01Y66031D02*
X1938893D01*
G01X1937126D02*
Y68531D01*
X1936085D01*
X1935751Y68406D01*
X1935543Y68239D01*
X1935460Y67906D01*
X1935543Y67573D01*
X1935793Y67364D01*
X1936085Y67239D01*
X1937126D01*
G01X1936085D02*
X1935460Y66031D01*
G01X1934110Y66531D02*
X1933860Y66239D01*
X1933526Y66073D01*
X1933151Y66031D01*
X1932818Y66073D01*
X1932485Y66281D01*
X1932276Y66531D01*
X1932235Y66781D01*
X1932318Y67073D01*
X1932610Y67281D01*
X1932901Y67364D01*
X1933276D01*
G01X1932901D02*
X1932651Y67489D01*
X1932443Y67698D01*
X1932360Y67948D01*
X1932443Y68198D01*
X1932651Y68406D01*
X1933026Y68531D01*
X1933401Y68489D01*
X1933776Y68323D01*
G01X1913933Y75392D02*
X1914183Y75517D01*
X1914475Y75600D01*
X1914808D01*
X1915183Y75475D01*
X1915475Y75267D01*
X1915683Y75017D01*
X1915850Y74600D01*
X1915892Y74225D01*
X1915808Y73850D01*
X1915683Y73600D01*
X1915433Y73350D01*
X1915142Y73183D01*
X1914850Y73100D01*
X1914558D01*
X1914267Y73183D01*
X1914017Y73308D01*
X1913808Y73475D01*
G01X1912458Y73392D02*
X1912167Y73183D01*
X1911833Y73100D01*
X1911500Y73183D01*
X1911208Y73433D01*
X1911000Y73808D01*
X1910917Y74183D01*
Y74642D01*
X1911000Y75017D01*
X1911208Y75350D01*
X1911458Y75517D01*
X1911750Y75600D01*
X1912083Y75517D01*
X1912333Y75350D01*
X1912500Y75100D01*
X1912583Y74767D01*
X1912500Y74475D01*
X1912292Y74183D01*
X1912042Y74017D01*
X1911750Y73975D01*
X1911417Y74058D01*
X1911167Y74267D01*
X1910917Y74642D01*
G01X1908400Y74350D02*
X1907567D01*
Y73600D01*
X1907817Y73350D01*
X1908108Y73183D01*
X1908525Y73100D01*
X1908942Y73183D01*
X1909233Y73350D01*
X1909483Y73600D01*
X1909650Y73892D01*
X1909733Y74225D01*
Y74517D01*
X1909650Y74767D01*
X1909483Y75058D01*
X1909233Y75308D01*
X1908983Y75475D01*
X1908650Y75600D01*
X1908358D01*
X1908025Y75517D01*
X1907775Y75350D01*
G01X1905550Y73100D02*
Y75600D01*
X1906050Y75100D01*
G01Y73100D02*
X1905050D01*
G01X1913250Y78733D02*
X1911458D01*
X1911083Y78900D01*
X1910833Y79233D01*
X1910750Y79650D01*
X1910833Y80067D01*
X1911083Y80400D01*
X1911458Y80567D01*
X1913250D01*
G01X1911042Y82042D02*
X1910833Y82333D01*
X1910750Y82667D01*
X1910833Y83000D01*
X1911083Y83292D01*
X1911458Y83500D01*
X1911833Y83583D01*
X1912292D01*
X1912667Y83500D01*
X1913000Y83292D01*
X1913167Y83042D01*
X1913250Y82750D01*
X1913167Y82417D01*
X1913000Y82167D01*
X1912750Y82000D01*
X1912417Y81917D01*
X1912125Y82000D01*
X1911833Y82208D01*
X1911667Y82458D01*
X1911625Y82750D01*
X1911708Y83083D01*
X1911917Y83333D01*
X1912292Y83583D01*
G01X1910750Y86683D02*
Y85017D01*
X1913250D01*
Y86683D01*
G01X1912042Y86017D02*
Y85017D01*
G01X1910750Y88950D02*
X1913250D01*
X1912750Y88450D01*
G01X1910750D02*
Y89450D01*
G01X1936629Y89570D02*
X1930729D01*
Y94570D01*
X1936629D01*
G01Y86270D02*
Y97770D01*
X1915129D01*
Y86270D01*
X1936629D01*
G01X1918800Y160600D02*
X1924600D01*
Y153900D01*
X1934300D01*
Y148600D01*
X1939000D01*
Y147200D01*
X1949200D01*
G01X1953200Y147600D02*
X1960000D01*
G01X1972833Y128667D02*
Y131167D01*
X1971792D01*
X1971458Y131042D01*
X1971250Y130875D01*
X1971167Y130542D01*
X1971250Y130209D01*
X1971500Y130000D01*
X1971792Y129875D01*
X1972833D01*
G01X1971792D02*
X1971167Y128667D01*
G01X1969608Y128959D02*
X1969317Y128750D01*
X1968983Y128667D01*
X1968650Y128750D01*
X1968358Y129000D01*
X1968150Y129375D01*
X1968067Y129750D01*
Y130209D01*
X1968150Y130584D01*
X1968358Y130917D01*
X1968608Y131084D01*
X1968900Y131167D01*
X1969233Y131084D01*
X1969483Y130917D01*
X1969650Y130667D01*
X1969733Y130334D01*
X1969650Y130042D01*
X1969442Y129750D01*
X1969192Y129584D01*
X1968900Y129542D01*
X1968567Y129625D01*
X1968317Y129834D01*
X1968067Y130209D01*
G01X1966592Y128667D02*
Y131167D01*
X1965008D01*
G01X1965592Y129959D02*
X1966592D01*
G01X1963492Y129709D02*
X1963200Y130000D01*
X1962950Y130167D01*
X1962617Y130250D01*
X1962325Y130167D01*
X1962117Y130000D01*
X1961950Y129750D01*
X1961908Y129459D01*
X1961950Y129209D01*
X1962117Y128959D01*
X1962367Y128750D01*
X1962658Y128667D01*
X1962992Y128750D01*
X1963283Y129000D01*
X1963450Y129375D01*
X1963492Y129792D01*
X1963408Y130334D01*
X1963283Y130625D01*
X1963075Y130917D01*
X1962783Y131125D01*
X1962492Y131167D01*
X1962200Y131084D01*
X1961992Y130875D01*
G01X1960517Y129042D02*
X1960267Y128834D01*
X1959975Y128709D01*
X1959600Y128667D01*
X1959225Y128750D01*
X1958933Y128917D01*
X1958725Y129209D01*
X1958683Y129542D01*
X1958767Y129875D01*
X1958975Y130084D01*
X1959267Y130250D01*
X1959558Y130292D01*
X1959850Y130250D01*
X1960225Y130084D01*
X1960100Y131167D01*
X1958975D01*
G01X1956333Y128767D02*
Y131267D01*
X1955292D01*
X1954958Y131142D01*
X1954750Y130975D01*
X1954667Y130642D01*
X1954750Y130309D01*
X1955000Y130100D01*
X1955292Y129975D01*
X1956333D01*
G01X1955292D02*
X1954667Y128767D01*
G01X1953108Y129059D02*
X1952817Y128850D01*
X1952483Y128767D01*
X1952150Y128850D01*
X1951858Y129100D01*
X1951650Y129475D01*
X1951567Y129850D01*
Y130309D01*
X1951650Y130684D01*
X1951858Y131017D01*
X1952108Y131184D01*
X1952400Y131267D01*
X1952733Y131184D01*
X1952983Y131017D01*
X1953150Y130767D01*
X1953233Y130434D01*
X1953150Y130142D01*
X1952942Y129850D01*
X1952692Y129684D01*
X1952400Y129642D01*
X1952067Y129725D01*
X1951817Y129934D01*
X1951567Y130309D01*
G01X1950092Y128767D02*
Y131267D01*
X1948508D01*
G01X1949092Y130059D02*
X1950092D01*
G01X1946992Y129809D02*
X1946700Y130100D01*
X1946450Y130267D01*
X1946117Y130350D01*
X1945825Y130267D01*
X1945617Y130100D01*
X1945450Y129850D01*
X1945408Y129559D01*
X1945450Y129309D01*
X1945617Y129059D01*
X1945867Y128850D01*
X1946158Y128767D01*
X1946492Y128850D01*
X1946783Y129100D01*
X1946950Y129475D01*
X1946992Y129892D01*
X1946908Y130434D01*
X1946783Y130725D01*
X1946575Y131017D01*
X1946283Y131225D01*
X1945992Y131267D01*
X1945700Y131184D01*
X1945492Y130975D01*
G01X1943892Y129809D02*
X1943600Y130100D01*
X1943350Y130267D01*
X1943017Y130350D01*
X1942725Y130267D01*
X1942517Y130100D01*
X1942350Y129850D01*
X1942308Y129559D01*
X1942350Y129309D01*
X1942517Y129059D01*
X1942767Y128850D01*
X1943058Y128767D01*
X1943392Y128850D01*
X1943683Y129100D01*
X1943850Y129475D01*
X1943892Y129892D01*
X1943808Y130434D01*
X1943683Y130725D01*
X1943475Y131017D01*
X1943183Y131225D01*
X1942892Y131267D01*
X1942600Y131184D01*
X1942392Y130975D01*
G01X1939535Y111517D02*
X1942035D01*
Y112558D01*
X1941910Y112892D01*
X1941743Y113100D01*
X1941410Y113183D01*
X1941077Y113100D01*
X1940868Y112850D01*
X1940743Y112558D01*
Y111517D01*
G01Y112558D02*
X1939535Y113183D01*
G01Y115450D02*
X1942035D01*
X1941535Y114950D01*
G01X1939535D02*
Y115950D01*
G01Y117717D02*
X1942035D01*
Y118758D01*
X1941910Y119092D01*
X1941743Y119300D01*
X1941410Y119383D01*
X1941077Y119300D01*
X1940868Y119050D01*
X1940743Y118758D01*
Y117717D01*
G01Y118758D02*
X1939535Y119383D01*
G01X1939827Y120942D02*
X1939618Y121233D01*
X1939535Y121567D01*
X1939618Y121900D01*
X1939868Y122192D01*
X1940243Y122400D01*
X1940618Y122483D01*
X1941077D01*
X1941452Y122400D01*
X1941785Y122192D01*
X1941952Y121942D01*
X1942035Y121650D01*
X1941952Y121317D01*
X1941785Y121067D01*
X1941535Y120900D01*
X1941202Y120817D01*
X1940910Y120900D01*
X1940618Y121108D01*
X1940452Y121358D01*
X1940410Y121650D01*
X1940493Y121983D01*
X1940702Y122233D01*
X1941077Y122483D01*
G01X1935720Y111517D02*
X1938220D01*
Y112558D01*
X1938095Y112892D01*
X1937928Y113100D01*
X1937595Y113183D01*
X1937262Y113100D01*
X1937053Y112850D01*
X1936928Y112558D01*
Y111517D01*
G01Y112558D02*
X1935720Y113183D01*
G01Y115450D02*
X1938220D01*
X1937720Y114950D01*
G01X1935720D02*
Y115950D01*
G01Y117717D02*
X1938220D01*
Y118758D01*
X1938095Y119092D01*
X1937928Y119300D01*
X1937595Y119383D01*
X1937262Y119300D01*
X1937053Y119050D01*
X1936928Y118758D01*
Y117717D01*
G01Y118758D02*
X1935720Y119383D01*
G01Y121567D02*
X1936262Y121650D01*
X1936720Y121775D01*
X1937137Y121942D01*
X1937595Y122150D01*
X1938220Y122483D01*
Y120817D01*
G01X1932067Y111538D02*
X1934567D01*
Y112579D01*
X1934442Y112913D01*
X1934275Y113121D01*
X1933942Y113204D01*
X1933609Y113121D01*
X1933400Y112871D01*
X1933275Y112579D01*
Y111538D01*
G01Y112579D02*
X1932067Y113204D01*
G01Y115471D02*
X1934567D01*
X1934067Y114971D01*
G01X1932067D02*
Y115971D01*
G01Y117738D02*
X1934567D01*
Y118779D01*
X1934442Y119113D01*
X1934275Y119321D01*
X1933942Y119404D01*
X1933609Y119321D01*
X1933400Y119071D01*
X1933275Y118779D01*
Y117738D01*
G01Y118779D02*
X1932067Y119404D01*
G01X1933109Y120879D02*
X1933400Y121171D01*
X1933567Y121421D01*
X1933650Y121754D01*
X1933567Y122046D01*
X1933400Y122254D01*
X1933150Y122421D01*
X1932859Y122463D01*
X1932609Y122421D01*
X1932359Y122254D01*
X1932150Y122004D01*
X1932067Y121713D01*
X1932150Y121379D01*
X1932400Y121088D01*
X1932775Y120921D01*
X1933192Y120879D01*
X1933734Y120963D01*
X1934025Y121088D01*
X1934317Y121296D01*
X1934525Y121588D01*
X1934567Y121879D01*
X1934484Y122171D01*
X1934275Y122379D01*
G01X1913283Y122950D02*
Y125450D01*
X1912242D01*
X1911908Y125325D01*
X1911700Y125158D01*
X1911617Y124825D01*
X1911700Y124492D01*
X1911950Y124283D01*
X1912242Y124158D01*
X1913283D01*
G01X1912242D02*
X1911617Y122950D01*
G01X1910142Y125033D02*
X1909892Y125283D01*
X1909600Y125408D01*
X1909267Y125450D01*
X1908850Y125367D01*
X1908558Y125158D01*
X1908475Y124908D01*
X1908517Y124658D01*
X1908683Y124450D01*
X1909517Y124033D01*
X1909892Y123742D01*
X1910142Y123325D01*
X1910225Y122950D01*
X1908475D01*
G01X1906250Y125450D02*
Y122950D01*
G01X1907208Y125450D02*
X1905292D01*
G01X1902650Y122950D02*
Y125450D01*
X1904192Y123658D01*
X1902108D01*
G01X1900133Y122950D02*
X1900050Y123492D01*
X1899925Y123950D01*
X1899758Y124367D01*
X1899550Y124825D01*
X1899217Y125450D01*
X1900883D01*
G01X1923733Y138950D02*
Y141450D01*
X1922692D01*
X1922358Y141325D01*
X1922150Y141158D01*
X1922067Y140825D01*
X1922150Y140492D01*
X1922400Y140283D01*
X1922692Y140158D01*
X1923733D01*
G01X1922692D02*
X1922067Y138950D01*
G01X1920508Y139242D02*
X1920217Y139033D01*
X1919883Y138950D01*
X1919550Y139033D01*
X1919258Y139283D01*
X1919050Y139658D01*
X1918967Y140033D01*
Y140492D01*
X1919050Y140867D01*
X1919258Y141200D01*
X1919508Y141367D01*
X1919800Y141450D01*
X1920133Y141367D01*
X1920383Y141200D01*
X1920550Y140950D01*
X1920633Y140617D01*
X1920550Y140325D01*
X1920342Y140033D01*
X1920092Y139867D01*
X1919800Y139825D01*
X1919467Y139908D01*
X1919217Y140117D01*
X1918967Y140492D01*
G01X1917950Y141450D02*
X1917367Y138950D01*
X1916700Y141450D01*
X1916033Y138950D01*
X1915450Y141450D01*
G01X1914517Y139450D02*
X1914267Y139158D01*
X1913933Y138992D01*
X1913558Y138950D01*
X1913225Y138992D01*
X1912892Y139200D01*
X1912683Y139450D01*
X1912642Y139700D01*
X1912725Y139992D01*
X1913017Y140200D01*
X1913308Y140283D01*
X1913683D01*
G01X1913308D02*
X1913058Y140408D01*
X1912850Y140617D01*
X1912767Y140867D01*
X1912850Y141117D01*
X1913058Y141325D01*
X1913433Y141450D01*
X1913808Y141408D01*
X1914183Y141242D01*
G01X1910000Y138950D02*
Y141450D01*
X1911542Y139658D01*
X1909458D01*
G01X1922133Y133150D02*
Y135650D01*
X1921092D01*
X1920758Y135525D01*
X1920550Y135358D01*
X1920467Y135025D01*
X1920550Y134692D01*
X1920800Y134483D01*
X1921092Y134358D01*
X1922133D01*
G01X1921092D02*
X1920467Y133150D01*
G01X1918908Y133442D02*
X1918617Y133233D01*
X1918283Y133150D01*
X1917950Y133233D01*
X1917658Y133483D01*
X1917450Y133858D01*
X1917367Y134233D01*
Y134692D01*
X1917450Y135067D01*
X1917658Y135400D01*
X1917908Y135567D01*
X1918200Y135650D01*
X1918533Y135567D01*
X1918783Y135400D01*
X1918950Y135150D01*
X1919033Y134817D01*
X1918950Y134525D01*
X1918742Y134233D01*
X1918492Y134067D01*
X1918200Y134025D01*
X1917867Y134108D01*
X1917617Y134317D01*
X1917367Y134692D01*
G01X1916350Y135650D02*
X1915767Y133150D01*
X1915100Y135650D01*
X1914433Y133150D01*
X1913850Y135650D01*
G01X1912917Y133650D02*
X1912667Y133358D01*
X1912333Y133192D01*
X1911958Y133150D01*
X1911625Y133192D01*
X1911292Y133400D01*
X1911083Y133650D01*
X1911042Y133900D01*
X1911125Y134192D01*
X1911417Y134400D01*
X1911708Y134483D01*
X1912083D01*
G01X1911708D02*
X1911458Y134608D01*
X1911250Y134817D01*
X1911167Y135067D01*
X1911250Y135317D01*
X1911458Y135525D01*
X1911833Y135650D01*
X1912208Y135608D01*
X1912583Y135442D01*
G01X1909817Y133525D02*
X1909567Y133317D01*
X1909275Y133192D01*
X1908900Y133150D01*
X1908525Y133233D01*
X1908233Y133400D01*
X1908025Y133692D01*
X1907983Y134025D01*
X1908067Y134358D01*
X1908275Y134567D01*
X1908567Y134733D01*
X1908858Y134775D01*
X1909150Y134733D01*
X1909525Y134567D01*
X1909400Y135650D01*
X1908275D01*
G01X1907459Y138867D02*
X1907584Y138617D01*
X1907667Y138325D01*
Y137992D01*
X1907542Y137617D01*
X1907334Y137325D01*
X1907084Y137117D01*
X1906667Y136950D01*
X1906292Y136908D01*
X1905917Y136992D01*
X1905667Y137117D01*
X1905417Y137367D01*
X1905250Y137658D01*
X1905167Y137950D01*
Y138242D01*
X1905250Y138533D01*
X1905375Y138783D01*
X1905542Y138992D01*
G01X1905167Y141050D02*
X1907667D01*
X1907167Y140550D01*
G01X1905167D02*
Y141550D01*
G01X1907667Y144150D02*
X1905167D01*
G01X1907667Y143192D02*
Y145108D01*
G01X1905167Y147750D02*
X1907667D01*
X1905875Y146208D01*
Y148292D01*
G01X1906216Y153603D02*
X1906341Y153353D01*
X1906424Y153061D01*
Y152728D01*
X1906299Y152353D01*
X1906091Y152061D01*
X1905841Y151853D01*
X1905424Y151686D01*
X1905049Y151644D01*
X1904674Y151728D01*
X1904424Y151853D01*
X1904174Y152103D01*
X1904007Y152394D01*
X1903924Y152686D01*
Y152978D01*
X1904007Y153269D01*
X1904132Y153519D01*
X1904299Y153728D01*
G01X1903924Y155786D02*
X1906424D01*
X1905924Y155286D01*
G01X1903924D02*
Y156286D01*
G01X1906424Y158886D02*
X1903924D01*
G01X1906424Y157928D02*
Y159844D01*
G01X1904299Y161069D02*
X1904091Y161319D01*
X1903966Y161611D01*
X1903924Y161986D01*
X1904007Y162361D01*
X1904174Y162653D01*
X1904466Y162861D01*
X1904799Y162903D01*
X1905132Y162819D01*
X1905341Y162611D01*
X1905507Y162319D01*
X1905549Y162028D01*
X1905507Y161736D01*
X1905341Y161361D01*
X1906424Y161486D01*
Y162611D01*
G01X1950760Y109305D02*
X1951010Y109430D01*
X1951302Y109513D01*
X1951635D01*
X1952010Y109388D01*
X1952302Y109180D01*
X1952510Y108930D01*
X1952677Y108513D01*
X1952719Y108138D01*
X1952635Y107763D01*
X1952510Y107513D01*
X1952260Y107263D01*
X1951969Y107096D01*
X1951677Y107013D01*
X1951385D01*
X1951094Y107096D01*
X1950844Y107221D01*
X1950635Y107388D01*
G01X1948577Y107013D02*
Y109513D01*
X1949077Y109013D01*
G01Y107013D02*
X1948077D01*
G01X1946310D02*
Y109513D01*
X1945269D01*
X1944935Y109388D01*
X1944727Y109221D01*
X1944644Y108888D01*
X1944727Y108555D01*
X1944977Y108346D01*
X1945269Y108221D01*
X1946310D01*
G01X1945269D02*
X1944644Y107013D01*
G01X1943169Y109096D02*
X1942919Y109346D01*
X1942627Y109471D01*
X1942294Y109513D01*
X1941877Y109430D01*
X1941585Y109221D01*
X1941502Y108971D01*
X1941544Y108721D01*
X1941710Y108513D01*
X1942544Y108096D01*
X1942919Y107805D01*
X1943169Y107388D01*
X1943252Y107013D01*
X1941502D01*
G01X1940194Y107388D02*
X1939944Y107180D01*
X1939652Y107055D01*
X1939277Y107013D01*
X1938902Y107096D01*
X1938610Y107263D01*
X1938402Y107555D01*
X1938360Y107888D01*
X1938444Y108221D01*
X1938652Y108430D01*
X1938944Y108596D01*
X1939235Y108638D01*
X1939527Y108596D01*
X1939902Y108430D01*
X1939777Y109513D01*
X1938652D01*
G01X1924859Y119417D02*
X1924984Y119167D01*
X1925067Y118875D01*
Y118542D01*
X1924942Y118167D01*
X1924734Y117875D01*
X1924484Y117667D01*
X1924067Y117500D01*
X1923692Y117458D01*
X1923317Y117542D01*
X1923067Y117667D01*
X1922817Y117917D01*
X1922650Y118208D01*
X1922567Y118500D01*
Y118792D01*
X1922650Y119083D01*
X1922775Y119333D01*
X1922942Y119542D01*
G01X1922567Y121600D02*
X1925067D01*
X1924567Y121100D01*
G01X1922567D02*
Y122100D01*
G01X1925067Y124700D02*
X1922567D01*
G01X1925067Y123742D02*
Y125658D01*
G01X1922567Y127800D02*
X1925067D01*
X1924567Y127300D01*
G01X1922567D02*
Y128300D01*
G01Y130900D02*
X1925067D01*
X1924567Y130400D01*
G01X1922567D02*
Y131400D01*
G01X1920138Y148567D02*
X1920263Y148317D01*
X1920346Y148025D01*
Y147692D01*
X1920221Y147317D01*
X1920013Y147025D01*
X1919763Y146817D01*
X1919346Y146650D01*
X1918971Y146608D01*
X1918596Y146692D01*
X1918346Y146817D01*
X1918096Y147067D01*
X1917929Y147358D01*
X1917846Y147650D01*
Y147942D01*
X1917929Y148233D01*
X1918054Y148483D01*
X1918221Y148692D01*
G01X1917846Y150750D02*
X1920346D01*
X1919846Y150250D01*
G01X1917846D02*
Y151250D01*
G01X1920346Y153850D02*
X1917846D01*
G01X1920346Y152892D02*
Y154808D01*
G01X1918346Y156033D02*
X1918054Y156283D01*
X1917888Y156617D01*
X1917846Y156992D01*
X1917888Y157325D01*
X1918096Y157658D01*
X1918346Y157867D01*
X1918596Y157908D01*
X1918888Y157825D01*
X1919096Y157533D01*
X1919179Y157242D01*
Y156867D01*
G01Y157242D02*
X1919304Y157492D01*
X1919513Y157700D01*
X1919763Y157783D01*
X1920013Y157700D01*
X1920221Y157492D01*
X1920346Y157117D01*
X1920304Y156742D01*
X1920138Y156367D01*
G01X1910300Y95008D02*
X1912800D01*
Y96592D01*
G01X1911592Y96008D02*
Y95008D01*
G01X1911633Y99233D02*
X1911758Y99400D01*
X1911967Y99525D01*
X1912258Y99608D01*
X1912508Y99525D01*
X1912675Y99358D01*
X1912800Y99067D01*
Y97942D01*
X1910300D01*
Y99317D01*
X1910467Y99608D01*
X1910717Y99775D01*
X1911008Y99858D01*
X1911300Y99775D01*
X1911550Y99525D01*
X1911633Y99233D01*
Y97942D01*
G01X1912383Y101208D02*
X1912633Y101458D01*
X1912758Y101750D01*
X1912800Y102083D01*
X1912717Y102500D01*
X1912508Y102792D01*
X1912258Y102875D01*
X1912008Y102833D01*
X1911800Y102667D01*
X1911383Y101833D01*
X1911092Y101458D01*
X1910675Y101208D01*
X1910300Y101125D01*
Y102875D01*
G01X1912800Y105100D02*
X1910300D01*
G01X1912800Y104142D02*
Y106058D01*
G01X1912383Y107408D02*
X1912633Y107658D01*
X1912758Y107950D01*
X1912800Y108283D01*
X1912717Y108700D01*
X1912508Y108992D01*
X1912258Y109075D01*
X1912008Y109033D01*
X1911800Y108867D01*
X1911383Y108033D01*
X1911092Y107658D01*
X1910675Y107408D01*
X1910300Y107325D01*
Y109075D01*
G01X1941004Y134148D02*
Y132356D01*
X1940837Y131981D01*
X1940504Y131731D01*
X1940087Y131648D01*
X1939670Y131731D01*
X1939337Y131981D01*
X1939170Y132356D01*
Y134148D01*
G01X1937695Y131940D02*
X1937404Y131731D01*
X1937070Y131648D01*
X1936737Y131731D01*
X1936445Y131981D01*
X1936237Y132356D01*
X1936154Y132731D01*
Y133190D01*
X1936237Y133565D01*
X1936445Y133898D01*
X1936695Y134065D01*
X1936987Y134148D01*
X1937320Y134065D01*
X1937570Y133898D01*
X1937737Y133648D01*
X1937820Y133315D01*
X1937737Y133023D01*
X1937529Y132731D01*
X1937279Y132565D01*
X1936987Y132523D01*
X1936654Y132606D01*
X1936404Y132815D01*
X1936154Y133190D01*
G01X1934679Y131648D02*
Y134148D01*
X1933095D01*
G01X1933679Y132940D02*
X1934679D01*
G01X1930787Y131648D02*
Y134148D01*
X1931287Y133648D01*
G01Y131648D02*
X1930287D01*
G01X1934934Y146648D02*
X1936932D01*
G01X1934934Y138348D02*
X1936932D01*
G01X1957443Y134699D02*
Y132907D01*
X1957276Y132532D01*
X1956943Y132282D01*
X1956526Y132199D01*
X1956109Y132282D01*
X1955776Y132532D01*
X1955609Y132907D01*
Y134699D01*
G01X1954134Y132491D02*
X1953843Y132282D01*
X1953509Y132199D01*
X1953176Y132282D01*
X1952884Y132532D01*
X1952676Y132907D01*
X1952593Y133282D01*
Y133741D01*
X1952676Y134116D01*
X1952884Y134449D01*
X1953134Y134616D01*
X1953426Y134699D01*
X1953759Y134616D01*
X1954009Y134449D01*
X1954176Y134199D01*
X1954259Y133866D01*
X1954176Y133574D01*
X1953968Y133282D01*
X1953718Y133116D01*
X1953426Y133074D01*
X1953093Y133157D01*
X1952843Y133366D01*
X1952593Y133741D01*
G01X1951118Y132199D02*
Y134699D01*
X1949534D01*
G01X1950118Y133491D02*
X1951118D01*
G01X1948018Y134282D02*
X1947768Y134532D01*
X1947476Y134657D01*
X1947143Y134699D01*
X1946726Y134616D01*
X1946434Y134407D01*
X1946351Y134157D01*
X1946393Y133907D01*
X1946559Y133699D01*
X1947393Y133282D01*
X1947768Y132991D01*
X1948018Y132574D01*
X1948101Y132199D01*
X1946351D01*
G01X1946571Y166819D02*
Y152559D01*
G01X1947221Y152609D02*
X1957331D01*
G01X1947271D02*
X1946581D01*
X1946541Y152569D01*
G01X1956381Y152639D02*
Y166889D01*
G01X1954833Y191050D02*
X1960167D01*
Y198050D01*
X1954833D01*
G01X1956967Y194667D02*
X1960167D01*
G01X1912300Y165000D02*
X1898300D01*
Y162700D01*
G01X1928014Y196600D02*
X1945800D01*
Y199000D01*
X1950200D01*
Y201000D01*
X1956400D01*
Y199700D01*
X1974100D01*
Y148800D01*
G01X1916633Y198500D02*
Y201000D01*
X1915592D01*
X1915258Y200875D01*
X1915050Y200708D01*
X1914967Y200375D01*
X1915050Y200042D01*
X1915300Y199833D01*
X1915592Y199708D01*
X1916633D01*
G01X1915592D02*
X1914967Y198500D01*
G01X1912700D02*
Y201000D01*
X1913200Y200500D01*
G01Y198500D02*
X1912200D01*
G01X1910433D02*
Y201000D01*
X1909392D01*
X1909058Y200875D01*
X1908850Y200708D01*
X1908767Y200375D01*
X1908850Y200042D01*
X1909100Y199833D01*
X1909392Y199708D01*
X1910433D01*
G01X1909392D02*
X1908767Y198500D01*
G01X1906500D02*
Y201000D01*
X1907000Y200500D01*
G01Y198500D02*
X1906000D01*
G01X1952398Y204394D02*
X1952648Y204519D01*
X1952940Y204602D01*
X1953273D01*
X1953648Y204477D01*
X1953940Y204269D01*
X1954148Y204019D01*
X1954315Y203602D01*
X1954357Y203227D01*
X1954273Y202852D01*
X1954148Y202602D01*
X1953898Y202352D01*
X1953607Y202185D01*
X1953315Y202102D01*
X1953023D01*
X1952732Y202185D01*
X1952482Y202310D01*
X1952273Y202477D01*
G01X1951007Y204185D02*
X1950757Y204435D01*
X1950465Y204560D01*
X1950132Y204602D01*
X1949715Y204519D01*
X1949423Y204310D01*
X1949340Y204060D01*
X1949382Y203810D01*
X1949548Y203602D01*
X1950382Y203185D01*
X1950757Y202894D01*
X1951007Y202477D01*
X1951090Y202102D01*
X1949340D01*
G01X1948032Y202477D02*
X1947782Y202269D01*
X1947490Y202144D01*
X1947115Y202102D01*
X1946740Y202185D01*
X1946448Y202352D01*
X1946240Y202644D01*
X1946198Y202977D01*
X1946282Y203310D01*
X1946490Y203519D01*
X1946782Y203685D01*
X1947073Y203727D01*
X1947365Y203685D01*
X1947740Y203519D01*
X1947615Y204602D01*
X1946490D01*
G01X1944848Y202102D02*
Y204602D01*
X1943848D01*
X1943515Y204477D01*
X1943265Y204185D01*
X1943182Y203852D01*
X1943265Y203519D01*
X1943473Y203269D01*
X1943848Y203144D01*
X1944848D01*
G01X1940915Y202102D02*
X1940623Y202144D01*
X1940290Y202269D01*
X1940082Y202477D01*
X1939998Y202769D01*
X1940082Y203060D01*
X1940332Y203310D01*
X1940707Y203435D01*
X1941123D01*
X1941373Y203519D01*
X1941582Y203727D01*
X1941665Y204019D01*
X1941540Y204310D01*
X1941248Y204519D01*
X1940915Y204602D01*
X1940582Y204519D01*
X1940290Y204310D01*
X1940165Y204019D01*
X1940248Y203727D01*
X1940457Y203519D01*
X1940707Y203435D01*
X1941123D01*
X1941498Y203310D01*
X1941748Y203060D01*
X1941832Y202769D01*
X1941748Y202477D01*
X1941540Y202269D01*
X1941207Y202144D01*
X1940915Y202102D01*
G01X1938732Y202602D02*
X1938482Y202310D01*
X1938148Y202144D01*
X1937773Y202102D01*
X1937440Y202144D01*
X1937107Y202352D01*
X1936898Y202602D01*
X1936857Y202852D01*
X1936940Y203144D01*
X1937232Y203352D01*
X1937523Y203435D01*
X1937898D01*
G01X1937523D02*
X1937273Y203560D01*
X1937065Y203769D01*
X1936982Y204019D01*
X1937065Y204269D01*
X1937273Y204477D01*
X1937648Y204602D01*
X1938023Y204560D01*
X1938398Y204394D01*
G01X1960456Y216929D02*
X1960581Y216679D01*
X1960664Y216387D01*
Y216054D01*
X1960539Y215679D01*
X1960331Y215387D01*
X1960081Y215179D01*
X1959664Y215012D01*
X1959289Y214970D01*
X1958914Y215054D01*
X1958664Y215179D01*
X1958414Y215429D01*
X1958247Y215720D01*
X1958164Y216012D01*
Y216304D01*
X1958247Y216595D01*
X1958372Y216845D01*
X1958539Y217054D01*
G01X1958164Y218279D02*
X1960664D01*
Y219320D01*
X1960539Y219654D01*
X1960372Y219862D01*
X1960039Y219945D01*
X1959706Y219862D01*
X1959497Y219612D01*
X1959372Y219320D01*
Y218279D01*
G01Y219320D02*
X1958164Y219945D01*
G01X1958664Y221295D02*
X1958372Y221545D01*
X1958206Y221879D01*
X1958164Y222254D01*
X1958206Y222587D01*
X1958414Y222920D01*
X1958664Y223129D01*
X1958914Y223170D01*
X1959206Y223087D01*
X1959414Y222795D01*
X1959497Y222504D01*
Y222129D01*
G01Y222504D02*
X1959622Y222754D01*
X1959831Y222962D01*
X1960081Y223045D01*
X1960331Y222962D01*
X1960539Y222754D01*
X1960664Y222379D01*
X1960622Y222004D01*
X1960456Y221629D01*
G01X1960664Y225312D02*
X1960581Y224979D01*
X1960372Y224729D01*
X1960122Y224562D01*
X1959789Y224437D01*
X1959414Y224395D01*
X1959039Y224437D01*
X1958706Y224562D01*
X1958456Y224729D01*
X1958247Y224979D01*
X1958164Y225312D01*
X1958247Y225645D01*
X1958456Y225895D01*
X1958706Y226062D01*
X1959039Y226187D01*
X1959414Y226229D01*
X1959789Y226187D01*
X1960122Y226062D01*
X1960372Y225895D01*
X1960581Y225645D01*
X1960664Y225312D01*
G01Y227162D02*
X1958164Y227745D01*
X1960664Y228412D01*
X1958164Y229079D01*
X1960664Y229662D01*
G01X1958164Y231512D02*
X1960664D01*
X1960164Y231012D01*
G01X1958164D02*
Y232012D01*
G01X1941704Y208923D02*
Y211423D01*
X1940120D01*
G01X1940704Y210215D02*
X1941704D01*
G01X1938604Y211006D02*
X1938354Y211256D01*
X1938062Y211381D01*
X1937729Y211423D01*
X1937312Y211340D01*
X1937020Y211131D01*
X1936937Y210881D01*
X1936979Y210631D01*
X1937145Y210423D01*
X1937979Y210006D01*
X1938354Y209715D01*
X1938604Y209298D01*
X1938687Y208923D01*
X1936937D01*
G01X1935629Y209298D02*
X1935379Y209090D01*
X1935087Y208965D01*
X1934712Y208923D01*
X1934337Y209006D01*
X1934045Y209173D01*
X1933837Y209465D01*
X1933795Y209798D01*
X1933879Y210131D01*
X1934087Y210340D01*
X1934379Y210506D01*
X1934670Y210548D01*
X1934962Y210506D01*
X1935337Y210340D01*
X1935212Y211423D01*
X1934087D01*
G01X1932862D02*
X1932279Y208923D01*
X1931612Y211423D01*
X1930945Y208923D01*
X1930362Y211423D01*
G01X1928512Y208923D02*
Y211423D01*
X1929012Y210923D01*
G01Y208923D02*
X1928012D01*
G01X1912181Y212499D02*
X1925281D01*
G01X1912181Y204399D02*
Y212499D01*
G01X1925281Y204399D02*
X1912181D01*
G01X1925281Y212499D02*
Y204399D01*
G01X1954490Y216975D02*
X1954615Y216725D01*
X1954698Y216433D01*
Y216100D01*
X1954573Y215725D01*
X1954365Y215433D01*
X1954115Y215225D01*
X1953698Y215058D01*
X1953323Y215016D01*
X1952948Y215100D01*
X1952698Y215225D01*
X1952448Y215475D01*
X1952281Y215766D01*
X1952198Y216058D01*
Y216350D01*
X1952281Y216641D01*
X1952406Y216891D01*
X1952573Y217100D01*
G01X1952698Y218241D02*
X1952406Y218491D01*
X1952240Y218825D01*
X1952198Y219200D01*
X1952240Y219533D01*
X1952448Y219866D01*
X1952698Y220075D01*
X1952948Y220116D01*
X1953240Y220033D01*
X1953448Y219741D01*
X1953531Y219450D01*
Y219075D01*
G01Y219450D02*
X1953656Y219700D01*
X1953865Y219908D01*
X1954115Y219991D01*
X1954365Y219908D01*
X1954573Y219700D01*
X1954698Y219325D01*
X1954656Y218950D01*
X1954490Y218575D01*
G01X1954698Y222258D02*
X1954615Y221925D01*
X1954406Y221675D01*
X1954156Y221508D01*
X1953823Y221383D01*
X1953448Y221341D01*
X1953073Y221383D01*
X1952740Y221508D01*
X1952490Y221675D01*
X1952281Y221925D01*
X1952198Y222258D01*
X1952281Y222591D01*
X1952490Y222841D01*
X1952740Y223008D01*
X1953073Y223133D01*
X1953448Y223175D01*
X1953823Y223133D01*
X1954156Y223008D01*
X1954406Y222841D01*
X1954615Y222591D01*
X1954698Y222258D01*
G01Y224108D02*
X1952198Y224691D01*
X1954698Y225358D01*
X1952198Y226025D01*
X1954698Y226608D01*
G01X1952198Y228458D02*
X1952240Y228750D01*
X1952365Y229083D01*
X1952573Y229291D01*
X1952865Y229375D01*
X1953156Y229291D01*
X1953406Y229041D01*
X1953531Y228666D01*
Y228250D01*
X1953615Y228000D01*
X1953823Y227791D01*
X1954115Y227708D01*
X1954406Y227833D01*
X1954615Y228125D01*
X1954698Y228458D01*
X1954615Y228791D01*
X1954406Y229083D01*
X1954115Y229208D01*
X1953823Y229125D01*
X1953615Y228916D01*
X1953531Y228666D01*
Y228250D01*
X1953406Y227875D01*
X1953156Y227625D01*
X1952865Y227541D01*
X1952573Y227625D01*
X1952365Y227833D01*
X1952240Y228166D01*
X1952198Y228458D01*
G01X1946709Y211942D02*
X1946834Y211692D01*
X1946917Y211400D01*
Y211067D01*
X1946792Y210692D01*
X1946584Y210400D01*
X1946334Y210192D01*
X1945917Y210025D01*
X1945542Y209983D01*
X1945167Y210067D01*
X1944917Y210192D01*
X1944667Y210442D01*
X1944500Y210733D01*
X1944417Y211025D01*
Y211317D01*
X1944500Y211608D01*
X1944625Y211858D01*
X1944792Y212067D01*
G01X1944917Y213208D02*
X1944625Y213458D01*
X1944459Y213792D01*
X1944417Y214167D01*
X1944459Y214500D01*
X1944667Y214833D01*
X1944917Y215042D01*
X1945167Y215083D01*
X1945459Y215000D01*
X1945667Y214708D01*
X1945750Y214417D01*
Y214042D01*
G01Y214417D02*
X1945875Y214667D01*
X1946084Y214875D01*
X1946334Y214958D01*
X1946584Y214875D01*
X1946792Y214667D01*
X1946917Y214292D01*
X1946875Y213917D01*
X1946709Y213542D01*
G01X1946917Y217225D02*
X1946834Y216892D01*
X1946625Y216642D01*
X1946375Y216475D01*
X1946042Y216350D01*
X1945667Y216308D01*
X1945292Y216350D01*
X1944959Y216475D01*
X1944709Y216642D01*
X1944500Y216892D01*
X1944417Y217225D01*
X1944500Y217558D01*
X1944709Y217808D01*
X1944959Y217975D01*
X1945292Y218100D01*
X1945667Y218142D01*
X1946042Y218100D01*
X1946375Y217975D01*
X1946625Y217808D01*
X1946834Y217558D01*
X1946917Y217225D01*
G01Y219075D02*
X1944417Y219658D01*
X1946917Y220325D01*
X1944417Y220992D01*
X1946917Y221575D01*
G01X1944709Y222717D02*
X1944500Y223008D01*
X1944417Y223342D01*
X1944500Y223675D01*
X1944750Y223967D01*
X1945125Y224175D01*
X1945500Y224258D01*
X1945959D01*
X1946334Y224175D01*
X1946667Y223967D01*
X1946834Y223717D01*
X1946917Y223425D01*
X1946834Y223092D01*
X1946667Y222842D01*
X1946417Y222675D01*
X1946084Y222592D01*
X1945792Y222675D01*
X1945500Y222883D01*
X1945334Y223133D01*
X1945292Y223425D01*
X1945375Y223758D01*
X1945584Y224008D01*
X1945959Y224258D01*
G01X1947221Y166859D02*
X1946501D01*
G01X1947201D02*
X1956361D01*
G01X1910000Y210650D02*
Y226750D01*
G01X1903000Y210650D02*
X1910000D01*
G01X1903000Y226750D02*
Y210650D01*
G01X1938646Y231223D02*
Y233723D01*
X1937605D01*
X1937271Y233598D01*
X1937063Y233431D01*
X1936980Y233098D01*
X1937063Y232765D01*
X1937313Y232556D01*
X1937605Y232431D01*
X1938646D01*
G01X1937605D02*
X1936980Y231223D01*
G01X1935630Y231723D02*
X1935380Y231431D01*
X1935046Y231265D01*
X1934671Y231223D01*
X1934338Y231265D01*
X1934005Y231473D01*
X1933796Y231723D01*
X1933755Y231973D01*
X1933838Y232265D01*
X1934130Y232473D01*
X1934421Y232556D01*
X1934796D01*
G01X1934421D02*
X1934171Y232681D01*
X1933963Y232890D01*
X1933880Y233140D01*
X1933963Y233390D01*
X1934171Y233598D01*
X1934546Y233723D01*
X1934921Y233681D01*
X1935296Y233515D01*
G01X1931613Y233723D02*
X1931946Y233640D01*
X1932196Y233431D01*
X1932363Y233181D01*
X1932488Y232848D01*
X1932530Y232473D01*
X1932488Y232098D01*
X1932363Y231765D01*
X1932196Y231515D01*
X1931946Y231306D01*
X1931613Y231223D01*
X1931280Y231306D01*
X1931030Y231515D01*
X1930863Y231765D01*
X1930738Y232098D01*
X1930696Y232473D01*
X1930738Y232848D01*
X1930863Y233181D01*
X1931030Y233431D01*
X1931280Y233640D01*
X1931613Y233723D01*
G01X1929763D02*
X1929180Y231223D01*
X1928513Y233723D01*
X1927846Y231223D01*
X1927263Y233723D01*
G01X1925413Y231223D02*
Y233723D01*
X1925913Y233223D01*
G01Y231223D02*
X1924913D01*
G01X1937539Y227957D02*
Y230457D01*
X1936498D01*
X1936164Y230332D01*
X1935956Y230165D01*
X1935873Y229832D01*
X1935956Y229499D01*
X1936206Y229290D01*
X1936498Y229165D01*
X1937539D01*
G01X1936498D02*
X1935873Y227957D01*
G01X1934523Y228457D02*
X1934273Y228165D01*
X1933939Y227999D01*
X1933564Y227957D01*
X1933231Y227999D01*
X1932898Y228207D01*
X1932689Y228457D01*
X1932648Y228707D01*
X1932731Y228999D01*
X1933023Y229207D01*
X1933314Y229290D01*
X1933689D01*
G01X1933314D02*
X1933064Y229415D01*
X1932856Y229624D01*
X1932773Y229874D01*
X1932856Y230124D01*
X1933064Y230332D01*
X1933439Y230457D01*
X1933814Y230415D01*
X1934189Y230249D01*
G01X1930506Y230457D02*
X1930839Y230374D01*
X1931089Y230165D01*
X1931256Y229915D01*
X1931381Y229582D01*
X1931423Y229207D01*
X1931381Y228832D01*
X1931256Y228499D01*
X1931089Y228249D01*
X1930839Y228040D01*
X1930506Y227957D01*
X1930173Y228040D01*
X1929923Y228249D01*
X1929756Y228499D01*
X1929631Y228832D01*
X1929589Y229207D01*
X1929631Y229582D01*
X1929756Y229915D01*
X1929923Y230165D01*
X1930173Y230374D01*
X1930506Y230457D01*
G01X1928656D02*
X1928073Y227957D01*
X1927406Y230457D01*
X1926739Y227957D01*
X1926156Y230457D01*
G01X1925098Y230040D02*
X1924848Y230290D01*
X1924556Y230415D01*
X1924223Y230457D01*
X1923806Y230374D01*
X1923514Y230165D01*
X1923431Y229915D01*
X1923473Y229665D01*
X1923639Y229457D01*
X1924473Y229040D01*
X1924848Y228749D01*
X1925098Y228332D01*
X1925181Y227957D01*
X1923431D01*
G01X1940050Y218883D02*
X1942550D01*
Y219717D01*
X1942425Y220050D01*
X1942258Y220300D01*
X1942008Y220508D01*
X1941717Y220675D01*
X1941300Y220717D01*
X1940883Y220675D01*
X1940592Y220508D01*
X1940342Y220300D01*
X1940175Y220050D01*
X1940050Y219717D01*
Y218883D01*
G01X1942133Y222108D02*
X1942383Y222358D01*
X1942508Y222650D01*
X1942550Y222983D01*
X1942467Y223400D01*
X1942258Y223692D01*
X1942008Y223775D01*
X1941758Y223733D01*
X1941550Y223567D01*
X1941133Y222733D01*
X1940842Y222358D01*
X1940425Y222108D01*
X1940050Y222025D01*
Y223775D01*
G01X1940425Y225083D02*
X1940217Y225333D01*
X1940092Y225625D01*
X1940050Y226000D01*
X1940133Y226375D01*
X1940300Y226667D01*
X1940592Y226875D01*
X1940925Y226917D01*
X1941258Y226833D01*
X1941467Y226625D01*
X1941633Y226333D01*
X1941675Y226042D01*
X1941633Y225750D01*
X1941467Y225375D01*
X1942550Y225500D01*
Y226625D01*
G01Y227850D02*
X1940050Y228433D01*
X1942550Y229100D01*
X1940050Y229767D01*
X1942550Y230350D01*
G01X1940050Y232200D02*
X1940092Y232492D01*
X1940217Y232825D01*
X1940425Y233033D01*
X1940717Y233117D01*
X1941008Y233033D01*
X1941258Y232783D01*
X1941383Y232408D01*
Y231992D01*
X1941467Y231742D01*
X1941675Y231533D01*
X1941967Y231450D01*
X1942258Y231575D01*
X1942467Y231867D01*
X1942550Y232200D01*
X1942467Y232533D01*
X1942258Y232825D01*
X1941967Y232950D01*
X1941675Y232867D01*
X1941467Y232658D01*
X1941383Y232408D01*
Y231992D01*
X1941258Y231617D01*
X1941008Y231367D01*
X1940717Y231283D01*
X1940425Y231367D01*
X1940217Y231575D01*
X1940092Y231908D01*
X1940050Y232200D01*
G01X1910000Y226750D02*
X1903000D01*
G01X1932577Y243962D02*
Y241462D01*
X1930911D01*
G01X1929561Y241962D02*
X1929311Y241670D01*
X1928977Y241504D01*
X1928602Y241462D01*
X1928269Y241504D01*
X1927936Y241712D01*
X1927727Y241962D01*
X1927686Y242212D01*
X1927769Y242504D01*
X1928061Y242712D01*
X1928352Y242795D01*
X1928727D01*
G01X1928352D02*
X1928102Y242920D01*
X1927894Y243129D01*
X1927811Y243379D01*
X1927894Y243629D01*
X1928102Y243837D01*
X1928477Y243962D01*
X1928852Y243920D01*
X1929227Y243754D01*
G01X1925544Y243962D02*
X1925877Y243879D01*
X1926127Y243670D01*
X1926294Y243420D01*
X1926419Y243087D01*
X1926461Y242712D01*
X1926419Y242337D01*
X1926294Y242004D01*
X1926127Y241754D01*
X1925877Y241545D01*
X1925544Y241462D01*
X1925211Y241545D01*
X1924961Y241754D01*
X1924794Y242004D01*
X1924669Y242337D01*
X1924627Y242712D01*
X1924669Y243087D01*
X1924794Y243420D01*
X1924961Y243670D01*
X1925211Y243879D01*
X1925544Y243962D01*
G01X1923694D02*
X1923111Y241462D01*
X1922444Y243962D01*
X1921777Y241462D01*
X1921194Y243962D01*
G01X1920136Y243545D02*
X1919886Y243795D01*
X1919594Y243920D01*
X1919261Y243962D01*
X1918844Y243879D01*
X1918552Y243670D01*
X1918469Y243420D01*
X1918511Y243170D01*
X1918677Y242962D01*
X1919511Y242545D01*
X1919886Y242254D01*
X1920136Y241837D01*
X1920219Y241462D01*
X1918469D01*
G01X1908359Y227775D02*
X1905859D01*
Y229441D01*
G01X1906359Y230791D02*
X1906067Y231041D01*
X1905901Y231375D01*
X1905859Y231750D01*
X1905901Y232083D01*
X1906109Y232416D01*
X1906359Y232625D01*
X1906609Y232666D01*
X1906901Y232583D01*
X1907109Y232291D01*
X1907192Y232000D01*
Y231625D01*
G01Y232000D02*
X1907317Y232250D01*
X1907526Y232458D01*
X1907776Y232541D01*
X1908026Y232458D01*
X1908234Y232250D01*
X1908359Y231875D01*
X1908317Y231500D01*
X1908151Y231125D01*
G01X1908359Y234808D02*
X1908276Y234475D01*
X1908067Y234225D01*
X1907817Y234058D01*
X1907484Y233933D01*
X1907109Y233891D01*
X1906734Y233933D01*
X1906401Y234058D01*
X1906151Y234225D01*
X1905942Y234475D01*
X1905859Y234808D01*
X1905942Y235141D01*
X1906151Y235391D01*
X1906401Y235558D01*
X1906734Y235683D01*
X1907109Y235725D01*
X1907484Y235683D01*
X1907817Y235558D01*
X1908067Y235391D01*
X1908276Y235141D01*
X1908359Y234808D01*
G01Y236658D02*
X1905859Y237241D01*
X1908359Y237908D01*
X1905859Y238575D01*
X1908359Y239158D01*
G01X1905859Y241008D02*
X1908359D01*
X1907859Y240508D01*
G01X1905859D02*
Y241508D01*
G01X1946838Y439357D02*
X1947088Y439482D01*
X1947380Y439565D01*
X1947713D01*
X1948088Y439440D01*
X1948380Y439232D01*
X1948588Y438982D01*
X1948755Y438565D01*
X1948797Y438190D01*
X1948713Y437815D01*
X1948588Y437565D01*
X1948338Y437315D01*
X1948047Y437148D01*
X1947755Y437065D01*
X1947463D01*
X1947172Y437148D01*
X1946922Y437273D01*
X1946713Y437440D01*
G01X1944655Y437065D02*
Y439565D01*
X1945155Y439065D01*
G01Y437065D02*
X1944155D01*
G01X1942638D02*
Y439565D01*
X1941555Y437482D01*
X1940472Y439565D01*
Y437065D01*
G01X1939247Y439148D02*
X1938997Y439398D01*
X1938705Y439523D01*
X1938372Y439565D01*
X1937955Y439482D01*
X1937663Y439273D01*
X1937580Y439023D01*
X1937622Y438773D01*
X1937788Y438565D01*
X1938622Y438148D01*
X1938997Y437857D01*
X1939247Y437440D01*
X1939330Y437065D01*
X1937580D01*
G01X1936147Y438107D02*
X1935855Y438398D01*
X1935605Y438565D01*
X1935272Y438648D01*
X1934980Y438565D01*
X1934772Y438398D01*
X1934605Y438148D01*
X1934563Y437857D01*
X1934605Y437607D01*
X1934772Y437357D01*
X1935022Y437148D01*
X1935313Y437065D01*
X1935647Y437148D01*
X1935938Y437398D01*
X1936105Y437773D01*
X1936147Y438190D01*
X1936063Y438732D01*
X1935938Y439023D01*
X1935730Y439315D01*
X1935438Y439523D01*
X1935147Y439565D01*
X1934855Y439482D01*
X1934647Y439273D01*
G01X1933153Y461997D02*
X1935653D01*
Y463038D01*
X1935528Y463372D01*
X1935361Y463580D01*
X1935028Y463663D01*
X1934695Y463580D01*
X1934486Y463330D01*
X1934361Y463038D01*
Y461997D01*
G01Y463038D02*
X1933153Y463663D01*
G01X1933445Y465222D02*
X1933236Y465513D01*
X1933153Y465847D01*
X1933236Y466180D01*
X1933486Y466472D01*
X1933861Y466680D01*
X1934236Y466763D01*
X1934695D01*
X1935070Y466680D01*
X1935403Y466472D01*
X1935570Y466222D01*
X1935653Y465930D01*
X1935570Y465597D01*
X1935403Y465347D01*
X1935153Y465180D01*
X1934820Y465097D01*
X1934528Y465180D01*
X1934236Y465388D01*
X1934070Y465638D01*
X1934028Y465930D01*
X1934111Y466263D01*
X1934320Y466513D01*
X1934695Y466763D01*
G01X1935653Y467780D02*
X1933153Y468363D01*
X1935653Y469030D01*
X1933153Y469697D01*
X1935653Y470280D01*
G01X1933153Y472130D02*
X1935653D01*
X1935153Y471630D01*
G01X1933153D02*
Y472630D01*
G01X1919775Y452084D02*
X1920025Y452209D01*
X1920317Y452292D01*
X1920650D01*
X1921025Y452167D01*
X1921317Y451959D01*
X1921525Y451709D01*
X1921692Y451292D01*
X1921734Y450917D01*
X1921650Y450542D01*
X1921525Y450292D01*
X1921275Y450042D01*
X1920984Y449875D01*
X1920692Y449792D01*
X1920400D01*
X1920109Y449875D01*
X1919859Y450000D01*
X1919650Y450167D01*
G01X1917592Y449792D02*
Y452292D01*
X1918092Y451792D01*
G01Y449792D02*
X1917092D01*
G01X1915575D02*
Y452292D01*
X1914492Y450209D01*
X1913409Y452292D01*
Y449792D01*
G01X1912184Y451875D02*
X1911934Y452125D01*
X1911642Y452250D01*
X1911309Y452292D01*
X1910892Y452209D01*
X1910600Y452000D01*
X1910517Y451750D01*
X1910559Y451500D01*
X1910725Y451292D01*
X1911559Y450875D01*
X1911934Y450584D01*
X1912184Y450167D01*
X1912267Y449792D01*
X1910517D01*
G01X1909209Y450292D02*
X1908959Y450000D01*
X1908625Y449834D01*
X1908250Y449792D01*
X1907917Y449834D01*
X1907584Y450042D01*
X1907375Y450292D01*
X1907334Y450542D01*
X1907417Y450834D01*
X1907709Y451042D01*
X1908000Y451125D01*
X1908375D01*
G01X1908000D02*
X1907750Y451250D01*
X1907542Y451459D01*
X1907459Y451709D01*
X1907542Y451959D01*
X1907750Y452167D01*
X1908125Y452292D01*
X1908500Y452250D01*
X1908875Y452084D01*
G01X1943083Y446459D02*
X1943333Y446584D01*
X1943625Y446667D01*
X1943958D01*
X1944333Y446542D01*
X1944625Y446334D01*
X1944833Y446084D01*
X1945000Y445667D01*
X1945042Y445292D01*
X1944958Y444917D01*
X1944833Y444667D01*
X1944583Y444417D01*
X1944292Y444250D01*
X1944000Y444167D01*
X1943708D01*
X1943417Y444250D01*
X1943167Y444375D01*
X1942958Y444542D01*
G01X1940900Y444167D02*
Y446667D01*
X1941400Y446167D01*
G01Y444167D02*
X1940400D01*
G01X1938883D02*
Y446667D01*
X1937800Y444584D01*
X1936717Y446667D01*
Y444167D01*
G01X1935492Y446250D02*
X1935242Y446500D01*
X1934950Y446625D01*
X1934617Y446667D01*
X1934200Y446584D01*
X1933908Y446375D01*
X1933825Y446125D01*
X1933867Y445875D01*
X1934033Y445667D01*
X1934867Y445250D01*
X1935242Y444959D01*
X1935492Y444542D01*
X1935575Y444167D01*
X1933825D01*
G01X1932392Y446250D02*
X1932142Y446500D01*
X1931850Y446625D01*
X1931517Y446667D01*
X1931100Y446584D01*
X1930808Y446375D01*
X1930725Y446125D01*
X1930767Y445875D01*
X1930933Y445667D01*
X1931767Y445250D01*
X1932142Y444959D01*
X1932392Y444542D01*
X1932475Y444167D01*
X1930725D01*
G01X1931564Y457400D02*
Y453609D01*
X1918768D01*
Y457400D01*
G01X1949783Y465000D02*
Y467500D01*
X1948742D01*
X1948408Y467375D01*
X1948200Y467208D01*
X1948117Y466875D01*
X1948200Y466542D01*
X1948450Y466333D01*
X1948742Y466208D01*
X1949783D01*
G01X1948742D02*
X1948117Y465000D01*
G01X1946558Y465292D02*
X1946267Y465083D01*
X1945933Y465000D01*
X1945600Y465083D01*
X1945308Y465333D01*
X1945100Y465708D01*
X1945017Y466083D01*
Y466542D01*
X1945100Y466917D01*
X1945308Y467250D01*
X1945558Y467417D01*
X1945850Y467500D01*
X1946183Y467417D01*
X1946433Y467250D01*
X1946600Y467000D01*
X1946683Y466667D01*
X1946600Y466375D01*
X1946392Y466083D01*
X1946142Y465917D01*
X1945850Y465875D01*
X1945517Y465958D01*
X1945267Y466167D01*
X1945017Y466542D01*
G01X1942417Y466333D02*
X1942250Y466458D01*
X1942125Y466667D01*
X1942042Y466958D01*
X1942125Y467208D01*
X1942292Y467375D01*
X1942583Y467500D01*
X1943708D01*
Y465000D01*
X1942333D01*
X1942042Y465167D01*
X1941875Y465417D01*
X1941792Y465708D01*
X1941875Y466000D01*
X1942125Y466250D01*
X1942417Y466333D01*
X1943708D01*
G01X1939733Y465000D02*
X1939650Y465542D01*
X1939525Y466000D01*
X1939358Y466417D01*
X1939150Y466875D01*
X1938817Y467500D01*
X1940483D01*
G01X1936600Y460717D02*
X1940600D01*
Y453317D01*
G01X1938933Y489010D02*
Y491510D01*
X1937892D01*
X1937558Y491385D01*
X1937350Y491218D01*
X1937267Y490885D01*
X1937350Y490552D01*
X1937600Y490343D01*
X1937892Y490218D01*
X1938933D01*
G01X1937892D02*
X1937267Y489010D01*
G01X1935708Y489302D02*
X1935417Y489093D01*
X1935083Y489010D01*
X1934750Y489093D01*
X1934458Y489343D01*
X1934250Y489718D01*
X1934167Y490093D01*
Y490552D01*
X1934250Y490927D01*
X1934458Y491260D01*
X1934708Y491427D01*
X1935000Y491510D01*
X1935333Y491427D01*
X1935583Y491260D01*
X1935750Y491010D01*
X1935833Y490677D01*
X1935750Y490385D01*
X1935542Y490093D01*
X1935292Y489927D01*
X1935000Y489885D01*
X1934667Y489968D01*
X1934417Y490177D01*
X1934167Y490552D01*
G01X1931567Y490343D02*
X1931400Y490468D01*
X1931275Y490677D01*
X1931192Y490968D01*
X1931275Y491218D01*
X1931442Y491385D01*
X1931733Y491510D01*
X1932858D01*
Y489010D01*
X1931483D01*
X1931192Y489177D01*
X1931025Y489427D01*
X1930942Y489718D01*
X1931025Y490010D01*
X1931275Y490260D01*
X1931567Y490343D01*
X1932858D01*
G01X1929592Y490052D02*
X1929300Y490343D01*
X1929050Y490510D01*
X1928717Y490593D01*
X1928425Y490510D01*
X1928217Y490343D01*
X1928050Y490093D01*
X1928008Y489802D01*
X1928050Y489552D01*
X1928217Y489302D01*
X1928467Y489093D01*
X1928758Y489010D01*
X1929092Y489093D01*
X1929383Y489343D01*
X1929550Y489718D01*
X1929592Y490135D01*
X1929508Y490677D01*
X1929383Y490968D01*
X1929175Y491260D01*
X1928883Y491468D01*
X1928592Y491510D01*
X1928300Y491427D01*
X1928092Y491218D01*
G01X1928437Y475109D02*
Y477609D01*
X1927396D01*
X1927062Y477484D01*
X1926854Y477317D01*
X1926771Y476984D01*
X1926854Y476651D01*
X1927104Y476442D01*
X1927396Y476317D01*
X1928437D01*
G01X1927396D02*
X1926771Y475109D01*
G01X1925212Y475401D02*
X1924921Y475192D01*
X1924587Y475109D01*
X1924254Y475192D01*
X1923962Y475442D01*
X1923754Y475817D01*
X1923671Y476192D01*
Y476651D01*
X1923754Y477026D01*
X1923962Y477359D01*
X1924212Y477526D01*
X1924504Y477609D01*
X1924837Y477526D01*
X1925087Y477359D01*
X1925254Y477109D01*
X1925337Y476776D01*
X1925254Y476484D01*
X1925046Y476192D01*
X1924796Y476026D01*
X1924504Y475984D01*
X1924171Y476067D01*
X1923921Y476276D01*
X1923671Y476651D01*
G01X1921154Y476359D02*
X1920321D01*
Y475609D01*
X1920571Y475359D01*
X1920862Y475192D01*
X1921279Y475109D01*
X1921696Y475192D01*
X1921987Y475359D01*
X1922237Y475609D01*
X1922404Y475901D01*
X1922487Y476234D01*
Y476526D01*
X1922404Y476776D01*
X1922237Y477067D01*
X1921987Y477317D01*
X1921737Y477484D01*
X1921404Y477609D01*
X1921112D01*
X1920779Y477526D01*
X1920529Y477359D01*
G01X1918304Y475109D02*
Y477609D01*
X1918804Y477109D01*
G01Y475109D02*
X1917804D01*
G01X1916121Y475609D02*
X1915871Y475317D01*
X1915537Y475151D01*
X1915162Y475109D01*
X1914829Y475151D01*
X1914496Y475359D01*
X1914287Y475609D01*
X1914246Y475859D01*
X1914329Y476151D01*
X1914621Y476359D01*
X1914912Y476442D01*
X1915287D01*
G01X1914912D02*
X1914662Y476567D01*
X1914454Y476776D01*
X1914371Y477026D01*
X1914454Y477276D01*
X1914662Y477484D01*
X1915037Y477609D01*
X1915412Y477567D01*
X1915787Y477401D01*
G01X1944137Y480452D02*
Y482952D01*
X1943096D01*
X1942762Y482827D01*
X1942554Y482660D01*
X1942471Y482327D01*
X1942554Y481994D01*
X1942804Y481785D01*
X1943096Y481660D01*
X1944137D01*
G01X1943096D02*
X1942471Y480452D01*
G01X1940912Y480744D02*
X1940621Y480535D01*
X1940287Y480452D01*
X1939954Y480535D01*
X1939662Y480785D01*
X1939454Y481160D01*
X1939371Y481535D01*
Y481994D01*
X1939454Y482369D01*
X1939662Y482702D01*
X1939912Y482869D01*
X1940204Y482952D01*
X1940537Y482869D01*
X1940787Y482702D01*
X1940954Y482452D01*
X1941037Y482119D01*
X1940954Y481827D01*
X1940746Y481535D01*
X1940496Y481369D01*
X1940204Y481327D01*
X1939871Y481410D01*
X1939621Y481619D01*
X1939371Y481994D01*
G01X1936854Y481702D02*
X1936021D01*
Y480952D01*
X1936271Y480702D01*
X1936562Y480535D01*
X1936979Y480452D01*
X1937396Y480535D01*
X1937687Y480702D01*
X1937937Y480952D01*
X1938104Y481244D01*
X1938187Y481577D01*
Y481869D01*
X1938104Y482119D01*
X1937937Y482410D01*
X1937687Y482660D01*
X1937437Y482827D01*
X1937104Y482952D01*
X1936812D01*
X1936479Y482869D01*
X1936229Y482702D01*
G01X1934004Y480452D02*
Y482952D01*
X1934504Y482452D01*
G01Y480452D02*
X1933504D01*
G01X1931696Y482535D02*
X1931446Y482785D01*
X1931154Y482910D01*
X1930821Y482952D01*
X1930404Y482869D01*
X1930112Y482660D01*
X1930029Y482410D01*
X1930071Y482160D01*
X1930237Y481952D01*
X1931071Y481535D01*
X1931446Y481244D01*
X1931696Y480827D01*
X1931779Y480452D01*
X1930029D01*
G01X1959520Y468667D02*
X1962020D01*
Y469708D01*
X1961895Y470042D01*
X1961728Y470250D01*
X1961395Y470333D01*
X1961062Y470250D01*
X1960853Y470000D01*
X1960728Y469708D01*
Y468667D01*
G01Y469708D02*
X1959520Y470333D01*
G01Y472600D02*
X1962020D01*
X1961520Y472100D01*
G01X1959520D02*
Y473100D01*
G01Y474617D02*
X1962020D01*
X1959937Y475700D01*
X1962020Y476783D01*
X1959520D01*
G01Y478800D02*
X1962020D01*
X1961520Y478300D01*
G01X1959520D02*
Y479300D01*
G01X1960020Y480983D02*
X1959728Y481233D01*
X1959562Y481567D01*
X1959520Y481942D01*
X1959562Y482275D01*
X1959770Y482608D01*
X1960020Y482817D01*
X1960270Y482858D01*
X1960562Y482775D01*
X1960770Y482483D01*
X1960853Y482192D01*
Y481817D01*
G01Y482192D02*
X1960978Y482442D01*
X1961187Y482650D01*
X1961437Y482733D01*
X1961687Y482650D01*
X1961895Y482442D01*
X1962020Y482067D01*
X1961978Y481692D01*
X1961812Y481317D01*
G01X1923883Y513000D02*
Y515500D01*
X1922842D01*
X1922508Y515375D01*
X1922300Y515208D01*
X1922217Y514875D01*
X1922300Y514542D01*
X1922550Y514333D01*
X1922842Y514208D01*
X1923883D01*
G01X1922842D02*
X1922217Y513000D01*
G01X1920742Y514042D02*
X1920450Y514333D01*
X1920200Y514500D01*
X1919867Y514583D01*
X1919575Y514500D01*
X1919367Y514333D01*
X1919200Y514083D01*
X1919158Y513792D01*
X1919200Y513542D01*
X1919367Y513292D01*
X1919617Y513083D01*
X1919908Y513000D01*
X1920242Y513083D01*
X1920533Y513333D01*
X1920700Y513708D01*
X1920742Y514125D01*
X1920658Y514667D01*
X1920533Y514958D01*
X1920325Y515250D01*
X1920033Y515458D01*
X1919742Y515500D01*
X1919450Y515417D01*
X1919242Y515208D01*
G01X1918100Y515500D02*
X1917517Y513000D01*
X1916850Y515500D01*
X1916183Y513000D01*
X1915600Y515500D01*
G01X1914667Y513375D02*
X1914417Y513167D01*
X1914125Y513042D01*
X1913750Y513000D01*
X1913375Y513083D01*
X1913083Y513250D01*
X1912875Y513542D01*
X1912833Y513875D01*
X1912917Y514208D01*
X1913125Y514417D01*
X1913417Y514583D01*
X1913708Y514625D01*
X1914000Y514583D01*
X1914375Y514417D01*
X1914250Y515500D01*
X1913125D01*
G01X1910650D02*
X1910983Y515417D01*
X1911233Y515208D01*
X1911400Y514958D01*
X1911525Y514625D01*
X1911567Y514250D01*
X1911525Y513875D01*
X1911400Y513542D01*
X1911233Y513292D01*
X1910983Y513083D01*
X1910650Y513000D01*
X1910317Y513083D01*
X1910067Y513292D01*
X1909900Y513542D01*
X1909775Y513875D01*
X1909733Y514250D01*
X1909775Y514625D01*
X1909900Y514958D01*
X1910067Y515208D01*
X1910317Y515417D01*
X1910650Y515500D01*
G01X1939707Y505790D02*
Y503998D01*
X1939540Y503623D01*
X1939207Y503373D01*
X1938790Y503290D01*
X1938373Y503373D01*
X1938040Y503623D01*
X1937873Y503998D01*
Y505790D01*
G01X1935690Y503290D02*
Y505790D01*
X1936190Y505290D01*
G01Y503290D02*
X1935190D01*
G01X1933673D02*
Y505790D01*
X1932590Y503707D01*
X1931507Y505790D01*
Y503290D01*
G01X1929490D02*
Y505790D01*
X1929990Y505290D01*
G01Y503290D02*
X1928990D01*
G01X1965927Y498530D02*
Y496738D01*
X1965760Y496363D01*
X1965427Y496113D01*
X1965010Y496030D01*
X1964593Y496113D01*
X1964260Y496363D01*
X1964093Y496738D01*
Y498530D01*
G01X1961910Y496030D02*
Y498530D01*
X1962410Y498030D01*
G01Y496030D02*
X1961410D01*
G01X1959893D02*
Y498530D01*
X1958810Y496447D01*
X1957727Y498530D01*
Y496030D01*
G01X1956502Y497072D02*
X1956210Y497363D01*
X1955960Y497530D01*
X1955627Y497613D01*
X1955335Y497530D01*
X1955127Y497363D01*
X1954960Y497113D01*
X1954918Y496822D01*
X1954960Y496572D01*
X1955127Y496322D01*
X1955377Y496113D01*
X1955668Y496030D01*
X1956002Y496113D01*
X1956293Y496363D01*
X1956460Y496738D01*
X1956502Y497155D01*
X1956418Y497697D01*
X1956293Y497988D01*
X1956085Y498280D01*
X1955793Y498488D01*
X1955502Y498530D01*
X1955210Y498447D01*
X1955002Y498238D01*
G01X1958842Y505047D02*
X1958967Y504797D01*
X1959050Y504505D01*
Y504172D01*
X1958925Y503797D01*
X1958717Y503505D01*
X1958467Y503297D01*
X1958050Y503130D01*
X1957675Y503088D01*
X1957300Y503172D01*
X1957050Y503297D01*
X1956800Y503547D01*
X1956633Y503838D01*
X1956550Y504130D01*
Y504422D01*
X1956633Y504713D01*
X1956758Y504963D01*
X1956925Y505172D01*
G01X1956550Y507230D02*
X1959050D01*
X1958550Y506730D01*
G01X1956550D02*
Y507730D01*
G01Y509247D02*
X1959050D01*
X1956967Y510330D01*
X1959050Y511413D01*
X1956550D01*
G01X1957050Y512513D02*
X1956758Y512763D01*
X1956592Y513097D01*
X1956550Y513472D01*
X1956592Y513805D01*
X1956800Y514138D01*
X1957050Y514347D01*
X1957300Y514388D01*
X1957592Y514305D01*
X1957800Y514013D01*
X1957883Y513722D01*
Y513347D01*
G01Y513722D02*
X1958008Y513972D01*
X1958217Y514180D01*
X1958467Y514263D01*
X1958717Y514180D01*
X1958925Y513972D01*
X1959050Y513597D01*
X1959008Y513222D01*
X1958842Y512847D01*
G01X1956550Y516530D02*
X1959050D01*
X1958550Y516030D01*
G01X1956550D02*
Y517030D01*
G01X1923933Y490892D02*
X1924183Y491017D01*
X1924475Y491100D01*
X1924808D01*
X1925183Y490975D01*
X1925475Y490767D01*
X1925683Y490517D01*
X1925850Y490100D01*
X1925892Y489725D01*
X1925808Y489350D01*
X1925683Y489100D01*
X1925433Y488850D01*
X1925142Y488683D01*
X1924850Y488600D01*
X1924558D01*
X1924267Y488683D01*
X1924017Y488808D01*
X1923808Y488975D01*
G01X1921750Y488600D02*
Y491100D01*
X1922250Y490600D01*
G01Y488600D02*
X1921250D01*
G01X1919733D02*
Y491100D01*
X1918650Y489017D01*
X1917567Y491100D01*
Y488600D01*
G01X1915050D02*
Y491100D01*
X1916592Y489308D01*
X1914508D01*
G01X1946883Y514892D02*
X1947133Y515017D01*
X1947425Y515100D01*
X1947758D01*
X1948133Y514975D01*
X1948425Y514767D01*
X1948633Y514517D01*
X1948800Y514100D01*
X1948842Y513725D01*
X1948758Y513350D01*
X1948633Y513100D01*
X1948383Y512850D01*
X1948092Y512683D01*
X1947800Y512600D01*
X1947508D01*
X1947217Y512683D01*
X1946967Y512808D01*
X1946758Y512975D01*
G01X1944700Y512600D02*
Y515100D01*
X1945200Y514600D01*
G01Y512600D02*
X1944200D01*
G01X1942683D02*
Y515100D01*
X1941600Y513017D01*
X1940517Y515100D01*
Y512600D01*
G01X1939417Y513100D02*
X1939167Y512808D01*
X1938833Y512642D01*
X1938458Y512600D01*
X1938125Y512642D01*
X1937792Y512850D01*
X1937583Y513100D01*
X1937542Y513350D01*
X1937625Y513642D01*
X1937917Y513850D01*
X1938208Y513933D01*
X1938583D01*
G01X1938208D02*
X1937958Y514058D01*
X1937750Y514267D01*
X1937667Y514517D01*
X1937750Y514767D01*
X1937958Y514975D01*
X1938333Y515100D01*
X1938708Y515058D01*
X1939083Y514892D01*
G01X1936192Y514683D02*
X1935942Y514933D01*
X1935650Y515058D01*
X1935317Y515100D01*
X1934900Y515017D01*
X1934608Y514808D01*
X1934525Y514558D01*
X1934567Y514308D01*
X1934733Y514100D01*
X1935567Y513683D01*
X1935942Y513392D01*
X1936192Y512975D01*
X1936275Y512600D01*
X1934525D01*
G01X1964443Y494512D02*
X1964693Y494637D01*
X1964985Y494720D01*
X1965318D01*
X1965693Y494595D01*
X1965985Y494387D01*
X1966193Y494137D01*
X1966360Y493720D01*
X1966402Y493345D01*
X1966318Y492970D01*
X1966193Y492720D01*
X1965943Y492470D01*
X1965652Y492303D01*
X1965360Y492220D01*
X1965068D01*
X1964777Y492303D01*
X1964527Y492428D01*
X1964318Y492595D01*
G01X1962260Y492220D02*
Y494720D01*
X1962760Y494220D01*
G01Y492220D02*
X1961760D01*
G01X1960243D02*
Y494720D01*
X1959160Y492637D01*
X1958077Y494720D01*
Y492220D01*
G01X1956977Y492720D02*
X1956727Y492428D01*
X1956393Y492262D01*
X1956018Y492220D01*
X1955685Y492262D01*
X1955352Y492470D01*
X1955143Y492720D01*
X1955102Y492970D01*
X1955185Y493262D01*
X1955477Y493470D01*
X1955768Y493553D01*
X1956143D01*
G01X1955768D02*
X1955518Y493678D01*
X1955310Y493887D01*
X1955227Y494137D01*
X1955310Y494387D01*
X1955518Y494595D01*
X1955893Y494720D01*
X1956268Y494678D01*
X1956643Y494512D01*
G01X1931564Y470000D02*
Y473562D01*
X1918768D01*
Y470000D01*
G01X1916790Y508067D02*
Y511167D01*
X1918208Y508945D01*
X1916292D01*
G01X1968167Y522800D02*
Y521008D01*
X1968000Y520633D01*
X1967667Y520383D01*
X1967250Y520300D01*
X1966833Y520383D01*
X1966500Y520633D01*
X1966333Y521008D01*
Y522800D01*
G01X1964150Y520300D02*
Y522800D01*
X1964650Y522300D01*
G01Y520300D02*
X1963650D01*
G01X1962133D02*
Y522800D01*
X1961050Y520717D01*
X1959967Y522800D01*
Y520300D01*
G01X1958742Y522383D02*
X1958492Y522633D01*
X1958200Y522758D01*
X1957867Y522800D01*
X1957450Y522717D01*
X1957158Y522508D01*
X1957075Y522258D01*
X1957117Y522008D01*
X1957283Y521800D01*
X1958117Y521383D01*
X1958492Y521092D01*
X1958742Y520675D01*
X1958825Y520300D01*
X1957075D01*
G01X1905462Y477277D02*
X1905587Y477027D01*
X1905670Y476735D01*
Y476402D01*
X1905545Y476027D01*
X1905337Y475735D01*
X1905087Y475527D01*
X1904670Y475360D01*
X1904295Y475318D01*
X1903920Y475402D01*
X1903670Y475527D01*
X1903420Y475777D01*
X1903253Y476068D01*
X1903170Y476360D01*
Y476652D01*
X1903253Y476943D01*
X1903378Y477193D01*
X1903545Y477402D01*
G01X1903462Y478752D02*
X1903253Y479043D01*
X1903170Y479377D01*
X1903253Y479710D01*
X1903503Y480002D01*
X1903878Y480210D01*
X1904253Y480293D01*
X1904712D01*
X1905087Y480210D01*
X1905420Y480002D01*
X1905587Y479752D01*
X1905670Y479460D01*
X1905587Y479127D01*
X1905420Y478877D01*
X1905170Y478710D01*
X1904837Y478627D01*
X1904545Y478710D01*
X1904253Y478918D01*
X1904087Y479168D01*
X1904045Y479460D01*
X1904128Y479793D01*
X1904337Y480043D01*
X1904712Y480293D01*
G01X1904503Y482893D02*
X1904628Y483060D01*
X1904837Y483185D01*
X1905128Y483268D01*
X1905378Y483185D01*
X1905545Y483018D01*
X1905670Y482727D01*
Y481602D01*
X1903170D01*
Y482977D01*
X1903337Y483268D01*
X1903587Y483435D01*
X1903878Y483518D01*
X1904170Y483435D01*
X1904420Y483185D01*
X1904503Y482893D01*
Y481602D01*
G01X1903462Y484952D02*
X1903253Y485243D01*
X1903170Y485577D01*
X1903253Y485910D01*
X1903503Y486202D01*
X1903878Y486410D01*
X1904253Y486493D01*
X1904712D01*
X1905087Y486410D01*
X1905420Y486202D01*
X1905587Y485952D01*
X1905670Y485660D01*
X1905587Y485327D01*
X1905420Y485077D01*
X1905170Y484910D01*
X1904837Y484827D01*
X1904545Y484910D01*
X1904253Y485118D01*
X1904087Y485368D01*
X1904045Y485660D01*
X1904128Y485993D01*
X1904337Y486243D01*
X1904712Y486493D01*
G01X1921500Y560000D02*
X1925000D01*
G01X1969925Y532898D02*
Y535398D01*
X1968884D01*
X1968550Y535273D01*
X1968342Y535106D01*
X1968259Y534773D01*
X1968342Y534440D01*
X1968592Y534231D01*
X1968884Y534106D01*
X1969925D01*
G01X1968884D02*
X1968259Y532898D01*
G01X1965992D02*
Y535398D01*
X1966492Y534898D01*
G01Y532898D02*
X1965492D01*
G01X1963725Y535398D02*
Y532898D01*
X1962059D01*
G01X1959292D02*
Y535398D01*
X1960834Y533606D01*
X1958750D01*
G01X1957609Y533398D02*
X1957359Y533106D01*
X1957025Y532940D01*
X1956650Y532898D01*
X1956317Y532940D01*
X1955984Y533148D01*
X1955775Y533398D01*
X1955734Y533648D01*
X1955817Y533940D01*
X1956109Y534148D01*
X1956400Y534231D01*
X1956775D01*
G01X1956400D02*
X1956150Y534356D01*
X1955942Y534565D01*
X1955859Y534815D01*
X1955942Y535065D01*
X1956150Y535273D01*
X1956525Y535398D01*
X1956900Y535356D01*
X1957275Y535190D01*
G01X1971873Y527400D02*
Y529900D01*
X1970832D01*
X1970498Y529775D01*
X1970290Y529608D01*
X1970207Y529275D01*
X1970290Y528942D01*
X1970540Y528733D01*
X1970832Y528608D01*
X1971873D01*
G01X1970832D02*
X1970207Y527400D01*
G01X1967940D02*
Y529900D01*
X1968440Y529400D01*
G01Y527400D02*
X1967440D01*
G01X1965673Y529900D02*
Y527400D01*
X1964007D01*
G01X1961240D02*
Y529900D01*
X1962782Y528108D01*
X1960698D01*
G01X1958140Y527400D02*
Y529900D01*
X1959682Y528108D01*
X1957598D01*
G01X1957300Y583267D02*
X1959800D01*
Y584308D01*
X1959675Y584642D01*
X1959508Y584850D01*
X1959175Y584933D01*
X1958842Y584850D01*
X1958633Y584600D01*
X1958508Y584308D01*
Y583267D01*
G01Y584308D02*
X1957300Y584933D01*
G01X1958342Y586408D02*
X1958633Y586700D01*
X1958800Y586950D01*
X1958883Y587283D01*
X1958800Y587575D01*
X1958633Y587783D01*
X1958383Y587950D01*
X1958092Y587992D01*
X1957842Y587950D01*
X1957592Y587783D01*
X1957383Y587533D01*
X1957300Y587242D01*
X1957383Y586908D01*
X1957633Y586617D01*
X1958008Y586450D01*
X1958425Y586408D01*
X1958967Y586492D01*
X1959258Y586617D01*
X1959550Y586825D01*
X1959758Y587117D01*
X1959800Y587408D01*
X1959717Y587700D01*
X1959508Y587908D01*
G01X1959800Y589050D02*
X1957300Y589633D01*
X1959800Y590300D01*
X1957300Y590967D01*
X1959800Y591550D01*
G01X1957800Y592483D02*
X1957508Y592733D01*
X1957342Y593067D01*
X1957300Y593442D01*
X1957342Y593775D01*
X1957550Y594108D01*
X1957800Y594317D01*
X1958050Y594358D01*
X1958342Y594275D01*
X1958550Y593983D01*
X1958633Y593692D01*
Y593317D01*
G01Y593692D02*
X1958758Y593942D01*
X1958967Y594150D01*
X1959217Y594233D01*
X1959467Y594150D01*
X1959675Y593942D01*
X1959800Y593567D01*
X1959758Y593192D01*
X1959592Y592817D01*
G01X1957592Y595792D02*
X1957383Y596083D01*
X1957300Y596417D01*
X1957383Y596750D01*
X1957633Y597042D01*
X1958008Y597250D01*
X1958383Y597333D01*
X1958842D01*
X1959217Y597250D01*
X1959550Y597042D01*
X1959717Y596792D01*
X1959800Y596500D01*
X1959717Y596167D01*
X1959550Y595917D01*
X1959300Y595750D01*
X1958967Y595667D01*
X1958675Y595750D01*
X1958383Y595958D01*
X1958217Y596208D01*
X1958175Y596500D01*
X1958258Y596833D01*
X1958467Y597083D01*
X1958842Y597333D01*
G01X1957500Y567167D02*
X1960000D01*
Y568208D01*
X1959875Y568542D01*
X1959708Y568750D01*
X1959375Y568833D01*
X1959042Y568750D01*
X1958833Y568500D01*
X1958708Y568208D01*
Y567167D01*
G01Y568208D02*
X1957500Y568833D01*
G01Y571100D02*
X1960000D01*
X1959500Y570600D01*
G01X1957500D02*
Y571600D01*
G01X1960000Y573367D02*
X1957500D01*
Y575033D01*
G01X1959583Y576508D02*
X1959833Y576758D01*
X1959958Y577050D01*
X1960000Y577383D01*
X1959917Y577800D01*
X1959708Y578092D01*
X1959458Y578175D01*
X1959208Y578133D01*
X1959000Y577967D01*
X1958583Y577133D01*
X1958292Y576758D01*
X1957875Y576508D01*
X1957500Y576425D01*
Y578175D01*
G01Y580400D02*
X1960000D01*
X1959500Y579900D01*
G01X1957500D02*
Y580900D01*
G01X1920183Y535750D02*
Y538250D01*
X1919142D01*
X1918808Y538125D01*
X1918600Y537958D01*
X1918517Y537625D01*
X1918600Y537292D01*
X1918850Y537083D01*
X1919142Y536958D01*
X1920183D01*
G01X1919142D02*
X1918517Y535750D01*
G01X1916250D02*
Y538250D01*
X1916750Y537750D01*
G01Y535750D02*
X1915750D01*
G01X1913983Y538250D02*
Y535750D01*
X1912317D01*
G01X1910967Y536250D02*
X1910717Y535958D01*
X1910383Y535792D01*
X1910008Y535750D01*
X1909675Y535792D01*
X1909342Y536000D01*
X1909133Y536250D01*
X1909092Y536500D01*
X1909175Y536792D01*
X1909467Y537000D01*
X1909758Y537083D01*
X1910133D01*
G01X1909758D02*
X1909508Y537208D01*
X1909300Y537417D01*
X1909217Y537667D01*
X1909300Y537917D01*
X1909508Y538125D01*
X1909883Y538250D01*
X1910258Y538208D01*
X1910633Y538042D01*
G01X1906950Y535750D02*
X1906658Y535792D01*
X1906325Y535917D01*
X1906117Y536125D01*
X1906033Y536417D01*
X1906117Y536708D01*
X1906367Y536958D01*
X1906742Y537083D01*
X1907158D01*
X1907408Y537167D01*
X1907617Y537375D01*
X1907700Y537667D01*
X1907575Y537958D01*
X1907283Y538167D01*
X1906950Y538250D01*
X1906617Y538167D01*
X1906325Y537958D01*
X1906200Y537667D01*
X1906283Y537375D01*
X1906492Y537167D01*
X1906742Y537083D01*
X1907158D01*
X1907533Y536958D01*
X1907783Y536708D01*
X1907867Y536417D01*
X1907783Y536125D01*
X1907575Y535917D01*
X1907242Y535792D01*
X1906950Y535750D01*
G01X1917233Y542000D02*
Y544500D01*
X1916192D01*
X1915858Y544375D01*
X1915650Y544208D01*
X1915567Y543875D01*
X1915650Y543542D01*
X1915900Y543333D01*
X1916192Y543208D01*
X1917233D01*
G01X1916192D02*
X1915567Y542000D01*
G01X1913300D02*
Y544500D01*
X1913800Y544000D01*
G01Y542000D02*
X1912800D01*
G01X1911033Y544500D02*
Y542000D01*
X1909367D01*
G01X1908017Y542500D02*
X1907767Y542208D01*
X1907433Y542042D01*
X1907058Y542000D01*
X1906725Y542042D01*
X1906392Y542250D01*
X1906183Y542500D01*
X1906142Y542750D01*
X1906225Y543042D01*
X1906517Y543250D01*
X1906808Y543333D01*
X1907183D01*
G01X1906808D02*
X1906558Y543458D01*
X1906350Y543667D01*
X1906267Y543917D01*
X1906350Y544167D01*
X1906558Y544375D01*
X1906933Y544500D01*
X1907308Y544458D01*
X1907683Y544292D01*
G01X1904792Y543042D02*
X1904500Y543333D01*
X1904250Y543500D01*
X1903917Y543583D01*
X1903625Y543500D01*
X1903417Y543333D01*
X1903250Y543083D01*
X1903208Y542792D01*
X1903250Y542542D01*
X1903417Y542292D01*
X1903667Y542083D01*
X1903958Y542000D01*
X1904292Y542083D01*
X1904583Y542333D01*
X1904750Y542708D01*
X1904792Y543125D01*
X1904708Y543667D01*
X1904583Y543958D01*
X1904375Y544250D01*
X1904083Y544458D01*
X1903792Y544500D01*
X1903500Y544417D01*
X1903292Y544208D01*
G01X1955183Y547800D02*
Y550300D01*
X1954142D01*
X1953808Y550175D01*
X1953600Y550008D01*
X1953517Y549675D01*
X1953600Y549342D01*
X1953850Y549133D01*
X1954142Y549008D01*
X1955183D01*
G01X1954142D02*
X1953517Y547800D01*
G01X1951250D02*
Y550300D01*
X1951750Y549800D01*
G01Y547800D02*
X1950750D01*
G01X1948983Y550300D02*
Y547800D01*
X1947317D01*
G01X1945967Y548300D02*
X1945717Y548008D01*
X1945383Y547842D01*
X1945008Y547800D01*
X1944675Y547842D01*
X1944342Y548050D01*
X1944133Y548300D01*
X1944092Y548550D01*
X1944175Y548842D01*
X1944467Y549050D01*
X1944758Y549133D01*
X1945133D01*
G01X1944758D02*
X1944508Y549258D01*
X1944300Y549467D01*
X1944217Y549717D01*
X1944300Y549967D01*
X1944508Y550175D01*
X1944883Y550300D01*
X1945258Y550258D01*
X1945633Y550092D01*
G01X1942742Y549883D02*
X1942492Y550133D01*
X1942200Y550258D01*
X1941867Y550300D01*
X1941450Y550217D01*
X1941158Y550008D01*
X1941075Y549758D01*
X1941117Y549508D01*
X1941283Y549300D01*
X1942117Y548883D01*
X1942492Y548592D01*
X1942742Y548175D01*
X1942825Y547800D01*
X1941075D01*
G01X1951083Y551700D02*
Y554200D01*
X1950042D01*
X1949708Y554075D01*
X1949500Y553908D01*
X1949417Y553575D01*
X1949500Y553242D01*
X1949750Y553033D01*
X1950042Y552908D01*
X1951083D01*
G01X1950042D02*
X1949417Y551700D01*
G01X1947150D02*
Y554200D01*
X1947650Y553700D01*
G01Y551700D02*
X1946650D01*
G01X1944883Y554200D02*
Y551700D01*
X1943217D01*
G01X1941867Y552200D02*
X1941617Y551908D01*
X1941283Y551742D01*
X1940908Y551700D01*
X1940575Y551742D01*
X1940242Y551950D01*
X1940033Y552200D01*
X1939992Y552450D01*
X1940075Y552742D01*
X1940367Y552950D01*
X1940658Y553033D01*
X1941033D01*
G01X1940658D02*
X1940408Y553158D01*
X1940200Y553367D01*
X1940117Y553617D01*
X1940200Y553867D01*
X1940408Y554075D01*
X1940783Y554200D01*
X1941158Y554158D01*
X1941533Y553992D01*
G01X1937850Y554200D02*
X1938183Y554117D01*
X1938433Y553908D01*
X1938600Y553658D01*
X1938725Y553325D01*
X1938767Y552950D01*
X1938725Y552575D01*
X1938600Y552242D01*
X1938433Y551992D01*
X1938183Y551783D01*
X1937850Y551700D01*
X1937517Y551783D01*
X1937267Y551992D01*
X1937100Y552242D01*
X1936975Y552575D01*
X1936933Y552950D01*
X1936975Y553325D01*
X1937100Y553658D01*
X1937267Y553908D01*
X1937517Y554117D01*
X1937850Y554200D01*
G01X1920717Y531260D02*
Y529468D01*
X1920550Y529093D01*
X1920217Y528843D01*
X1919800Y528760D01*
X1919383Y528843D01*
X1919050Y529093D01*
X1918883Y529468D01*
Y531260D01*
G01X1917492Y529802D02*
X1917200Y530093D01*
X1916950Y530260D01*
X1916617Y530343D01*
X1916325Y530260D01*
X1916117Y530093D01*
X1915950Y529843D01*
X1915908Y529552D01*
X1915950Y529302D01*
X1916117Y529052D01*
X1916367Y528843D01*
X1916658Y528760D01*
X1916992Y528843D01*
X1917283Y529093D01*
X1917450Y529468D01*
X1917492Y529885D01*
X1917408Y530427D01*
X1917283Y530718D01*
X1917075Y531010D01*
X1916783Y531218D01*
X1916492Y531260D01*
X1916200Y531177D01*
X1915992Y530968D01*
G01X1914850Y531260D02*
X1914267Y528760D01*
X1913600Y531260D01*
X1912933Y528760D01*
X1912350Y531260D01*
G01X1910000Y528760D02*
Y531260D01*
X1911542Y529468D01*
X1909458D01*
G01X1959700Y554433D02*
X1957908D01*
X1957533Y554600D01*
X1957283Y554933D01*
X1957200Y555350D01*
X1957283Y555767D01*
X1957533Y556100D01*
X1957908Y556267D01*
X1959700D01*
G01X1958242Y557658D02*
X1958533Y557950D01*
X1958700Y558200D01*
X1958783Y558533D01*
X1958700Y558825D01*
X1958533Y559033D01*
X1958283Y559200D01*
X1957992Y559242D01*
X1957742Y559200D01*
X1957492Y559033D01*
X1957283Y558783D01*
X1957200Y558492D01*
X1957283Y558158D01*
X1957533Y557867D01*
X1957908Y557700D01*
X1958325Y557658D01*
X1958867Y557742D01*
X1959158Y557867D01*
X1959450Y558075D01*
X1959658Y558367D01*
X1959700Y558658D01*
X1959617Y558950D01*
X1959408Y559158D01*
G01X1959700Y560300D02*
X1957200Y560883D01*
X1959700Y561550D01*
X1957200Y562217D01*
X1959700Y562800D01*
G01X1957575Y563733D02*
X1957367Y563983D01*
X1957242Y564275D01*
X1957200Y564650D01*
X1957283Y565025D01*
X1957450Y565317D01*
X1957742Y565525D01*
X1958075Y565567D01*
X1958408Y565483D01*
X1958617Y565275D01*
X1958783Y564983D01*
X1958825Y564692D01*
X1958783Y564400D01*
X1958617Y564025D01*
X1959700Y564150D01*
Y565275D01*
G01X1906400Y587400D02*
Y587100D01*
X1917600D01*
Y587400D01*
G01X1906400Y567900D02*
Y568200D01*
X1917600D01*
Y567900D01*
G01X1906400Y561300D02*
Y561000D01*
X1917600D01*
Y561300D01*
G01X1906400Y585300D02*
Y585600D01*
X1917600D01*
Y585300D01*
G01X1906400Y578700D02*
Y578400D01*
X1917600D01*
Y578700D01*
G01X1906400Y576600D02*
Y576900D01*
X1917600D01*
Y576600D01*
G01X1906400Y570000D02*
Y569700D01*
X1917600D01*
Y570000D01*
G01X1939522Y560717D02*
X1939752Y560407D01*
X1940020Y560252D01*
X1940327Y560200D01*
X1940710Y560303D01*
X1940978Y560562D01*
X1941055Y560872D01*
X1941017Y561182D01*
X1940863Y561440D01*
X1940097Y561957D01*
X1939752Y562318D01*
X1939522Y562835D01*
X1939445Y563300D01*
X1941055D01*
G01X1924347Y531435D02*
X1924117Y531177D01*
X1923849Y531022D01*
X1923504Y530970D01*
X1923159Y531073D01*
X1922891Y531280D01*
X1922699Y531642D01*
X1922661Y532055D01*
X1922737Y532468D01*
X1922929Y532727D01*
X1923197Y532933D01*
X1923466Y532985D01*
X1923734Y532933D01*
X1924079Y532727D01*
X1923964Y534070D01*
X1922929D01*
G01X1933950Y540967D02*
X1934283Y541009D01*
X1934575Y541175D01*
X1934825Y541425D01*
X1934992Y541717D01*
X1935075Y542050D01*
Y542384D01*
X1934992Y542717D01*
X1934825Y543009D01*
X1934575Y543259D01*
X1934283Y543425D01*
X1933950Y543467D01*
X1933617Y543425D01*
X1933325Y543259D01*
X1933075Y543009D01*
X1932908Y542717D01*
X1932825Y542384D01*
Y542050D01*
X1932908Y541717D01*
X1933075Y541425D01*
X1933325Y541175D01*
X1933617Y541009D01*
X1933950Y540967D01*
G01X1933617Y541634D02*
X1933117Y540967D01*
G01X1930850D02*
Y543467D01*
X1931350Y542967D01*
G01Y540967D02*
X1930350D01*
G01X1928583Y543467D02*
Y540967D01*
X1926917D01*
G01X1924150D02*
Y543467D01*
X1925692Y541675D01*
X1923608D01*
G01X1908000Y559000D02*
X1911250D01*
Y555500D01*
G01X1908000Y547000D02*
X1911250D01*
Y550500D01*
G01X1905750Y551750D02*
Y554250D01*
G01X1934750Y536900D02*
X1935083Y536942D01*
X1935375Y537108D01*
X1935625Y537358D01*
X1935792Y537650D01*
X1935875Y537983D01*
Y538317D01*
X1935792Y538650D01*
X1935625Y538942D01*
X1935375Y539192D01*
X1935083Y539358D01*
X1934750Y539400D01*
X1934417Y539358D01*
X1934125Y539192D01*
X1933875Y538942D01*
X1933708Y538650D01*
X1933625Y538317D01*
Y537983D01*
X1933708Y537650D01*
X1933875Y537358D01*
X1934125Y537108D01*
X1934417Y536942D01*
X1934750Y536900D01*
G01X1934417Y537567D02*
X1933917Y536900D01*
G01X1932442Y537942D02*
X1932150Y538233D01*
X1931900Y538400D01*
X1931567Y538483D01*
X1931275Y538400D01*
X1931067Y538233D01*
X1930900Y537983D01*
X1930858Y537692D01*
X1930900Y537442D01*
X1931067Y537192D01*
X1931317Y536983D01*
X1931608Y536900D01*
X1931942Y536983D01*
X1932233Y537233D01*
X1932400Y537608D01*
X1932442Y538025D01*
X1932358Y538567D01*
X1932233Y538858D01*
X1932025Y539150D01*
X1931733Y539358D01*
X1931442Y539400D01*
X1931150Y539317D01*
X1930942Y539108D01*
G01X1929800Y539400D02*
X1929217Y536900D01*
X1928550Y539400D01*
X1927883Y536900D01*
X1927300Y539400D01*
G01X1924950Y536900D02*
Y539400D01*
X1926492Y537608D01*
X1924408D01*
G01X1945000Y534100D02*
X1942500D01*
G01X1949750Y536350D02*
Y539600D01*
X1946250D01*
G01X1937750Y536350D02*
Y539600D01*
X1941250D01*
G01X1912467Y617737D02*
X1913267Y618087D01*
X1914200Y618320D01*
X1915267D01*
X1916467Y617970D01*
X1917400Y617387D01*
X1918067Y616687D01*
X1918600Y615520D01*
X1918733Y614470D01*
X1918467Y613420D01*
X1918067Y612720D01*
X1917267Y612020D01*
X1916333Y611553D01*
X1915400Y611320D01*
X1914467D01*
X1913533Y611553D01*
X1912733Y611903D01*
X1912067Y612370D01*
G01X1959300Y602717D02*
X1961800D01*
Y603758D01*
X1961675Y604092D01*
X1961508Y604300D01*
X1961175Y604383D01*
X1960842Y604300D01*
X1960633Y604050D01*
X1960508Y603758D01*
Y602717D01*
G01Y603758D02*
X1959300Y604383D01*
G01Y606650D02*
X1961800D01*
X1961300Y606150D01*
G01X1959300D02*
Y607150D01*
G01X1961800Y608917D02*
X1959300D01*
Y610583D01*
G01Y612850D02*
X1959342Y613142D01*
X1959467Y613475D01*
X1959675Y613683D01*
X1959967Y613767D01*
X1960258Y613683D01*
X1960508Y613433D01*
X1960633Y613058D01*
Y612642D01*
X1960717Y612392D01*
X1960925Y612183D01*
X1961217Y612100D01*
X1961508Y612225D01*
X1961717Y612517D01*
X1961800Y612850D01*
X1961717Y613183D01*
X1961508Y613475D01*
X1961217Y613600D01*
X1960925Y613517D01*
X1960717Y613308D01*
X1960633Y613058D01*
Y612642D01*
X1960508Y612267D01*
X1960258Y612017D01*
X1959967Y611933D01*
X1959675Y612017D01*
X1959467Y612225D01*
X1959342Y612558D01*
X1959300Y612850D01*
G01X1906400Y594000D02*
Y594300D01*
X1917600D01*
Y594000D01*
G01X1957636Y611784D02*
Y614884D01*
X1958096Y614264D01*
G01Y611784D02*
X1957176D01*
G01X1955379Y612404D02*
X1955149Y612042D01*
X1954843Y611836D01*
X1954498Y611784D01*
X1954191Y611836D01*
X1953884Y612094D01*
X1953693Y612404D01*
X1953654Y612714D01*
X1953731Y613076D01*
X1953999Y613334D01*
X1954268Y613437D01*
X1954613D01*
G01X1954268D02*
X1954038Y613592D01*
X1953846Y613851D01*
X1953769Y614161D01*
X1953846Y614471D01*
X1954038Y614729D01*
X1954383Y614884D01*
X1954728Y614832D01*
X1955073Y614626D01*
G01X1944796Y611904D02*
Y615004D01*
X1945256Y614384D01*
G01Y611904D02*
X1944336D01*
G01X1941236D02*
Y615004D01*
X1942654Y612782D01*
X1940738D01*
G01X1966800Y147800D02*
X1971600D01*
G01X1961373Y146699D02*
X1963371D01*
G01X1961373Y138399D02*
X1963371D01*
G01X1961401Y167019D02*
Y152759D01*
G01X1962051Y152809D02*
X1972161D01*
G01X1962101D02*
X1961411D01*
X1961371Y152769D01*
G01X1971211Y152839D02*
Y167089D01*
G01X1963996Y216831D02*
X1964121Y216581D01*
X1964204Y216289D01*
Y215956D01*
X1964079Y215581D01*
X1963871Y215289D01*
X1963621Y215081D01*
X1963204Y214914D01*
X1962829Y214872D01*
X1962454Y214956D01*
X1962204Y215081D01*
X1961954Y215331D01*
X1961787Y215622D01*
X1961704Y215914D01*
Y216206D01*
X1961787Y216497D01*
X1961912Y216747D01*
X1962079Y216956D01*
G01X1962204Y218097D02*
X1961912Y218347D01*
X1961746Y218681D01*
X1961704Y219056D01*
X1961746Y219389D01*
X1961954Y219722D01*
X1962204Y219931D01*
X1962454Y219972D01*
X1962746Y219889D01*
X1962954Y219597D01*
X1963037Y219306D01*
Y218931D01*
G01Y219306D02*
X1963162Y219556D01*
X1963371Y219764D01*
X1963621Y219847D01*
X1963871Y219764D01*
X1964079Y219556D01*
X1964204Y219181D01*
X1964162Y218806D01*
X1963996Y218431D01*
G01X1964204Y222114D02*
X1964121Y221781D01*
X1963912Y221531D01*
X1963662Y221364D01*
X1963329Y221239D01*
X1962954Y221197D01*
X1962579Y221239D01*
X1962246Y221364D01*
X1961996Y221531D01*
X1961787Y221781D01*
X1961704Y222114D01*
X1961787Y222447D01*
X1961996Y222697D01*
X1962246Y222864D01*
X1962579Y222989D01*
X1962954Y223031D01*
X1963329Y222989D01*
X1963662Y222864D01*
X1963912Y222697D01*
X1964121Y222447D01*
X1964204Y222114D01*
G01Y223964D02*
X1961704Y224547D01*
X1964204Y225214D01*
X1961704Y225881D01*
X1964204Y226464D01*
G01X1962079Y227397D02*
X1961871Y227647D01*
X1961746Y227939D01*
X1961704Y228314D01*
X1961787Y228689D01*
X1961954Y228981D01*
X1962246Y229189D01*
X1962579Y229231D01*
X1962912Y229147D01*
X1963121Y228939D01*
X1963287Y228647D01*
X1963329Y228356D01*
X1963287Y228064D01*
X1963121Y227689D01*
X1964204Y227814D01*
Y228939D01*
G01X1962051Y167059D02*
X1961331D01*
G01X1962031D02*
X1971191D01*
G01X1970253Y466472D02*
X1970503Y466597D01*
X1970795Y466680D01*
X1971128D01*
X1971503Y466555D01*
X1971795Y466347D01*
X1972003Y466097D01*
X1972170Y465680D01*
X1972212Y465305D01*
X1972128Y464930D01*
X1972003Y464680D01*
X1971753Y464430D01*
X1971462Y464263D01*
X1971170Y464180D01*
X1970878D01*
X1970587Y464263D01*
X1970337Y464388D01*
X1970128Y464555D01*
G01X1968778Y464472D02*
X1968487Y464263D01*
X1968153Y464180D01*
X1967820Y464263D01*
X1967528Y464513D01*
X1967320Y464888D01*
X1967237Y465263D01*
Y465722D01*
X1967320Y466097D01*
X1967528Y466430D01*
X1967778Y466597D01*
X1968070Y466680D01*
X1968403Y466597D01*
X1968653Y466430D01*
X1968820Y466180D01*
X1968903Y465847D01*
X1968820Y465555D01*
X1968612Y465263D01*
X1968362Y465097D01*
X1968070Y465055D01*
X1967737Y465138D01*
X1967487Y465347D01*
X1967237Y465722D01*
G01X1964637Y465513D02*
X1964470Y465638D01*
X1964345Y465847D01*
X1964262Y466138D01*
X1964345Y466388D01*
X1964512Y466555D01*
X1964803Y466680D01*
X1965928D01*
Y464180D01*
X1964553D01*
X1964262Y464347D01*
X1964095Y464597D01*
X1964012Y464888D01*
X1964095Y465180D01*
X1964345Y465430D01*
X1964637Y465513D01*
X1965928D01*
G01X1961953Y464180D02*
X1961870Y464722D01*
X1961745Y465180D01*
X1961578Y465597D01*
X1961370Y466055D01*
X1961037Y466680D01*
X1962703D01*
G01X1967611Y468971D02*
X1970111D01*
Y470012D01*
X1969986Y470346D01*
X1969819Y470554D01*
X1969486Y470637D01*
X1969153Y470554D01*
X1968944Y470304D01*
X1968819Y470012D01*
Y468971D01*
G01Y470012D02*
X1967611Y470637D01*
G01Y472904D02*
X1970111D01*
X1969611Y472404D01*
G01X1967611D02*
Y473404D01*
G01Y474921D02*
X1970111D01*
X1968028Y476004D01*
X1970111Y477087D01*
X1967611D01*
G01Y479104D02*
X1970111D01*
X1969611Y478604D01*
G01X1967611D02*
Y479604D01*
G01Y482204D02*
X1970111D01*
X1969611Y481704D01*
G01X1967611D02*
Y482704D01*
G01X1963692Y469123D02*
X1966192D01*
Y470164D01*
X1966067Y470498D01*
X1965900Y470706D01*
X1965567Y470789D01*
X1965234Y470706D01*
X1965025Y470456D01*
X1964900Y470164D01*
Y469123D01*
G01Y470164D02*
X1963692Y470789D01*
G01Y473056D02*
X1966192D01*
X1965692Y472556D01*
G01X1963692D02*
Y473556D01*
G01Y475073D02*
X1966192D01*
X1964109Y476156D01*
X1966192Y477239D01*
X1963692D01*
G01Y479256D02*
X1966192D01*
X1965692Y478756D01*
G01X1963692D02*
Y479756D01*
G01X1965775Y481564D02*
X1966025Y481814D01*
X1966150Y482106D01*
X1966192Y482439D01*
X1966109Y482856D01*
X1965900Y483148D01*
X1965650Y483231D01*
X1965400Y483189D01*
X1965192Y483023D01*
X1964775Y482189D01*
X1964484Y481814D01*
X1964067Y481564D01*
X1963692Y481481D01*
Y483231D01*
G01X1971523Y468907D02*
X1974023D01*
Y469948D01*
X1973898Y470282D01*
X1973731Y470490D01*
X1973398Y470573D01*
X1973065Y470490D01*
X1972856Y470240D01*
X1972731Y469948D01*
Y468907D01*
G01Y469948D02*
X1971523Y470573D01*
G01Y472840D02*
X1974023D01*
X1973523Y472340D01*
G01X1971523D02*
Y473340D01*
G01Y474857D02*
X1974023D01*
X1971940Y475940D01*
X1974023Y477023D01*
X1971523D01*
G01Y479040D02*
X1974023D01*
X1973523Y478540D01*
G01X1971523D02*
Y479540D01*
G01X1974023Y482140D02*
X1973940Y481807D01*
X1973731Y481557D01*
X1973481Y481390D01*
X1973148Y481265D01*
X1972773Y481223D01*
X1972398Y481265D01*
X1972065Y481390D01*
X1971815Y481557D01*
X1971606Y481807D01*
X1971523Y482140D01*
X1971606Y482473D01*
X1971815Y482723D01*
X1972065Y482890D01*
X1972398Y483015D01*
X1972773Y483057D01*
X1973148Y483015D01*
X1973481Y482890D01*
X1973731Y482723D01*
X1973940Y482473D01*
X1974023Y482140D01*
G01X1973192Y508677D02*
X1973317Y508427D01*
X1973400Y508135D01*
Y507802D01*
X1973275Y507427D01*
X1973067Y507135D01*
X1972817Y506927D01*
X1972400Y506760D01*
X1972025Y506718D01*
X1971650Y506802D01*
X1971400Y506927D01*
X1971150Y507177D01*
X1970983Y507468D01*
X1970900Y507760D01*
Y508052D01*
X1970983Y508343D01*
X1971108Y508593D01*
X1971275Y508802D01*
G01X1970900Y510860D02*
X1973400D01*
X1972900Y510360D01*
G01X1970900D02*
Y511360D01*
G01Y512877D02*
X1973400D01*
X1971317Y513960D01*
X1973400Y515043D01*
X1970900D01*
G01X1972983Y516268D02*
X1973233Y516518D01*
X1973358Y516810D01*
X1973400Y517143D01*
X1973317Y517560D01*
X1973108Y517852D01*
X1972858Y517935D01*
X1972608Y517893D01*
X1972400Y517727D01*
X1971983Y516893D01*
X1971692Y516518D01*
X1971275Y516268D01*
X1970900Y516185D01*
Y517935D01*
G01Y520160D02*
X1970942Y520452D01*
X1971067Y520785D01*
X1971275Y520993D01*
X1971567Y521077D01*
X1971858Y520993D01*
X1972108Y520743D01*
X1972233Y520368D01*
Y519952D01*
X1972317Y519702D01*
X1972525Y519493D01*
X1972817Y519410D01*
X1973108Y519535D01*
X1973317Y519827D01*
X1973400Y520160D01*
X1973317Y520493D01*
X1973108Y520785D01*
X1972817Y520910D01*
X1972525Y520827D01*
X1972317Y520618D01*
X1972233Y520368D01*
Y519952D01*
X1972108Y519577D01*
X1971858Y519327D01*
X1971567Y519243D01*
X1971275Y519327D01*
X1971067Y519535D01*
X1970942Y519868D01*
X1970900Y520160D01*
G01X1974829Y547013D02*
Y549513D01*
X1973788D01*
X1973454Y549388D01*
X1973246Y549221D01*
X1973163Y548888D01*
X1973246Y548555D01*
X1973496Y548346D01*
X1973788Y548221D01*
X1974829D01*
G01X1973788D02*
X1973163Y547013D01*
G01X1971688Y548055D02*
X1971396Y548346D01*
X1971146Y548513D01*
X1970813Y548596D01*
X1970521Y548513D01*
X1970313Y548346D01*
X1970146Y548096D01*
X1970104Y547805D01*
X1970146Y547555D01*
X1970313Y547305D01*
X1970563Y547096D01*
X1970854Y547013D01*
X1971188Y547096D01*
X1971479Y547346D01*
X1971646Y547721D01*
X1971688Y548138D01*
X1971604Y548680D01*
X1971479Y548971D01*
X1971271Y549263D01*
X1970979Y549471D01*
X1970688Y549513D01*
X1970396Y549430D01*
X1970188Y549221D01*
G01X1969046Y549513D02*
X1968463Y547013D01*
X1967796Y549513D01*
X1967129Y547013D01*
X1966546Y549513D01*
G01X1965613Y547513D02*
X1965363Y547221D01*
X1965029Y547055D01*
X1964654Y547013D01*
X1964321Y547055D01*
X1963988Y547263D01*
X1963779Y547513D01*
X1963738Y547763D01*
X1963821Y548055D01*
X1964113Y548263D01*
X1964404Y548346D01*
X1964779D01*
G01X1964404D02*
X1964154Y548471D01*
X1963946Y548680D01*
X1963863Y548930D01*
X1963946Y549180D01*
X1964154Y549388D01*
X1964529Y549513D01*
X1964904Y549471D01*
X1965279Y549305D01*
G01X1961596Y547013D02*
X1961304Y547055D01*
X1960971Y547180D01*
X1960763Y547388D01*
X1960679Y547680D01*
X1960763Y547971D01*
X1961013Y548221D01*
X1961388Y548346D01*
X1961804D01*
X1962054Y548430D01*
X1962263Y548638D01*
X1962346Y548930D01*
X1962221Y549221D01*
X1961929Y549430D01*
X1961596Y549513D01*
X1961263Y549430D01*
X1960971Y549221D01*
X1960846Y548930D01*
X1960929Y548638D01*
X1961138Y548430D01*
X1961388Y548346D01*
X1961804D01*
X1962179Y548221D01*
X1962429Y547971D01*
X1962513Y547680D01*
X1962429Y547388D01*
X1962221Y547180D01*
X1961888Y547055D01*
X1961596Y547013D01*
G01X1973624Y536348D02*
Y538848D01*
X1972583D01*
X1972249Y538723D01*
X1972041Y538556D01*
X1971958Y538223D01*
X1972041Y537890D01*
X1972291Y537681D01*
X1972583Y537556D01*
X1973624D01*
G01X1972583D02*
X1971958Y536348D01*
G01X1969691D02*
Y538848D01*
X1970191Y538348D01*
G01Y536348D02*
X1969191D01*
G01X1967424Y538848D02*
Y536348D01*
X1965758D01*
G01X1964408Y536848D02*
X1964158Y536556D01*
X1963824Y536390D01*
X1963449Y536348D01*
X1963116Y536390D01*
X1962783Y536598D01*
X1962574Y536848D01*
X1962533Y537098D01*
X1962616Y537390D01*
X1962908Y537598D01*
X1963199Y537681D01*
X1963574D01*
G01X1963199D02*
X1962949Y537806D01*
X1962741Y538015D01*
X1962658Y538265D01*
X1962741Y538515D01*
X1962949Y538723D01*
X1963324Y538848D01*
X1963699Y538806D01*
X1964074Y538640D01*
G01X1961308Y536848D02*
X1961058Y536556D01*
X1960724Y536390D01*
X1960349Y536348D01*
X1960016Y536390D01*
X1959683Y536598D01*
X1959474Y536848D01*
X1959433Y537098D01*
X1959516Y537390D01*
X1959808Y537598D01*
X1960099Y537681D01*
X1960474D01*
G01X1960099D02*
X1959849Y537806D01*
X1959641Y538015D01*
X1959558Y538265D01*
X1959641Y538515D01*
X1959849Y538723D01*
X1960224Y538848D01*
X1960599Y538806D01*
X1960974Y538640D01*
G01X1974600Y584633D02*
X1972808D01*
X1972433Y584800D01*
X1972183Y585133D01*
X1972100Y585550D01*
X1972183Y585967D01*
X1972433Y586300D01*
X1972808Y586467D01*
X1974600D01*
G01X1973142Y587858D02*
X1973433Y588150D01*
X1973600Y588400D01*
X1973683Y588733D01*
X1973600Y589025D01*
X1973433Y589233D01*
X1973183Y589400D01*
X1972892Y589442D01*
X1972642Y589400D01*
X1972392Y589233D01*
X1972183Y588983D01*
X1972100Y588692D01*
X1972183Y588358D01*
X1972433Y588067D01*
X1972808Y587900D01*
X1973225Y587858D01*
X1973767Y587942D01*
X1974058Y588067D01*
X1974350Y588275D01*
X1974558Y588567D01*
X1974600Y588858D01*
X1974517Y589150D01*
X1974308Y589358D01*
G01X1974600Y590500D02*
X1972100Y591083D01*
X1974600Y591750D01*
X1972100Y592417D01*
X1974600Y593000D01*
G01X1973142Y594058D02*
X1973433Y594350D01*
X1973600Y594600D01*
X1973683Y594933D01*
X1973600Y595225D01*
X1973433Y595433D01*
X1973183Y595600D01*
X1972892Y595642D01*
X1972642Y595600D01*
X1972392Y595433D01*
X1972183Y595183D01*
X1972100Y594892D01*
X1972183Y594558D01*
X1972433Y594267D01*
X1972808Y594100D01*
X1973225Y594058D01*
X1973767Y594142D01*
X1974058Y594267D01*
X1974350Y594475D01*
X1974558Y594767D01*
X1974600Y595058D01*
X1974517Y595350D01*
X1974308Y595558D01*
G01X1970300Y606167D02*
X1972800D01*
Y607208D01*
X1972675Y607542D01*
X1972508Y607750D01*
X1972175Y607833D01*
X1971842Y607750D01*
X1971633Y607500D01*
X1971508Y607208D01*
Y606167D01*
G01Y607208D02*
X1970300Y607833D01*
G01X1971342Y609308D02*
X1971633Y609600D01*
X1971800Y609850D01*
X1971883Y610183D01*
X1971800Y610475D01*
X1971633Y610683D01*
X1971383Y610850D01*
X1971092Y610892D01*
X1970842Y610850D01*
X1970592Y610683D01*
X1970383Y610433D01*
X1970300Y610142D01*
X1970383Y609808D01*
X1970633Y609517D01*
X1971008Y609350D01*
X1971425Y609308D01*
X1971967Y609392D01*
X1972258Y609517D01*
X1972550Y609725D01*
X1972758Y610017D01*
X1972800Y610308D01*
X1972717Y610600D01*
X1972508Y610808D01*
G01X1972800Y611950D02*
X1970300Y612533D01*
X1972800Y613200D01*
X1970300Y613867D01*
X1972800Y614450D01*
G01X1970800Y615383D02*
X1970508Y615633D01*
X1970342Y615967D01*
X1970300Y616342D01*
X1970342Y616675D01*
X1970550Y617008D01*
X1970800Y617217D01*
X1971050Y617258D01*
X1971342Y617175D01*
X1971550Y616883D01*
X1971633Y616592D01*
Y616217D01*
G01Y616592D02*
X1971758Y616842D01*
X1971967Y617050D01*
X1972217Y617133D01*
X1972467Y617050D01*
X1972675Y616842D01*
X1972800Y616467D01*
X1972758Y616092D01*
X1972592Y615717D01*
G01X1970300Y619317D02*
X1970842Y619400D01*
X1971300Y619525D01*
X1971717Y619692D01*
X1972175Y619900D01*
X1972800Y620233D01*
Y618567D01*
G01X1966800Y605867D02*
X1969300D01*
Y606908D01*
X1969175Y607242D01*
X1969008Y607450D01*
X1968675Y607533D01*
X1968342Y607450D01*
X1968133Y607200D01*
X1968008Y606908D01*
Y605867D01*
G01Y606908D02*
X1966800Y607533D01*
G01X1967842Y609008D02*
X1968133Y609300D01*
X1968300Y609550D01*
X1968383Y609883D01*
X1968300Y610175D01*
X1968133Y610383D01*
X1967883Y610550D01*
X1967592Y610592D01*
X1967342Y610550D01*
X1967092Y610383D01*
X1966883Y610133D01*
X1966800Y609842D01*
X1966883Y609508D01*
X1967133Y609217D01*
X1967508Y609050D01*
X1967925Y609008D01*
X1968467Y609092D01*
X1968758Y609217D01*
X1969050Y609425D01*
X1969258Y609717D01*
X1969300Y610008D01*
X1969217Y610300D01*
X1969008Y610508D01*
G01X1969300Y611650D02*
X1966800Y612233D01*
X1969300Y612900D01*
X1966800Y613567D01*
X1969300Y614150D01*
G01X1967300Y615083D02*
X1967008Y615333D01*
X1966842Y615667D01*
X1966800Y616042D01*
X1966842Y616375D01*
X1967050Y616708D01*
X1967300Y616917D01*
X1967550Y616958D01*
X1967842Y616875D01*
X1968050Y616583D01*
X1968133Y616292D01*
Y615917D01*
G01Y616292D02*
X1968258Y616542D01*
X1968467Y616750D01*
X1968717Y616833D01*
X1968967Y616750D01*
X1969175Y616542D01*
X1969300Y616167D01*
X1969258Y615792D01*
X1969092Y615417D01*
G01X1967842Y618308D02*
X1968133Y618600D01*
X1968300Y618850D01*
X1968383Y619183D01*
X1968300Y619475D01*
X1968133Y619683D01*
X1967883Y619850D01*
X1967592Y619892D01*
X1967342Y619850D01*
X1967092Y619683D01*
X1966883Y619433D01*
X1966800Y619142D01*
X1966883Y618808D01*
X1967133Y618517D01*
X1967508Y618350D01*
X1967925Y618308D01*
X1968467Y618392D01*
X1968758Y618517D01*
X1969050Y618725D01*
X1969258Y619017D01*
X1969300Y619308D01*
X1969217Y619600D01*
X1969008Y619808D01*
G54D18*
G01X1649000Y91500D02*
Y93500D01*
G01Y86500D02*
Y88500D01*
G01X1621500Y89800D02*
Y91800D01*
G01X1627049Y157438D02*
Y155438D01*
G01X1628618Y125218D02*
X1630618D01*
G01X1617849Y101538D02*
X1615849D01*
G01X1649000Y96500D02*
Y98500D01*
G01X1683000Y166650D02*
Y164650D01*
G01X1770903Y115412D02*
X1774903D01*
G01X1782903Y71879D02*
Y67879D01*
G01X1836450Y100250D02*
Y96250D01*
M02*
